# Lightning_PEB_SI constraints.xls — Net Rule by Layer (si-constraints)
| Project Name: 15105-1 |  |  |  |  |  |  |  |  |  |  |  |  |  |  |  |  |  |
| Project Path: C:\Users\<user>\Desktop\OCP\PEB\15105-1_20161102-1057.db |  |  |  |  |  |  |  |  |  |  |  |  |  |  |  |  |  |
| Net Name | Group Name | Type | Layer | T_W(X) | P-P | P-V | P-T | V-V | V-T | T_T(Y) | P-F | V-F | T-F | F-F | T_T(Z) | Ohm | Ref Layer |
| ADC_12V | ADC | BUS | 1 | 4.75 | 5 | 10 | 5 | 14 | 6 | 9.5 | 12 | 12 | 12 | 12 |  | 50 Ohms | TOP=L2:L3=L2/L4:L6=L5/L7:BOTTOM=L7 |
| ADC_12V | ADC | BUS | 2 | 5 | 5 | 10 | 5 | 14 | 6 | 10 | 12 | 12 | 12 | 12 |  | 50 Ohms | TOP=L2:L3=L2/L4:L6=L5/L7:BOTTOM=L7 |
| ADC_12V | ADC | BUS | 3 | 5 | 5 | 10 | 5 | 14 | 6 | 10 | 12 | 12 | 12 | 12 |  | 50 Ohms | TOP=L2:L3=L2/L4:L6=L5/L7:BOTTOM=L7 |
| ADC_12V | ADC | BUS | 4 | 5 | 5 | 10 | 5 | 14 | 6 | 10 | 12 | 12 | 12 | 12 |  | 50 Ohms | TOP=L2:L3=L2/L4:L6=L5/L7:BOTTOM=L7 |
| ADC_12V | ADC | BUS | 5 | 5 | 5 | 10 | 5 | 14 | 6 | 10 | 12 | 12 | 12 | 12 |  | 50 Ohms | TOP=L2:L3=L2/L4:L6=L5/L7:BOTTOM=L7 |
| ADC_12V | ADC | BUS | 6 | 5 | 5 | 10 | 5 | 14 | 6 | 10 | 12 | 12 | 12 | 12 |  | 50 Ohms | TOP=L2:L3=L2/L4:L6=L5/L7:BOTTOM=L7 |
| ADC_12V | ADC | BUS | 7 | 5 | 5 | 10 | 5 | 14 | 6 | 10 | 12 | 12 | 12 | 12 |  | 50 Ohms | TOP=L2:L3=L2/L4:L6=L5/L7:BOTTOM=L7 |
| ADC_12V | ADC | BUS | 8 | 4.75 | 5 | 10 | 5 | 14 | 6 | 9.5 | 12 | 12 | 12 | 12 |  | 50 Ohms | TOP=L2:L3=L2/L4:L6=L5/L7:BOTTOM=L7 |
| ADC_P0V9 | ADC | BUS | 1 | 4.75 | 5 | 10 | 5 | 14 | 6 | 9.5 | 12 | 12 | 12 | 12 |  | 50 Ohms | TOP=L2:L3=L2/L4:L6=L5/L7:BOTTOM=L7 |
| ADC_P0V9 | ADC | BUS | 2 | 5 | 5 | 10 | 5 | 14 | 6 | 10 | 12 | 12 | 12 | 12 |  | 50 Ohms | TOP=L2:L3=L2/L4:L6=L5/L7:BOTTOM=L7 |
| ADC_P0V9 | ADC | BUS | 3 | 5 | 5 | 10 | 5 | 14 | 6 | 10 | 12 | 12 | 12 | 12 |  | 50 Ohms | TOP=L2:L3=L2/L4:L6=L5/L7:BOTTOM=L7 |
| ADC_P0V9 | ADC | BUS | 4 | 5 | 5 | 10 | 5 | 14 | 6 | 10 | 12 | 12 | 12 | 12 |  | 50 Ohms | TOP=L2:L3=L2/L4:L6=L5/L7:BOTTOM=L7 |
| ADC_P0V9 | ADC | BUS | 5 | 5 | 5 | 10 | 5 | 14 | 6 | 10 | 12 | 12 | 12 | 12 |  | 50 Ohms | TOP=L2:L3=L2/L4:L6=L5/L7:BOTTOM=L7 |
| ADC_P0V9 | ADC | BUS | 6 | 5 | 5 | 10 | 5 | 14 | 6 | 10 | 12 | 12 | 12 | 12 |  | 50 Ohms | TOP=L2:L3=L2/L4:L6=L5/L7:BOTTOM=L7 |
| ADC_P0V9 | ADC | BUS | 7 | 5 | 5 | 10 | 5 | 14 | 6 | 10 | 12 | 12 | 12 | 12 |  | 50 Ohms | TOP=L2:L3=L2/L4:L6=L5/L7:BOTTOM=L7 |
| ADC_P0V9 | ADC | BUS | 8 | 4.75 | 5 | 10 | 5 | 14 | 6 | 9.5 | 12 | 12 | 12 | 12 |  | 50 Ohms | TOP=L2:L3=L2/L4:L6=L5/L7:BOTTOM=L7 |
| ADC_P0V9_E | ADC | BUS | 1 | 4.75 | 5 | 10 | 5 | 14 | 6 | 9.5 | 12 | 12 | 12 | 12 |  | 50 Ohms | TOP=L2:L3=L2/L4:L6=L5/L7:BOTTOM=L7 |
| ADC_P0V9_E | ADC | BUS | 2 | 5 | 5 | 10 | 5 | 14 | 6 | 10 | 12 | 12 | 12 | 12 |  | 50 Ohms | TOP=L2:L3=L2/L4:L6=L5/L7:BOTTOM=L7 |
| ADC_P0V9_E | ADC | BUS | 3 | 5 | 5 | 10 | 5 | 14 | 6 | 10 | 12 | 12 | 12 | 12 |  | 50 Ohms | TOP=L2:L3=L2/L4:L6=L5/L7:BOTTOM=L7 |
| ADC_P0V9_E | ADC | BUS | 4 | 5 | 5 | 10 | 5 | 14 | 6 | 10 | 12 | 12 | 12 | 12 |  | 50 Ohms | TOP=L2:L3=L2/L4:L6=L5/L7:BOTTOM=L7 |
| ADC_P0V9_E | ADC | BUS | 5 | 5 | 5 | 10 | 5 | 14 | 6 | 10 | 12 | 12 | 12 | 12 |  | 50 Ohms | TOP=L2:L3=L2/L4:L6=L5/L7:BOTTOM=L7 |
| ADC_P0V9_E | ADC | BUS | 6 | 5 | 5 | 10 | 5 | 14 | 6 | 10 | 12 | 12 | 12 | 12 |  | 50 Ohms | TOP=L2:L3=L2/L4:L6=L5/L7:BOTTOM=L7 |
| ADC_P0V9_E | ADC | BUS | 7 | 5 | 5 | 10 | 5 | 14 | 6 | 10 | 12 | 12 | 12 | 12 |  | 50 Ohms | TOP=L2:L3=L2/L4:L6=L5/L7:BOTTOM=L7 |
| ADC_P0V9_E | ADC | BUS | 8 | 4.75 | 5 | 10 | 5 | 14 | 6 | 9.5 | 12 | 12 | 12 | 12 |  | 50 Ohms | TOP=L2:L3=L2/L4:L6=L5/L7:BOTTOM=L7 |
| ADC_P0V9_E_BMC | ADC | BUS | 1 | 4.75 | 5 | 10 | 5 | 14 | 6 | 9.5 | 12 | 12 | 12 | 12 |  | 50 Ohms | TOP=L2:L3=L2/L4:L6=L5/L7:BOTTOM=L7 |
| ADC_P0V9_E_BMC | ADC | BUS | 2 | 5 | 5 | 10 | 5 | 14 | 6 | 10 | 12 | 12 | 12 | 12 |  | 50 Ohms | TOP=L2:L3=L2/L4:L6=L5/L7:BOTTOM=L7 |
| ADC_P0V9_E_BMC | ADC | BUS | 3 | 5 | 5 | 10 | 5 | 14 | 6 | 10 | 12 | 12 | 12 | 12 |  | 50 Ohms | TOP=L2:L3=L2/L4:L6=L5/L7:BOTTOM=L7 |
| ADC_P0V9_E_BMC | ADC | BUS | 4 | 5 | 5 | 10 | 5 | 14 | 6 | 10 | 12 | 12 | 12 | 12 |  | 50 Ohms | TOP=L2:L3=L2/L4:L6=L5/L7:BOTTOM=L7 |
| ADC_P0V9_E_BMC | ADC | BUS | 5 | 5 | 5 | 10 | 5 | 14 | 6 | 10 | 12 | 12 | 12 | 12 |  | 50 Ohms | TOP=L2:L3=L2/L4:L6=L5/L7:BOTTOM=L7 |
| ADC_P0V9_E_BMC | ADC | BUS | 6 | 5 | 5 | 10 | 5 | 14 | 6 | 10 | 12 | 12 | 12 | 12 |  | 50 Ohms | TOP=L2:L3=L2/L4:L6=L5/L7:BOTTOM=L7 |
| ADC_P0V9_E_BMC | ADC | BUS | 7 | 5 | 5 | 10 | 5 | 14 | 6 | 10 | 12 | 12 | 12 | 12 |  | 50 Ohms | TOP=L2:L3=L2/L4:L6=L5/L7:BOTTOM=L7 |
| ADC_P0V9_E_BMC | ADC | BUS | 8 | 4.75 | 5 | 10 | 5 | 14 | 6 | 9.5 | 12 | 12 | 12 | 12 |  | 50 Ohms | TOP=L2:L3=L2/L4:L6=L5/L7:BOTTOM=L7 |
| ADC_P1V26 | ADC | BUS | 1 | 4.75 | 5 | 10 | 5 | 14 | 6 | 9.5 | 12 | 12 | 12 | 12 |  | 50 Ohms | TOP=L2:L3=L2/L4:L6=L5/L7:BOTTOM=L7 |
| ADC_P1V26 | ADC | BUS | 2 | 5 | 5 | 10 | 5 | 14 | 6 | 10 | 12 | 12 | 12 | 12 |  | 50 Ohms | TOP=L2:L3=L2/L4:L6=L5/L7:BOTTOM=L7 |
| ADC_P1V26 | ADC | BUS | 3 | 5 | 5 | 10 | 5 | 14 | 6 | 10 | 12 | 12 | 12 | 12 |  | 50 Ohms | TOP=L2:L3=L2/L4:L6=L5/L7:BOTTOM=L7 |
| ADC_P1V26 | ADC | BUS | 4 | 5 | 5 | 10 | 5 | 14 | 6 | 10 | 12 | 12 | 12 | 12 |  | 50 Ohms | TOP=L2:L3=L2/L4:L6=L5/L7:BOTTOM=L7 |
| ADC_P1V26 | ADC | BUS | 5 | 5 | 5 | 10 | 5 | 14 | 6 | 10 | 12 | 12 | 12 | 12 |  | 50 Ohms | TOP=L2:L3=L2/L4:L6=L5/L7:BOTTOM=L7 |
| ADC_P1V26 | ADC | BUS | 6 | 5 | 5 | 10 | 5 | 14 | 6 | 10 | 12 | 12 | 12 | 12 |  | 50 Ohms | TOP=L2:L3=L2/L4:L6=L5/L7:BOTTOM=L7 |
| ADC_P1V26 | ADC | BUS | 7 | 5 | 5 | 10 | 5 | 14 | 6 | 10 | 12 | 12 | 12 | 12 |  | 50 Ohms | TOP=L2:L3=L2/L4:L6=L5/L7:BOTTOM=L7 |
| ADC_P1V26 | ADC | BUS | 8 | 4.75 | 5 | 10 | 5 | 14 | 6 | 9.5 | 12 | 12 | 12 | 12 |  | 50 Ohms | TOP=L2:L3=L2/L4:L6=L5/L7:BOTTOM=L7 |
| ADC_P1V53V | ADC | BUS | 1 | 4.75 | 5 | 10 | 5 | 14 | 6 | 9.5 | 12 | 12 | 12 | 12 |  | 50 Ohms | TOP=L2:L3=L2/L4:L6=L5/L7:BOTTOM=L7 |
| ADC_P1V53V | ADC | BUS | 2 | 5 | 5 | 10 | 5 | 14 | 6 | 10 | 12 | 12 | 12 | 12 |  | 50 Ohms | TOP=L2:L3=L2/L4:L6=L5/L7:BOTTOM=L7 |
| ADC_P1V53V | ADC | BUS | 3 | 5 | 5 | 10 | 5 | 14 | 6 | 10 | 12 | 12 | 12 | 12 |  | 50 Ohms | TOP=L2:L3=L2/L4:L6=L5/L7:BOTTOM=L7 |
| ADC_P1V53V | ADC | BUS | 4 | 5 | 5 | 10 | 5 | 14 | 6 | 10 | 12 | 12 | 12 | 12 |  | 50 Ohms | TOP=L2:L3=L2/L4:L6=L5/L7:BOTTOM=L7 |
| ADC_P1V53V | ADC | BUS | 5 | 5 | 5 | 10 | 5 | 14 | 6 | 10 | 12 | 12 | 12 | 12 |  | 50 Ohms | TOP=L2:L3=L2/L4:L6=L5/L7:BOTTOM=L7 |
| ADC_P1V53V | ADC | BUS | 6 | 5 | 5 | 10 | 5 | 14 | 6 | 10 | 12 | 12 | 12 | 12 |  | 50 Ohms | TOP=L2:L3=L2/L4:L6=L5/L7:BOTTOM=L7 |
| ADC_P1V53V | ADC | BUS | 7 | 5 | 5 | 10 | 5 | 14 | 6 | 10 | 12 | 12 | 12 | 12 |  | 50 Ohms | TOP=L2:L3=L2/L4:L6=L5/L7:BOTTOM=L7 |
| ADC_P1V53V | ADC | BUS | 8 | 4.75 | 5 | 10 | 5 | 14 | 6 | 9.5 | 12 | 12 | 12 | 12 |  | 50 Ohms | TOP=L2:L3=L2/L4:L6=L5/L7:BOTTOM=L7 |
| ADC_P1V8_STBY | ADC | BUS | 1 | 4.75 | 5 | 10 | 5 | 14 | 6 | 9.5 | 12 | 12 | 12 | 12 |  | 50 Ohms | TOP=L2:L3=L2/L4:L6=L5/L7:BOTTOM=L7 |
| ADC_P1V8_STBY | ADC | BUS | 2 | 5 | 5 | 10 | 5 | 14 | 6 | 10 | 12 | 12 | 12 | 12 |  | 50 Ohms | TOP=L2:L3=L2/L4:L6=L5/L7:BOTTOM=L7 |
| ADC_P1V8_STBY | ADC | BUS | 3 | 5 | 5 | 10 | 5 | 14 | 6 | 10 | 12 | 12 | 12 | 12 |  | 50 Ohms | TOP=L2:L3=L2/L4:L6=L5/L7:BOTTOM=L7 |
| ADC_P1V8_STBY | ADC | BUS | 4 | 5 | 5 | 10 | 5 | 14 | 6 | 10 | 12 | 12 | 12 | 12 |  | 50 Ohms | TOP=L2:L3=L2/L4:L6=L5/L7:BOTTOM=L7 |
| ADC_P1V8_STBY | ADC | BUS | 5 | 5 | 5 | 10 | 5 | 14 | 6 | 10 | 12 | 12 | 12 | 12 |  | 50 Ohms | TOP=L2:L3=L2/L4:L6=L5/L7:BOTTOM=L7 |
| ADC_P1V8_STBY | ADC | BUS | 6 | 5 | 5 | 10 | 5 | 14 | 6 | 10 | 12 | 12 | 12 | 12 |  | 50 Ohms | TOP=L2:L3=L2/L4:L6=L5/L7:BOTTOM=L7 |
| ADC_P1V8_STBY | ADC | BUS | 7 | 5 | 5 | 10 | 5 | 14 | 6 | 10 | 12 | 12 | 12 | 12 |  | 50 Ohms | TOP=L2:L3=L2/L4:L6=L5/L7:BOTTOM=L7 |
| ADC_P1V8_STBY | ADC | BUS | 8 | 4.75 | 5 | 10 | 5 | 14 | 6 | 9.5 | 12 | 12 | 12 | 12 |  | 50 Ohms | TOP=L2:L3=L2/L4:L6=L5/L7:BOTTOM=L7 |
| ADC_P1V8_STBY_BMC | ADC | BUS | 1 | 4.75 | 5 | 10 | 5 | 14 | 6 | 9.5 | 12 | 12 | 12 | 12 |  | 50 Ohms | TOP=L2:L3=L2/L4:L6=L5/L7:BOTTOM=L7 |
| ADC_P1V8_STBY_BMC | ADC | BUS | 2 | 5 | 5 | 10 | 5 | 14 | 6 | 10 | 12 | 12 | 12 | 12 |  | 50 Ohms | TOP=L2:L3=L2/L4:L6=L5/L7:BOTTOM=L7 |
| ADC_P1V8_STBY_BMC | ADC | BUS | 3 | 5 | 5 | 10 | 5 | 14 | 6 | 10 | 12 | 12 | 12 | 12 |  | 50 Ohms | TOP=L2:L3=L2/L4:L6=L5/L7:BOTTOM=L7 |
| ADC_P1V8_STBY_BMC | ADC | BUS | 4 | 5 | 5 | 10 | 5 | 14 | 6 | 10 | 12 | 12 | 12 | 12 |  | 50 Ohms | TOP=L2:L3=L2/L4:L6=L5/L7:BOTTOM=L7 |
| ADC_P1V8_STBY_BMC | ADC | BUS | 5 | 5 | 5 | 10 | 5 | 14 | 6 | 10 | 12 | 12 | 12 | 12 |  | 50 Ohms | TOP=L2:L3=L2/L4:L6=L5/L7:BOTTOM=L7 |
| ADC_P1V8_STBY_BMC | ADC | BUS | 6 | 5 | 5 | 10 | 5 | 14 | 6 | 10 | 12 | 12 | 12 | 12 |  | 50 Ohms | TOP=L2:L3=L2/L4:L6=L5/L7:BOTTOM=L7 |
| ADC_P1V8_STBY_BMC | ADC | BUS | 7 | 5 | 5 | 10 | 5 | 14 | 6 | 10 | 12 | 12 | 12 | 12 |  | 50 Ohms | TOP=L2:L3=L2/L4:L6=L5/L7:BOTTOM=L7 |
| ADC_P1V8_STBY_BMC | ADC | BUS | 8 | 4.75 | 5 | 10 | 5 | 14 | 6 | 9.5 | 12 | 12 | 12 | 12 |  | 50 Ohms | TOP=L2:L3=L2/L4:L6=L5/L7:BOTTOM=L7 |
| ADC_P3V3_STBY | ADC | BUS | 1 | 4.75 | 5 | 10 | 5 | 14 | 6 | 9.5 | 12 | 12 | 12 | 12 |  | 50 Ohms | TOP=L2:L3=L2/L4:L6=L5/L7:BOTTOM=L7 |
| ADC_P3V3_STBY | ADC | BUS | 2 | 5 | 5 | 10 | 5 | 14 | 6 | 10 | 12 | 12 | 12 | 12 |  | 50 Ohms | TOP=L2:L3=L2/L4:L6=L5/L7:BOTTOM=L7 |
| ADC_P3V3_STBY | ADC | BUS | 3 | 5 | 5 | 10 | 5 | 14 | 6 | 10 | 12 | 12 | 12 | 12 |  | 50 Ohms | TOP=L2:L3=L2/L4:L6=L5/L7:BOTTOM=L7 |
| ADC_P3V3_STBY | ADC | BUS | 4 | 5 | 5 | 10 | 5 | 14 | 6 | 10 | 12 | 12 | 12 | 12 |  | 50 Ohms | TOP=L2:L3=L2/L4:L6=L5/L7:BOTTOM=L7 |
| ADC_P3V3_STBY | ADC | BUS | 5 | 5 | 5 | 10 | 5 | 14 | 6 | 10 | 12 | 12 | 12 | 12 |  | 50 Ohms | TOP=L2:L3=L2/L4:L6=L5/L7:BOTTOM=L7 |
| ADC_P3V3_STBY | ADC | BUS | 6 | 5 | 5 | 10 | 5 | 14 | 6 | 10 | 12 | 12 | 12 | 12 |  | 50 Ohms | TOP=L2:L3=L2/L4:L6=L5/L7:BOTTOM=L7 |
| ADC_P3V3_STBY | ADC | BUS | 7 | 5 | 5 | 10 | 5 | 14 | 6 | 10 | 12 | 12 | 12 | 12 |  | 50 Ohms | TOP=L2:L3=L2/L4:L6=L5/L7:BOTTOM=L7 |
| ADC_P3V3_STBY | ADC | BUS | 8 | 4.75 | 5 | 10 | 5 | 14 | 6 | 9.5 | 12 | 12 | 12 | 12 |  | 50 Ohms | TOP=L2:L3=L2/L4:L6=L5/L7:BOTTOM=L7 |
| ADC_P3V3_STBY_BMC | ADC | BUS | 1 | 4.75 | 5 | 10 | 5 | 14 | 6 | 9.5 | 12 | 12 | 12 | 12 |  | 50 Ohms | TOP=L2:L3=L2/L4:L6=L5/L7:BOTTOM=L7 |
| ADC_P3V3_STBY_BMC | ADC | BUS | 2 | 5 | 5 | 10 | 5 | 14 | 6 | 10 | 12 | 12 | 12 | 12 |  | 50 Ohms | TOP=L2:L3=L2/L4:L6=L5/L7:BOTTOM=L7 |
| ADC_P3V3_STBY_BMC | ADC | BUS | 3 | 5 | 5 | 10 | 5 | 14 | 6 | 10 | 12 | 12 | 12 | 12 |  | 50 Ohms | TOP=L2:L3=L2/L4:L6=L5/L7:BOTTOM=L7 |
| ADC_P3V3_STBY_BMC | ADC | BUS | 4 | 5 | 5 | 10 | 5 | 14 | 6 | 10 | 12 | 12 | 12 | 12 |  | 50 Ohms | TOP=L2:L3=L2/L4:L6=L5/L7:BOTTOM=L7 |
| ADC_P3V3_STBY_BMC | ADC | BUS | 5 | 5 | 5 | 10 | 5 | 14 | 6 | 10 | 12 | 12 | 12 | 12 |  | 50 Ohms | TOP=L2:L3=L2/L4:L6=L5/L7:BOTTOM=L7 |
| ADC_P3V3_STBY_BMC | ADC | BUS | 6 | 5 | 5 | 10 | 5 | 14 | 6 | 10 | 12 | 12 | 12 | 12 |  | 50 Ohms | TOP=L2:L3=L2/L4:L6=L5/L7:BOTTOM=L7 |
| ADC_P3V3_STBY_BMC | ADC | BUS | 7 | 5 | 5 | 10 | 5 | 14 | 6 | 10 | 12 | 12 | 12 | 12 |  | 50 Ohms | TOP=L2:L3=L2/L4:L6=L5/L7:BOTTOM=L7 |
| ADC_P3V3_STBY_BMC | ADC | BUS | 8 | 4.75 | 5 | 10 | 5 | 14 | 6 | 9.5 | 12 | 12 | 12 | 12 |  | 50 Ohms | TOP=L2:L3=L2/L4:L6=L5/L7:BOTTOM=L7 |
| ADC_P5V_STBY | ADC | BUS | 1 | 4.75 | 5 | 10 | 5 | 14 | 6 | 9.5 | 12 | 12 | 12 | 12 |  | 50 Ohms | TOP=L2:L3=L2/L4:L6=L5/L7:BOTTOM=L7 |
| ADC_P5V_STBY | ADC | BUS | 2 | 5 | 5 | 10 | 5 | 14 | 6 | 10 | 12 | 12 | 12 | 12 |  | 50 Ohms | TOP=L2:L3=L2/L4:L6=L5/L7:BOTTOM=L7 |
| ADC_P5V_STBY | ADC | BUS | 3 | 5 | 5 | 10 | 5 | 14 | 6 | 10 | 12 | 12 | 12 | 12 |  | 50 Ohms | TOP=L2:L3=L2/L4:L6=L5/L7:BOTTOM=L7 |
| ADC_P5V_STBY | ADC | BUS | 4 | 5 | 5 | 10 | 5 | 14 | 6 | 10 | 12 | 12 | 12 | 12 |  | 50 Ohms | TOP=L2:L3=L2/L4:L6=L5/L7:BOTTOM=L7 |
| ADC_P5V_STBY | ADC | BUS | 5 | 5 | 5 | 10 | 5 | 14 | 6 | 10 | 12 | 12 | 12 | 12 |  | 50 Ohms | TOP=L2:L3=L2/L4:L6=L5/L7:BOTTOM=L7 |
| ADC_P5V_STBY | ADC | BUS | 6 | 5 | 5 | 10 | 5 | 14 | 6 | 10 | 12 | 12 | 12 | 12 |  | 50 Ohms | TOP=L2:L3=L2/L4:L6=L5/L7:BOTTOM=L7 |
| ADC_P5V_STBY | ADC | BUS | 7 | 5 | 5 | 10 | 5 | 14 | 6 | 10 | 12 | 12 | 12 | 12 |  | 50 Ohms | TOP=L2:L3=L2/L4:L6=L5/L7:BOTTOM=L7 |
| ADC_P5V_STBY | ADC | BUS | 8 | 4.75 | 5 | 10 | 5 | 14 | 6 | 9.5 | 12 | 12 | 12 | 12 |  | 50 Ohms | TOP=L2:L3=L2/L4:L6=L5/L7:BOTTOM=L7 |
| ADC_P5V_STBY_BMC | ADC | BUS | 1 | 4.75 | 5 | 10 | 5 | 14 | 6 | 9.5 | 12 | 12 | 12 | 12 |  | 50 Ohms | TOP=L2:L3=L2/L4:L6=L5/L7:BOTTOM=L7 |
| ADC_P5V_STBY_BMC | ADC | BUS | 2 | 5 | 5 | 10 | 5 | 14 | 6 | 10 | 12 | 12 | 12 | 12 |  | 50 Ohms | TOP=L2:L3=L2/L4:L6=L5/L7:BOTTOM=L7 |
| ADC_P5V_STBY_BMC | ADC | BUS | 3 | 5 | 5 | 10 | 5 | 14 | 6 | 10 | 12 | 12 | 12 | 12 |  | 50 Ohms | TOP=L2:L3=L2/L4:L6=L5/L7:BOTTOM=L7 |
| ADC_P5V_STBY_BMC | ADC | BUS | 4 | 5 | 5 | 10 | 5 | 14 | 6 | 10 | 12 | 12 | 12 | 12 |  | 50 Ohms | TOP=L2:L3=L2/L4:L6=L5/L7:BOTTOM=L7 |
| ADC_P5V_STBY_BMC | ADC | BUS | 5 | 5 | 5 | 10 | 5 | 14 | 6 | 10 | 12 | 12 | 12 | 12 |  | 50 Ohms | TOP=L2:L3=L2/L4:L6=L5/L7:BOTTOM=L7 |
| ADC_P5V_STBY_BMC | ADC | BUS | 6 | 5 | 5 | 10 | 5 | 14 | 6 | 10 | 12 | 12 | 12 | 12 |  | 50 Ohms | TOP=L2:L3=L2/L4:L6=L5/L7:BOTTOM=L7 |
| ADC_P5V_STBY_BMC | ADC | BUS | 7 | 5 | 5 | 10 | 5 | 14 | 6 | 10 | 12 | 12 | 12 | 12 |  | 50 Ohms | TOP=L2:L3=L2/L4:L6=L5/L7:BOTTOM=L7 |
| ADC_P5V_STBY_BMC | ADC | BUS | 8 | 4.75 | 5 | 10 | 5 | 14 | 6 | 9.5 | 12 | 12 | 12 | 12 |  | 50 Ohms | TOP=L2:L3=L2/L4:L6=L5/L7:BOTTOM=L7 |
| ADC0_12V_BMC | ADC | BUS | 1 | 4.75 | 5 | 10 | 5 | 14 | 6 | 9.5 | 12 | 12 | 12 | 12 |  | 50 Ohms | TOP=L2:L3=L2/L4:L6=L5/L7:BOTTOM=L7 |
| ADC0_12V_BMC | ADC | BUS | 2 | 5 | 5 | 10 | 5 | 14 | 6 | 10 | 12 | 12 | 12 | 12 |  | 50 Ohms | TOP=L2:L3=L2/L4:L6=L5/L7:BOTTOM=L7 |
| ADC0_12V_BMC | ADC | BUS | 3 | 5 | 5 | 10 | 5 | 14 | 6 | 10 | 12 | 12 | 12 | 12 |  | 50 Ohms | TOP=L2:L3=L2/L4:L6=L5/L7:BOTTOM=L7 |
| ADC0_12V_BMC | ADC | BUS | 4 | 5 | 5 | 10 | 5 | 14 | 6 | 10 | 12 | 12 | 12 | 12 |  | 50 Ohms | TOP=L2:L3=L2/L4:L6=L5/L7:BOTTOM=L7 |
| ADC0_12V_BMC | ADC | BUS | 5 | 5 | 5 | 10 | 5 | 14 | 6 | 10 | 12 | 12 | 12 | 12 |  | 50 Ohms | TOP=L2:L3=L2/L4:L6=L5/L7:BOTTOM=L7 |
| ADC0_12V_BMC | ADC | BUS | 6 | 5 | 5 | 10 | 5 | 14 | 6 | 10 | 12 | 12 | 12 | 12 |  | 50 Ohms | TOP=L2:L3=L2/L4:L6=L5/L7:BOTTOM=L7 |
| ADC0_12V_BMC | ADC | BUS | 7 | 5 | 5 | 10 | 5 | 14 | 6 | 10 | 12 | 12 | 12 | 12 |  | 50 Ohms | TOP=L2:L3=L2/L4:L6=L5/L7:BOTTOM=L7 |
| ADC0_12V_BMC | ADC | BUS | 8 | 4.75 | 5 | 10 | 5 | 14 | 6 | 9.5 | 12 | 12 | 12 | 12 |  | 50 Ohms | TOP=L2:L3=L2/L4:L6=L5/L7:BOTTOM=L7 |
| 8644_CBL_PRSNT_R_1 | OTHERS | BUS | 1 | 4.75 | 5 | 10 | 5 | 14 | 6 | 9.5 | 12 | 12 | 12 | 12 |  | 50 Ohms | TOP=L2:L3=L2/L4:L6=L5/L7:BOTTOM=L7 |
| 8644_CBL_PRSNT_R_1 | OTHERS | BUS | 2 | 5 | 5 | 10 | 5 | 14 | 6 | 10 | 12 | 12 | 12 | 12 |  | 50 Ohms | TOP=L2:L3=L2/L4:L6=L5/L7:BOTTOM=L7 |
| 8644_CBL_PRSNT_R_1 | OTHERS | BUS | 3 | 5 | 5 | 10 | 5 | 14 | 6 | 10 | 12 | 12 | 12 | 12 |  | 50 Ohms | TOP=L2:L3=L2/L4:L6=L5/L7:BOTTOM=L7 |
| 8644_CBL_PRSNT_R_1 | OTHERS | BUS | 4 | 5 | 5 | 10 | 5 | 14 | 6 | 10 | 12 | 12 | 12 | 12 |  | 50 Ohms | TOP=L2:L3=L2/L4:L6=L5/L7:BOTTOM=L7 |
| 8644_CBL_PRSNT_R_1 | OTHERS | BUS | 5 | 5 | 5 | 10 | 5 | 14 | 6 | 10 | 12 | 12 | 12 | 12 |  | 50 Ohms | TOP=L2:L3=L2/L4:L6=L5/L7:BOTTOM=L7 |
| 8644_CBL_PRSNT_R_1 | OTHERS | BUS | 6 | 5 | 5 | 10 | 5 | 14 | 6 | 10 | 12 | 12 | 12 | 12 |  | 50 Ohms | TOP=L2:L3=L2/L4:L6=L5/L7:BOTTOM=L7 |
| 8644_CBL_PRSNT_R_1 | OTHERS | BUS | 7 | 5 | 5 | 10 | 5 | 14 | 6 | 10 | 12 | 12 | 12 | 12 |  | 50 Ohms | TOP=L2:L3=L2/L4:L6=L5/L7:BOTTOM=L7 |
| 8644_CBL_PRSNT_R_1 | OTHERS | BUS | 8 | 4.75 | 5 | 10 | 5 | 14 | 6 | 9.5 | 12 | 12 | 12 | 12 |  | 50 Ohms | TOP=L2:L3=L2/L4:L6=L5/L7:BOTTOM=L7 |
| 8644_CBL_PRSNT_R_2 | OTHERS | BUS | 1 | 4.75 | 5 | 10 | 5 | 14 | 6 | 9.5 | 12 | 12 | 12 | 12 |  | 50 Ohms | TOP=L2:L3=L2/L4:L6=L5/L7:BOTTOM=L7 |
| 8644_CBL_PRSNT_R_2 | OTHERS | BUS | 2 | 5 | 5 | 10 | 5 | 14 | 6 | 10 | 12 | 12 | 12 | 12 |  | 50 Ohms | TOP=L2:L3=L2/L4:L6=L5/L7:BOTTOM=L7 |
| 8644_CBL_PRSNT_R_2 | OTHERS | BUS | 3 | 5 | 5 | 10 | 5 | 14 | 6 | 10 | 12 | 12 | 12 | 12 |  | 50 Ohms | TOP=L2:L3=L2/L4:L6=L5/L7:BOTTOM=L7 |
| 8644_CBL_PRSNT_R_2 | OTHERS | BUS | 4 | 5 | 5 | 10 | 5 | 14 | 6 | 10 | 12 | 12 | 12 | 12 |  | 50 Ohms | TOP=L2:L3=L2/L4:L6=L5/L7:BOTTOM=L7 |
| 8644_CBL_PRSNT_R_2 | OTHERS | BUS | 5 | 5 | 5 | 10 | 5 | 14 | 6 | 10 | 12 | 12 | 12 | 12 |  | 50 Ohms | TOP=L2:L3=L2/L4:L6=L5/L7:BOTTOM=L7 |
| 8644_CBL_PRSNT_R_2 | OTHERS | BUS | 6 | 5 | 5 | 10 | 5 | 14 | 6 | 10 | 12 | 12 | 12 | 12 |  | 50 Ohms | TOP=L2:L3=L2/L4:L6=L5/L7:BOTTOM=L7 |
| 8644_CBL_PRSNT_R_2 | OTHERS | BUS | 7 | 5 | 5 | 10 | 5 | 14 | 6 | 10 | 12 | 12 | 12 | 12 |  | 50 Ohms | TOP=L2:L3=L2/L4:L6=L5/L7:BOTTOM=L7 |
| 8644_CBL_PRSNT_R_2 | OTHERS | BUS | 8 | 4.75 | 5 | 10 | 5 | 14 | 6 | 9.5 | 12 | 12 | 12 | 12 |  | 50 Ohms | TOP=L2:L3=L2/L4:L6=L5/L7:BOTTOM=L7 |
| 8644_CBL_PRSNT_R_3 | OTHERS | BUS | 1 | 4.75 | 5 | 10 | 5 | 14 | 6 | 9.5 | 12 | 12 | 12 | 12 |  | 50 Ohms | TOP=L2:L3=L2/L4:L6=L5/L7:BOTTOM=L7 |
| 8644_CBL_PRSNT_R_3 | OTHERS | BUS | 2 | 5 | 5 | 10 | 5 | 14 | 6 | 10 | 12 | 12 | 12 | 12 |  | 50 Ohms | TOP=L2:L3=L2/L4:L6=L5/L7:BOTTOM=L7 |
| 8644_CBL_PRSNT_R_3 | OTHERS | BUS | 3 | 5 | 5 | 10 | 5 | 14 | 6 | 10 | 12 | 12 | 12 | 12 |  | 50 Ohms | TOP=L2:L3=L2/L4:L6=L5/L7:BOTTOM=L7 |
| 8644_CBL_PRSNT_R_3 | OTHERS | BUS | 4 | 5 | 5 | 10 | 5 | 14 | 6 | 10 | 12 | 12 | 12 | 12 |  | 50 Ohms | TOP=L2:L3=L2/L4:L6=L5/L7:BOTTOM=L7 |
| 8644_CBL_PRSNT_R_3 | OTHERS | BUS | 5 | 5 | 5 | 10 | 5 | 14 | 6 | 10 | 12 | 12 | 12 | 12 |  | 50 Ohms | TOP=L2:L3=L2/L4:L6=L5/L7:BOTTOM=L7 |
| 8644_CBL_PRSNT_R_3 | OTHERS | BUS | 6 | 5 | 5 | 10 | 5 | 14 | 6 | 10 | 12 | 12 | 12 | 12 |  | 50 Ohms | TOP=L2:L3=L2/L4:L6=L5/L7:BOTTOM=L7 |
| 8644_CBL_PRSNT_R_3 | OTHERS | BUS | 7 | 5 | 5 | 10 | 5 | 14 | 6 | 10 | 12 | 12 | 12 | 12 |  | 50 Ohms | TOP=L2:L3=L2/L4:L6=L5/L7:BOTTOM=L7 |
| 8644_CBL_PRSNT_R_3 | OTHERS | BUS | 8 | 4.75 | 5 | 10 | 5 | 14 | 6 | 9.5 | 12 | 12 | 12 | 12 |  | 50 Ohms | TOP=L2:L3=L2/L4:L6=L5/L7:BOTTOM=L7 |
| 8644_CBL_PRSNT_R_4 | OTHERS | BUS | 1 | 4.75 | 5 | 10 | 5 | 14 | 6 | 9.5 | 12 | 12 | 12 | 12 |  | 50 Ohms | TOP=L2:L3=L2/L4:L6=L5/L7:BOTTOM=L7 |
| 8644_CBL_PRSNT_R_4 | OTHERS | BUS | 2 | 5 | 5 | 10 | 5 | 14 | 6 | 10 | 12 | 12 | 12 | 12 |  | 50 Ohms | TOP=L2:L3=L2/L4:L6=L5/L7:BOTTOM=L7 |
| 8644_CBL_PRSNT_R_4 | OTHERS | BUS | 3 | 5 | 5 | 10 | 5 | 14 | 6 | 10 | 12 | 12 | 12 | 12 |  | 50 Ohms | TOP=L2:L3=L2/L4:L6=L5/L7:BOTTOM=L7 |
| 8644_CBL_PRSNT_R_4 | OTHERS | BUS | 4 | 5 | 5 | 10 | 5 | 14 | 6 | 10 | 12 | 12 | 12 | 12 |  | 50 Ohms | TOP=L2:L3=L2/L4:L6=L5/L7:BOTTOM=L7 |
| 8644_CBL_PRSNT_R_4 | OTHERS | BUS | 5 | 5 | 5 | 10 | 5 | 14 | 6 | 10 | 12 | 12 | 12 | 12 |  | 50 Ohms | TOP=L2:L3=L2/L4:L6=L5/L7:BOTTOM=L7 |
| 8644_CBL_PRSNT_R_4 | OTHERS | BUS | 6 | 5 | 5 | 10 | 5 | 14 | 6 | 10 | 12 | 12 | 12 | 12 |  | 50 Ohms | TOP=L2:L3=L2/L4:L6=L5/L7:BOTTOM=L7 |
| 8644_CBL_PRSNT_R_4 | OTHERS | BUS | 7 | 5 | 5 | 10 | 5 | 14 | 6 | 10 | 12 | 12 | 12 | 12 |  | 50 Ohms | TOP=L2:L3=L2/L4:L6=L5/L7:BOTTOM=L7 |
| 8644_CBL_PRSNT_R_4 | OTHERS | BUS | 8 | 4.75 | 5 | 10 | 5 | 14 | 6 | 9.5 | 12 | 12 | 12 | 12 |  | 50 Ohms | TOP=L2:L3=L2/L4:L6=L5/L7:BOTTOM=L7 |
| 8644_CBL_PRSNT_R_5 | OTHERS | BUS | 1 | 4.75 | 5 | 10 | 5 | 14 | 6 | 9.5 | 12 | 12 | 12 | 12 |  | 50 Ohms | TOP=L2:L3=L2/L4:L6=L5/L7:BOTTOM=L7 |
| 8644_CBL_PRSNT_R_5 | OTHERS | BUS | 2 | 5 | 5 | 10 | 5 | 14 | 6 | 10 | 12 | 12 | 12 | 12 |  | 50 Ohms | TOP=L2:L3=L2/L4:L6=L5/L7:BOTTOM=L7 |
| 8644_CBL_PRSNT_R_5 | OTHERS | BUS | 3 | 5 | 5 | 10 | 5 | 14 | 6 | 10 | 12 | 12 | 12 | 12 |  | 50 Ohms | TOP=L2:L3=L2/L4:L6=L5/L7:BOTTOM=L7 |
| 8644_CBL_PRSNT_R_5 | OTHERS | BUS | 4 | 5 | 5 | 10 | 5 | 14 | 6 | 10 | 12 | 12 | 12 | 12 |  | 50 Ohms | TOP=L2:L3=L2/L4:L6=L5/L7:BOTTOM=L7 |
| 8644_CBL_PRSNT_R_5 | OTHERS | BUS | 5 | 5 | 5 | 10 | 5 | 14 | 6 | 10 | 12 | 12 | 12 | 12 |  | 50 Ohms | TOP=L2:L3=L2/L4:L6=L5/L7:BOTTOM=L7 |
| 8644_CBL_PRSNT_R_5 | OTHERS | BUS | 6 | 5 | 5 | 10 | 5 | 14 | 6 | 10 | 12 | 12 | 12 | 12 |  | 50 Ohms | TOP=L2:L3=L2/L4:L6=L5/L7:BOTTOM=L7 |
| 8644_CBL_PRSNT_R_5 | OTHERS | BUS | 7 | 5 | 5 | 10 | 5 | 14 | 6 | 10 | 12 | 12 | 12 | 12 |  | 50 Ohms | TOP=L2:L3=L2/L4:L6=L5/L7:BOTTOM=L7 |
| 8644_CBL_PRSNT_R_5 | OTHERS | BUS | 8 | 4.75 | 5 | 10 | 5 | 14 | 6 | 9.5 | 12 | 12 | 12 | 12 |  | 50 Ohms | TOP=L2:L3=L2/L4:L6=L5/L7:BOTTOM=L7 |
| 8644_CBL_PRSNT_R_6 | OTHERS | BUS | 1 | 4.75 | 5 | 10 | 5 | 14 | 6 | 9.5 | 12 | 12 | 12 | 12 |  | 50 Ohms | TOP=L2:L3=L2/L4:L6=L5/L7:BOTTOM=L7 |
| 8644_CBL_PRSNT_R_6 | OTHERS | BUS | 2 | 5 | 5 | 10 | 5 | 14 | 6 | 10 | 12 | 12 | 12 | 12 |  | 50 Ohms | TOP=L2:L3=L2/L4:L6=L5/L7:BOTTOM=L7 |
| 8644_CBL_PRSNT_R_6 | OTHERS | BUS | 3 | 5 | 5 | 10 | 5 | 14 | 6 | 10 | 12 | 12 | 12 | 12 |  | 50 Ohms | TOP=L2:L3=L2/L4:L6=L5/L7:BOTTOM=L7 |
| 8644_CBL_PRSNT_R_6 | OTHERS | BUS | 4 | 5 | 5 | 10 | 5 | 14 | 6 | 10 | 12 | 12 | 12 | 12 |  | 50 Ohms | TOP=L2:L3=L2/L4:L6=L5/L7:BOTTOM=L7 |
| 8644_CBL_PRSNT_R_6 | OTHERS | BUS | 5 | 5 | 5 | 10 | 5 | 14 | 6 | 10 | 12 | 12 | 12 | 12 |  | 50 Ohms | TOP=L2:L3=L2/L4:L6=L5/L7:BOTTOM=L7 |
| 8644_CBL_PRSNT_R_6 | OTHERS | BUS | 6 | 5 | 5 | 10 | 5 | 14 | 6 | 10 | 12 | 12 | 12 | 12 |  | 50 Ohms | TOP=L2:L3=L2/L4:L6=L5/L7:BOTTOM=L7 |
| 8644_CBL_PRSNT_R_6 | OTHERS | BUS | 7 | 5 | 5 | 10 | 5 | 14 | 6 | 10 | 12 | 12 | 12 | 12 |  | 50 Ohms | TOP=L2:L3=L2/L4:L6=L5/L7:BOTTOM=L7 |
| 8644_CBL_PRSNT_R_6 | OTHERS | BUS | 8 | 4.75 | 5 | 10 | 5 | 14 | 6 | 9.5 | 12 | 12 | 12 | 12 |  | 50 Ohms | TOP=L2:L3=L2/L4:L6=L5/L7:BOTTOM=L7 |
| 8644_CBL_PRSNT_R_7 | OTHERS | BUS | 1 | 4.75 | 5 | 10 | 5 | 14 | 6 | 9.5 | 12 | 12 | 12 | 12 |  | 50 Ohms | TOP=L2:L3=L2/L4:L6=L5/L7:BOTTOM=L7 |
| 8644_CBL_PRSNT_R_7 | OTHERS | BUS | 2 | 5 | 5 | 10 | 5 | 14 | 6 | 10 | 12 | 12 | 12 | 12 |  | 50 Ohms | TOP=L2:L3=L2/L4:L6=L5/L7:BOTTOM=L7 |
| 8644_CBL_PRSNT_R_7 | OTHERS | BUS | 3 | 5 | 5 | 10 | 5 | 14 | 6 | 10 | 12 | 12 | 12 | 12 |  | 50 Ohms | TOP=L2:L3=L2/L4:L6=L5/L7:BOTTOM=L7 |
| 8644_CBL_PRSNT_R_7 | OTHERS | BUS | 4 | 5 | 5 | 10 | 5 | 14 | 6 | 10 | 12 | 12 | 12 | 12 |  | 50 Ohms | TOP=L2:L3=L2/L4:L6=L5/L7:BOTTOM=L7 |
| 8644_CBL_PRSNT_R_7 | OTHERS | BUS | 5 | 5 | 5 | 10 | 5 | 14 | 6 | 10 | 12 | 12 | 12 | 12 |  | 50 Ohms | TOP=L2:L3=L2/L4:L6=L5/L7:BOTTOM=L7 |
| 8644_CBL_PRSNT_R_7 | OTHERS | BUS | 6 | 5 | 5 | 10 | 5 | 14 | 6 | 10 | 12 | 12 | 12 | 12 |  | 50 Ohms | TOP=L2:L3=L2/L4:L6=L5/L7:BOTTOM=L7 |
| 8644_CBL_PRSNT_R_7 | OTHERS | BUS | 7 | 5 | 5 | 10 | 5 | 14 | 6 | 10 | 12 | 12 | 12 | 12 |  | 50 Ohms | TOP=L2:L3=L2/L4:L6=L5/L7:BOTTOM=L7 |
| 8644_CBL_PRSNT_R_7 | OTHERS | BUS | 8 | 4.75 | 5 | 10 | 5 | 14 | 6 | 9.5 | 12 | 12 | 12 | 12 |  | 50 Ohms | TOP=L2:L3=L2/L4:L6=L5/L7:BOTTOM=L7 |
| 8644_CBL_PRSNT_R_8 | OTHERS | BUS | 1 | 4.75 | 5 | 10 | 5 | 14 | 6 | 9.5 | 12 | 12 | 12 | 12 |  | 50 Ohms | TOP=L2:L3=L2/L4:L6=L5/L7:BOTTOM=L7 |
| 8644_CBL_PRSNT_R_8 | OTHERS | BUS | 2 | 5 | 5 | 10 | 5 | 14 | 6 | 10 | 12 | 12 | 12 | 12 |  | 50 Ohms | TOP=L2:L3=L2/L4:L6=L5/L7:BOTTOM=L7 |
| 8644_CBL_PRSNT_R_8 | OTHERS | BUS | 3 | 5 | 5 | 10 | 5 | 14 | 6 | 10 | 12 | 12 | 12 | 12 |  | 50 Ohms | TOP=L2:L3=L2/L4:L6=L5/L7:BOTTOM=L7 |
| 8644_CBL_PRSNT_R_8 | OTHERS | BUS | 4 | 5 | 5 | 10 | 5 | 14 | 6 | 10 | 12 | 12 | 12 | 12 |  | 50 Ohms | TOP=L2:L3=L2/L4:L6=L5/L7:BOTTOM=L7 |
| 8644_CBL_PRSNT_R_8 | OTHERS | BUS | 5 | 5 | 5 | 10 | 5 | 14 | 6 | 10 | 12 | 12 | 12 | 12 |  | 50 Ohms | TOP=L2:L3=L2/L4:L6=L5/L7:BOTTOM=L7 |
| 8644_CBL_PRSNT_R_8 | OTHERS | BUS | 6 | 5 | 5 | 10 | 5 | 14 | 6 | 10 | 12 | 12 | 12 | 12 |  | 50 Ohms | TOP=L2:L3=L2/L4:L6=L5/L7:BOTTOM=L7 |
| 8644_CBL_PRSNT_R_8 | OTHERS | BUS | 7 | 5 | 5 | 10 | 5 | 14 | 6 | 10 | 12 | 12 | 12 | 12 |  | 50 Ohms | TOP=L2:L3=L2/L4:L6=L5/L7:BOTTOM=L7 |
| 8644_CBL_PRSNT_R_8 | OTHERS | BUS | 8 | 4.75 | 5 | 10 | 5 | 14 | 6 | 9.5 | 12 | 12 | 12 | 12 |  | 50 Ohms | TOP=L2:L3=L2/L4:L6=L5/L7:BOTTOM=L7 |
| 8644_SDA_R_1 | OTHERS | BUS | 1 | 4.75 | 5 | 10 | 5 | 14 | 6 | 9.5 | 12 | 12 | 12 | 12 |  | 50 Ohms | TOP=L2:L3=L2/L4:L6=L5/L7:BOTTOM=L7 |
| 8644_SDA_R_1 | OTHERS | BUS | 2 | 5 | 5 | 10 | 5 | 14 | 6 | 10 | 12 | 12 | 12 | 12 |  | 50 Ohms | TOP=L2:L3=L2/L4:L6=L5/L7:BOTTOM=L7 |
| 8644_SDA_R_1 | OTHERS | BUS | 3 | 5 | 5 | 10 | 5 | 14 | 6 | 10 | 12 | 12 | 12 | 12 |  | 50 Ohms | TOP=L2:L3=L2/L4:L6=L5/L7:BOTTOM=L7 |
| 8644_SDA_R_1 | OTHERS | BUS | 4 | 5 | 5 | 10 | 5 | 14 | 6 | 10 | 12 | 12 | 12 | 12 |  | 50 Ohms | TOP=L2:L3=L2/L4:L6=L5/L7:BOTTOM=L7 |
| 8644_SDA_R_1 | OTHERS | BUS | 5 | 5 | 5 | 10 | 5 | 14 | 6 | 10 | 12 | 12 | 12 | 12 |  | 50 Ohms | TOP=L2:L3=L2/L4:L6=L5/L7:BOTTOM=L7 |
| 8644_SDA_R_1 | OTHERS | BUS | 6 | 5 | 5 | 10 | 5 | 14 | 6 | 10 | 12 | 12 | 12 | 12 |  | 50 Ohms | TOP=L2:L3=L2/L4:L6=L5/L7:BOTTOM=L7 |
| 8644_SDA_R_1 | OTHERS | BUS | 7 | 5 | 5 | 10 | 5 | 14 | 6 | 10 | 12 | 12 | 12 | 12 |  | 50 Ohms | TOP=L2:L3=L2/L4:L6=L5/L7:BOTTOM=L7 |
| 8644_SDA_R_1 | OTHERS | BUS | 8 | 4.75 | 5 | 10 | 5 | 14 | 6 | 9.5 | 12 | 12 | 12 | 12 |  | 50 Ohms | TOP=L2:L3=L2/L4:L6=L5/L7:BOTTOM=L7 |
| 8644_SDA_R_2 | OTHERS | BUS | 1 | 4.75 | 5 | 10 | 5 | 14 | 6 | 9.5 | 12 | 12 | 12 | 12 |  | 50 Ohms | TOP=L2:L3=L2/L4:L6=L5/L7:BOTTOM=L7 |
| 8644_SDA_R_2 | OTHERS | BUS | 2 | 5 | 5 | 10 | 5 | 14 | 6 | 10 | 12 | 12 | 12 | 12 |  | 50 Ohms | TOP=L2:L3=L2/L4:L6=L5/L7:BOTTOM=L7 |
| 8644_SDA_R_2 | OTHERS | BUS | 3 | 5 | 5 | 10 | 5 | 14 | 6 | 10 | 12 | 12 | 12 | 12 |  | 50 Ohms | TOP=L2:L3=L2/L4:L6=L5/L7:BOTTOM=L7 |
| 8644_SDA_R_2 | OTHERS | BUS | 4 | 5 | 5 | 10 | 5 | 14 | 6 | 10 | 12 | 12 | 12 | 12 |  | 50 Ohms | TOP=L2:L3=L2/L4:L6=L5/L7:BOTTOM=L7 |
| 8644_SDA_R_2 | OTHERS | BUS | 5 | 5 | 5 | 10 | 5 | 14 | 6 | 10 | 12 | 12 | 12 | 12 |  | 50 Ohms | TOP=L2:L3=L2/L4:L6=L5/L7:BOTTOM=L7 |
| 8644_SDA_R_2 | OTHERS | BUS | 6 | 5 | 5 | 10 | 5 | 14 | 6 | 10 | 12 | 12 | 12 | 12 |  | 50 Ohms | TOP=L2:L3=L2/L4:L6=L5/L7:BOTTOM=L7 |
| 8644_SDA_R_2 | OTHERS | BUS | 7 | 5 | 5 | 10 | 5 | 14 | 6 | 10 | 12 | 12 | 12 | 12 |  | 50 Ohms | TOP=L2:L3=L2/L4:L6=L5/L7:BOTTOM=L7 |
| 8644_SDA_R_2 | OTHERS | BUS | 8 | 4.75 | 5 | 10 | 5 | 14 | 6 | 9.5 | 12 | 12 | 12 | 12 |  | 50 Ohms | TOP=L2:L3=L2/L4:L6=L5/L7:BOTTOM=L7 |
| 8644_SDA_R_3 | OTHERS | BUS | 1 | 4.75 | 5 | 10 | 5 | 14 | 6 | 9.5 | 12 | 12 | 12 | 12 |  | 50 Ohms | TOP=L2:L3=L2/L4:L6=L5/L7:BOTTOM=L7 |
| 8644_SDA_R_3 | OTHERS | BUS | 2 | 5 | 5 | 10 | 5 | 14 | 6 | 10 | 12 | 12 | 12 | 12 |  | 50 Ohms | TOP=L2:L3=L2/L4:L6=L5/L7:BOTTOM=L7 |
| 8644_SDA_R_3 | OTHERS | BUS | 3 | 5 | 5 | 10 | 5 | 14 | 6 | 10 | 12 | 12 | 12 | 12 |  | 50 Ohms | TOP=L2:L3=L2/L4:L6=L5/L7:BOTTOM=L7 |
| 8644_SDA_R_3 | OTHERS | BUS | 4 | 5 | 5 | 10 | 5 | 14 | 6 | 10 | 12 | 12 | 12 | 12 |  | 50 Ohms | TOP=L2:L3=L2/L4:L6=L5/L7:BOTTOM=L7 |
| 8644_SDA_R_3 | OTHERS | BUS | 5 | 5 | 5 | 10 | 5 | 14 | 6 | 10 | 12 | 12 | 12 | 12 |  | 50 Ohms | TOP=L2:L3=L2/L4:L6=L5/L7:BOTTOM=L7 |
| 8644_SDA_R_3 | OTHERS | BUS | 6 | 5 | 5 | 10 | 5 | 14 | 6 | 10 | 12 | 12 | 12 | 12 |  | 50 Ohms | TOP=L2:L3=L2/L4:L6=L5/L7:BOTTOM=L7 |
| 8644_SDA_R_3 | OTHERS | BUS | 7 | 5 | 5 | 10 | 5 | 14 | 6 | 10 | 12 | 12 | 12 | 12 |  | 50 Ohms | TOP=L2:L3=L2/L4:L6=L5/L7:BOTTOM=L7 |
| 8644_SDA_R_3 | OTHERS | BUS | 8 | 4.75 | 5 | 10 | 5 | 14 | 6 | 9.5 | 12 | 12 | 12 | 12 |  | 50 Ohms | TOP=L2:L3=L2/L4:L6=L5/L7:BOTTOM=L7 |
| 8644_SDA_R_4 | OTHERS | BUS | 1 | 4.75 | 5 | 10 | 5 | 14 | 6 | 9.5 | 12 | 12 | 12 | 12 |  | 50 Ohms | TOP=L2:L3=L2/L4:L6=L5/L7:BOTTOM=L7 |
| 8644_SDA_R_4 | OTHERS | BUS | 2 | 5 | 5 | 10 | 5 | 14 | 6 | 10 | 12 | 12 | 12 | 12 |  | 50 Ohms | TOP=L2:L3=L2/L4:L6=L5/L7:BOTTOM=L7 |
| 8644_SDA_R_4 | OTHERS | BUS | 3 | 5 | 5 | 10 | 5 | 14 | 6 | 10 | 12 | 12 | 12 | 12 |  | 50 Ohms | TOP=L2:L3=L2/L4:L6=L5/L7:BOTTOM=L7 |
| 8644_SDA_R_4 | OTHERS | BUS | 4 | 5 | 5 | 10 | 5 | 14 | 6 | 10 | 12 | 12 | 12 | 12 |  | 50 Ohms | TOP=L2:L3=L2/L4:L6=L5/L7:BOTTOM=L7 |
| 8644_SDA_R_4 | OTHERS | BUS | 5 | 5 | 5 | 10 | 5 | 14 | 6 | 10 | 12 | 12 | 12 | 12 |  | 50 Ohms | TOP=L2:L3=L2/L4:L6=L5/L7:BOTTOM=L7 |
| 8644_SDA_R_4 | OTHERS | BUS | 6 | 5 | 5 | 10 | 5 | 14 | 6 | 10 | 12 | 12 | 12 | 12 |  | 50 Ohms | TOP=L2:L3=L2/L4:L6=L5/L7:BOTTOM=L7 |
| 8644_SDA_R_4 | OTHERS | BUS | 7 | 5 | 5 | 10 | 5 | 14 | 6 | 10 | 12 | 12 | 12 | 12 |  | 50 Ohms | TOP=L2:L3=L2/L4:L6=L5/L7:BOTTOM=L7 |
| 8644_SDA_R_4 | OTHERS | BUS | 8 | 4.75 | 5 | 10 | 5 | 14 | 6 | 9.5 | 12 | 12 | 12 | 12 |  | 50 Ohms | TOP=L2:L3=L2/L4:L6=L5/L7:BOTTOM=L7 |
| 8644_SDA_R_5 | OTHERS | BUS | 1 | 4.75 | 5 | 10 | 5 | 14 | 6 | 9.5 | 12 | 12 | 12 | 12 |  | 50 Ohms | TOP=L2:L3=L2/L4:L6=L5/L7:BOTTOM=L7 |
| 8644_SDA_R_5 | OTHERS | BUS | 2 | 5 | 5 | 10 | 5 | 14 | 6 | 10 | 12 | 12 | 12 | 12 |  | 50 Ohms | TOP=L2:L3=L2/L4:L6=L5/L7:BOTTOM=L7 |
| 8644_SDA_R_5 | OTHERS | BUS | 3 | 5 | 5 | 10 | 5 | 14 | 6 | 10 | 12 | 12 | 12 | 12 |  | 50 Ohms | TOP=L2:L3=L2/L4:L6=L5/L7:BOTTOM=L7 |
| 8644_SDA_R_5 | OTHERS | BUS | 4 | 5 | 5 | 10 | 5 | 14 | 6 | 10 | 12 | 12 | 12 | 12 |  | 50 Ohms | TOP=L2:L3=L2/L4:L6=L5/L7:BOTTOM=L7 |
| 8644_SDA_R_5 | OTHERS | BUS | 5 | 5 | 5 | 10 | 5 | 14 | 6 | 10 | 12 | 12 | 12 | 12 |  | 50 Ohms | TOP=L2:L3=L2/L4:L6=L5/L7:BOTTOM=L7 |
| 8644_SDA_R_5 | OTHERS | BUS | 6 | 5 | 5 | 10 | 5 | 14 | 6 | 10 | 12 | 12 | 12 | 12 |  | 50 Ohms | TOP=L2:L3=L2/L4:L6=L5/L7:BOTTOM=L7 |
| 8644_SDA_R_5 | OTHERS | BUS | 7 | 5 | 5 | 10 | 5 | 14 | 6 | 10 | 12 | 12 | 12 | 12 |  | 50 Ohms | TOP=L2:L3=L2/L4:L6=L5/L7:BOTTOM=L7 |
| 8644_SDA_R_5 | OTHERS | BUS | 8 | 4.75 | 5 | 10 | 5 | 14 | 6 | 9.5 | 12 | 12 | 12 | 12 |  | 50 Ohms | TOP=L2:L3=L2/L4:L6=L5/L7:BOTTOM=L7 |
| 8644_SDA_R_6 | OTHERS | BUS | 1 | 4.75 | 5 | 10 | 5 | 14 | 6 | 9.5 | 12 | 12 | 12 | 12 |  | 50 Ohms | TOP=L2:L3=L2/L4:L6=L5/L7:BOTTOM=L7 |
| 8644_SDA_R_6 | OTHERS | BUS | 2 | 5 | 5 | 10 | 5 | 14 | 6 | 10 | 12 | 12 | 12 | 12 |  | 50 Ohms | TOP=L2:L3=L2/L4:L6=L5/L7:BOTTOM=L7 |
| 8644_SDA_R_6 | OTHERS | BUS | 3 | 5 | 5 | 10 | 5 | 14 | 6 | 10 | 12 | 12 | 12 | 12 |  | 50 Ohms | TOP=L2:L3=L2/L4:L6=L5/L7:BOTTOM=L7 |
| 8644_SDA_R_6 | OTHERS | BUS | 4 | 5 | 5 | 10 | 5 | 14 | 6 | 10 | 12 | 12 | 12 | 12 |  | 50 Ohms | TOP=L2:L3=L2/L4:L6=L5/L7:BOTTOM=L7 |
| 8644_SDA_R_6 | OTHERS | BUS | 5 | 5 | 5 | 10 | 5 | 14 | 6 | 10 | 12 | 12 | 12 | 12 |  | 50 Ohms | TOP=L2:L3=L2/L4:L6=L5/L7:BOTTOM=L7 |
| 8644_SDA_R_6 | OTHERS | BUS | 6 | 5 | 5 | 10 | 5 | 14 | 6 | 10 | 12 | 12 | 12 | 12 |  | 50 Ohms | TOP=L2:L3=L2/L4:L6=L5/L7:BOTTOM=L7 |
| 8644_SDA_R_6 | OTHERS | BUS | 7 | 5 | 5 | 10 | 5 | 14 | 6 | 10 | 12 | 12 | 12 | 12 |  | 50 Ohms | TOP=L2:L3=L2/L4:L6=L5/L7:BOTTOM=L7 |
| 8644_SDA_R_6 | OTHERS | BUS | 8 | 4.75 | 5 | 10 | 5 | 14 | 6 | 9.5 | 12 | 12 | 12 | 12 |  | 50 Ohms | TOP=L2:L3=L2/L4:L6=L5/L7:BOTTOM=L7 |
| 8644_SDA_R_7 | OTHERS | BUS | 1 | 4.75 | 5 | 10 | 5 | 14 | 6 | 9.5 | 12 | 12 | 12 | 12 |  | 50 Ohms | TOP=L2:L3=L2/L4:L6=L5/L7:BOTTOM=L7 |
| 8644_SDA_R_7 | OTHERS | BUS | 2 | 5 | 5 | 10 | 5 | 14 | 6 | 10 | 12 | 12 | 12 | 12 |  | 50 Ohms | TOP=L2:L3=L2/L4:L6=L5/L7:BOTTOM=L7 |
| 8644_SDA_R_7 | OTHERS | BUS | 3 | 5 | 5 | 10 | 5 | 14 | 6 | 10 | 12 | 12 | 12 | 12 |  | 50 Ohms | TOP=L2:L3=L2/L4:L6=L5/L7:BOTTOM=L7 |
| 8644_SDA_R_7 | OTHERS | BUS | 4 | 5 | 5 | 10 | 5 | 14 | 6 | 10 | 12 | 12 | 12 | 12 |  | 50 Ohms | TOP=L2:L3=L2/L4:L6=L5/L7:BOTTOM=L7 |
| 8644_SDA_R_7 | OTHERS | BUS | 5 | 5 | 5 | 10 | 5 | 14 | 6 | 10 | 12 | 12 | 12 | 12 |  | 50 Ohms | TOP=L2:L3=L2/L4:L6=L5/L7:BOTTOM=L7 |
| 8644_SDA_R_7 | OTHERS | BUS | 6 | 5 | 5 | 10 | 5 | 14 | 6 | 10 | 12 | 12 | 12 | 12 |  | 50 Ohms | TOP=L2:L3=L2/L4:L6=L5/L7:BOTTOM=L7 |
| 8644_SDA_R_7 | OTHERS | BUS | 7 | 5 | 5 | 10 | 5 | 14 | 6 | 10 | 12 | 12 | 12 | 12 |  | 50 Ohms | TOP=L2:L3=L2/L4:L6=L5/L7:BOTTOM=L7 |
| 8644_SDA_R_7 | OTHERS | BUS | 8 | 4.75 | 5 | 10 | 5 | 14 | 6 | 9.5 | 12 | 12 | 12 | 12 |  | 50 Ohms | TOP=L2:L3=L2/L4:L6=L5/L7:BOTTOM=L7 |
| 8644_SDA_R_8 | OTHERS | BUS | 1 | 4.75 | 5 | 10 | 5 | 14 | 6 | 9.5 | 12 | 12 | 12 | 12 |  | 50 Ohms | TOP=L2:L3=L2/L4:L6=L5/L7:BOTTOM=L7 |
| 8644_SDA_R_8 | OTHERS | BUS | 2 | 5 | 5 | 10 | 5 | 14 | 6 | 10 | 12 | 12 | 12 | 12 |  | 50 Ohms | TOP=L2:L3=L2/L4:L6=L5/L7:BOTTOM=L7 |
| 8644_SDA_R_8 | OTHERS | BUS | 3 | 5 | 5 | 10 | 5 | 14 | 6 | 10 | 12 | 12 | 12 | 12 |  | 50 Ohms | TOP=L2:L3=L2/L4:L6=L5/L7:BOTTOM=L7 |
| 8644_SDA_R_8 | OTHERS | BUS | 4 | 5 | 5 | 10 | 5 | 14 | 6 | 10 | 12 | 12 | 12 | 12 |  | 50 Ohms | TOP=L2:L3=L2/L4:L6=L5/L7:BOTTOM=L7 |
| 8644_SDA_R_8 | OTHERS | BUS | 5 | 5 | 5 | 10 | 5 | 14 | 6 | 10 | 12 | 12 | 12 | 12 |  | 50 Ohms | TOP=L2:L3=L2/L4:L6=L5/L7:BOTTOM=L7 |
| 8644_SDA_R_8 | OTHERS | BUS | 6 | 5 | 5 | 10 | 5 | 14 | 6 | 10 | 12 | 12 | 12 | 12 |  | 50 Ohms | TOP=L2:L3=L2/L4:L6=L5/L7:BOTTOM=L7 |
| 8644_SDA_R_8 | OTHERS | BUS | 7 | 5 | 5 | 10 | 5 | 14 | 6 | 10 | 12 | 12 | 12 | 12 |  | 50 Ohms | TOP=L2:L3=L2/L4:L6=L5/L7:BOTTOM=L7 |
| 8644_SDA_R_8 | OTHERS | BUS | 8 | 4.75 | 5 | 10 | 5 | 14 | 6 | 9.5 | 12 | 12 | 12 | 12 |  | 50 Ohms | TOP=L2:L3=L2/L4:L6=L5/L7:BOTTOM=L7 |
| ADC_P0V9_BMC | OTHERS | BUS | 1 | 4.75 | 5 | 10 | 5 | 14 | 6 | 9.5 | 12 | 12 | 12 | 12 |  | 50 Ohms | TOP=L2:L3=L2/L4:L6=L5/L7:BOTTOM=L7 |
| ADC_P0V9_BMC | OTHERS | BUS | 2 | 5 | 5 | 10 | 5 | 14 | 6 | 10 | 12 | 12 | 12 | 12 |  | 50 Ohms | TOP=L2:L3=L2/L4:L6=L5/L7:BOTTOM=L7 |
| ADC_P0V9_BMC | OTHERS | BUS | 3 | 5 | 5 | 10 | 5 | 14 | 6 | 10 | 12 | 12 | 12 | 12 |  | 50 Ohms | TOP=L2:L3=L2/L4:L6=L5/L7:BOTTOM=L7 |
| ADC_P0V9_BMC | OTHERS | BUS | 4 | 5 | 5 | 10 | 5 | 14 | 6 | 10 | 12 | 12 | 12 | 12 |  | 50 Ohms | TOP=L2:L3=L2/L4:L6=L5/L7:BOTTOM=L7 |
| ADC_P0V9_BMC | OTHERS | BUS | 5 | 5 | 5 | 10 | 5 | 14 | 6 | 10 | 12 | 12 | 12 | 12 |  | 50 Ohms | TOP=L2:L3=L2/L4:L6=L5/L7:BOTTOM=L7 |
| ADC_P0V9_BMC | OTHERS | BUS | 6 | 5 | 5 | 10 | 5 | 14 | 6 | 10 | 12 | 12 | 12 | 12 |  | 50 Ohms | TOP=L2:L3=L2/L4:L6=L5/L7:BOTTOM=L7 |
| ADC_P0V9_BMC | OTHERS | BUS | 7 | 5 | 5 | 10 | 5 | 14 | 6 | 10 | 12 | 12 | 12 | 12 |  | 50 Ohms | TOP=L2:L3=L2/L4:L6=L5/L7:BOTTOM=L7 |
| ADC_P0V9_BMC | OTHERS | BUS | 8 | 4.75 | 5 | 10 | 5 | 14 | 6 | 9.5 | 12 | 12 | 12 | 12 |  | 50 Ohms | TOP=L2:L3=L2/L4:L6=L5/L7:BOTTOM=L7 |
| ADC_P1V26_BMC | OTHERS | BUS | 1 | 4.75 | 5 | 10 | 5 | 14 | 6 | 9.5 | 12 | 12 | 12 | 12 |  | 50 Ohms | TOP=L2:L3=L2/L4:L6=L5/L7:BOTTOM=L7 |
| ADC_P1V26_BMC | OTHERS | BUS | 2 | 5 | 5 | 10 | 5 | 14 | 6 | 10 | 12 | 12 | 12 | 12 |  | 50 Ohms | TOP=L2:L3=L2/L4:L6=L5/L7:BOTTOM=L7 |
| ADC_P1V26_BMC | OTHERS | BUS | 3 | 5 | 5 | 10 | 5 | 14 | 6 | 10 | 12 | 12 | 12 | 12 |  | 50 Ohms | TOP=L2:L3=L2/L4:L6=L5/L7:BOTTOM=L7 |
| ADC_P1V26_BMC | OTHERS | BUS | 4 | 5 | 5 | 10 | 5 | 14 | 6 | 10 | 12 | 12 | 12 | 12 |  | 50 Ohms | TOP=L2:L3=L2/L4:L6=L5/L7:BOTTOM=L7 |
| ADC_P1V26_BMC | OTHERS | BUS | 5 | 5 | 5 | 10 | 5 | 14 | 6 | 10 | 12 | 12 | 12 | 12 |  | 50 Ohms | TOP=L2:L3=L2/L4:L6=L5/L7:BOTTOM=L7 |
| ADC_P1V26_BMC | OTHERS | BUS | 6 | 5 | 5 | 10 | 5 | 14 | 6 | 10 | 12 | 12 | 12 | 12 |  | 50 Ohms | TOP=L2:L3=L2/L4:L6=L5/L7:BOTTOM=L7 |
| ADC_P1V26_BMC | OTHERS | BUS | 7 | 5 | 5 | 10 | 5 | 14 | 6 | 10 | 12 | 12 | 12 | 12 |  | 50 Ohms | TOP=L2:L3=L2/L4:L6=L5/L7:BOTTOM=L7 |
| ADC_P1V26_BMC | OTHERS | BUS | 8 | 4.75 | 5 | 10 | 5 | 14 | 6 | 9.5 | 12 | 12 | 12 | 12 |  | 50 Ohms | TOP=L2:L3=L2/L4:L6=L5/L7:BOTTOM=L7 |
| ADC_P1V53_BMC | OTHERS | BUS | 1 | 4.75 | 5 | 10 | 5 | 14 | 6 | 9.5 | 12 | 12 | 12 | 12 |  | 50 Ohms | TOP=L2:L3=L2/L4:L6=L5/L7:BOTTOM=L7 |
| ADC_P1V53_BMC | OTHERS | BUS | 2 | 5 | 5 | 10 | 5 | 14 | 6 | 10 | 12 | 12 | 12 | 12 |  | 50 Ohms | TOP=L2:L3=L2/L4:L6=L5/L7:BOTTOM=L7 |
| ADC_P1V53_BMC | OTHERS | BUS | 3 | 5 | 5 | 10 | 5 | 14 | 6 | 10 | 12 | 12 | 12 | 12 |  | 50 Ohms | TOP=L2:L3=L2/L4:L6=L5/L7:BOTTOM=L7 |
| ADC_P1V53_BMC | OTHERS | BUS | 4 | 5 | 5 | 10 | 5 | 14 | 6 | 10 | 12 | 12 | 12 | 12 |  | 50 Ohms | TOP=L2:L3=L2/L4:L6=L5/L7:BOTTOM=L7 |
| ADC_P1V53_BMC | OTHERS | BUS | 5 | 5 | 5 | 10 | 5 | 14 | 6 | 10 | 12 | 12 | 12 | 12 |  | 50 Ohms | TOP=L2:L3=L2/L4:L6=L5/L7:BOTTOM=L7 |
| ADC_P1V53_BMC | OTHERS | BUS | 6 | 5 | 5 | 10 | 5 | 14 | 6 | 10 | 12 | 12 | 12 | 12 |  | 50 Ohms | TOP=L2:L3=L2/L4:L6=L5/L7:BOTTOM=L7 |
| ADC_P1V53_BMC | OTHERS | BUS | 7 | 5 | 5 | 10 | 5 | 14 | 6 | 10 | 12 | 12 | 12 | 12 |  | 50 Ohms | TOP=L2:L3=L2/L4:L6=L5/L7:BOTTOM=L7 |
| ADC_P1V53_BMC | OTHERS | BUS | 8 | 4.75 | 5 | 10 | 5 | 14 | 6 | 9.5 | 12 | 12 | 12 | 12 |  | 50 Ohms | TOP=L2:L3=L2/L4:L6=L5/L7:BOTTOM=L7 |
| ADM1278_HS_N | OTHERS | BUS | 1 | 4.75 | 5 | 10 | 5 | 14 | 6 | 9.5 | 12 | 12 | 12 | 12 |  | 50 Ohms | TOP=L2:L3=L2/L4:L6=L5/L7:BOTTOM=L7 |
| ADM1278_HS_N | OTHERS | BUS | 2 | 5 | 5 | 10 | 5 | 14 | 6 | 10 | 12 | 12 | 12 | 12 |  | 50 Ohms | TOP=L2:L3=L2/L4:L6=L5/L7:BOTTOM=L7 |
| ADM1278_HS_N | OTHERS | BUS | 3 | 5 | 5 | 10 | 5 | 14 | 6 | 10 | 12 | 12 | 12 | 12 |  | 50 Ohms | TOP=L2:L3=L2/L4:L6=L5/L7:BOTTOM=L7 |
| ADM1278_HS_N | OTHERS | BUS | 4 | 5 | 5 | 10 | 5 | 14 | 6 | 10 | 12 | 12 | 12 | 12 |  | 50 Ohms | TOP=L2:L3=L2/L4:L6=L5/L7:BOTTOM=L7 |
| ADM1278_HS_N | OTHERS | BUS | 5 | 5 | 5 | 10 | 5 | 14 | 6 | 10 | 12 | 12 | 12 | 12 |  | 50 Ohms | TOP=L2:L3=L2/L4:L6=L5/L7:BOTTOM=L7 |
| ADM1278_HS_N | OTHERS | BUS | 6 | 5 | 5 | 10 | 5 | 14 | 6 | 10 | 12 | 12 | 12 | 12 |  | 50 Ohms | TOP=L2:L3=L2/L4:L6=L5/L7:BOTTOM=L7 |
| ADM1278_HS_N | OTHERS | BUS | 7 | 5 | 5 | 10 | 5 | 14 | 6 | 10 | 12 | 12 | 12 | 12 |  | 50 Ohms | TOP=L2:L3=L2/L4:L6=L5/L7:BOTTOM=L7 |
| ADM1278_HS_N | OTHERS | BUS | 8 | 4.75 | 5 | 10 | 5 | 14 | 6 | 9.5 | 12 | 12 | 12 | 12 |  | 50 Ohms | TOP=L2:L3=L2/L4:L6=L5/L7:BOTTOM=L7 |
| ADM1278_HS_P | OTHERS | BUS | 1 | 4.75 | 5 | 10 | 5 | 14 | 6 | 9.5 | 12 | 12 | 12 | 12 |  | 50 Ohms | TOP=L2:L3=L2/L4:L6=L5/L7:BOTTOM=L7 |
| ADM1278_HS_P | OTHERS | BUS | 2 | 5 | 5 | 10 | 5 | 14 | 6 | 10 | 12 | 12 | 12 | 12 |  | 50 Ohms | TOP=L2:L3=L2/L4:L6=L5/L7:BOTTOM=L7 |
| ADM1278_HS_P | OTHERS | BUS | 3 | 5 | 5 | 10 | 5 | 14 | 6 | 10 | 12 | 12 | 12 | 12 |  | 50 Ohms | TOP=L2:L3=L2/L4:L6=L5/L7:BOTTOM=L7 |
| ADM1278_HS_P | OTHERS | BUS | 4 | 5 | 5 | 10 | 5 | 14 | 6 | 10 | 12 | 12 | 12 | 12 |  | 50 Ohms | TOP=L2:L3=L2/L4:L6=L5/L7:BOTTOM=L7 |
| ADM1278_HS_P | OTHERS | BUS | 5 | 5 | 5 | 10 | 5 | 14 | 6 | 10 | 12 | 12 | 12 | 12 |  | 50 Ohms | TOP=L2:L3=L2/L4:L6=L5/L7:BOTTOM=L7 |
| ADM1278_HS_P | OTHERS | BUS | 6 | 5 | 5 | 10 | 5 | 14 | 6 | 10 | 12 | 12 | 12 | 12 |  | 50 Ohms | TOP=L2:L3=L2/L4:L6=L5/L7:BOTTOM=L7 |
| ADM1278_HS_P | OTHERS | BUS | 7 | 5 | 5 | 10 | 5 | 14 | 6 | 10 | 12 | 12 | 12 | 12 |  | 50 Ohms | TOP=L2:L3=L2/L4:L6=L5/L7:BOTTOM=L7 |
| ADM1278_HS_P | OTHERS | BUS | 8 | 4.75 | 5 | 10 | 5 | 14 | 6 | 9.5 | 12 | 12 | 12 | 12 |  | 50 Ohms | TOP=L2:L3=L2/L4:L6=L5/L7:BOTTOM=L7 |
| ADM6315_PM8536_RST# | OTHERS | BUS | 1 | 4.75 | 5 | 10 | 5 | 14 | 6 | 9.5 | 12 | 12 | 12 | 12 |  | 50 Ohms | TOP=L2:L3=L2/L4:L6=L5/L7:BOTTOM=L7 |
| ADM6315_PM8536_RST# | OTHERS | BUS | 2 | 5 | 5 | 10 | 5 | 14 | 6 | 10 | 12 | 12 | 12 | 12 |  | 50 Ohms | TOP=L2:L3=L2/L4:L6=L5/L7:BOTTOM=L7 |
| ADM6315_PM8536_RST# | OTHERS | BUS | 3 | 5 | 5 | 10 | 5 | 14 | 6 | 10 | 12 | 12 | 12 | 12 |  | 50 Ohms | TOP=L2:L3=L2/L4:L6=L5/L7:BOTTOM=L7 |
| ADM6315_PM8536_RST# | OTHERS | BUS | 4 | 5 | 5 | 10 | 5 | 14 | 6 | 10 | 12 | 12 | 12 | 12 |  | 50 Ohms | TOP=L2:L3=L2/L4:L6=L5/L7:BOTTOM=L7 |
| ADM6315_PM8536_RST# | OTHERS | BUS | 5 | 5 | 5 | 10 | 5 | 14 | 6 | 10 | 12 | 12 | 12 | 12 |  | 50 Ohms | TOP=L2:L3=L2/L4:L6=L5/L7:BOTTOM=L7 |
| ADM6315_PM8536_RST# | OTHERS | BUS | 6 | 5 | 5 | 10 | 5 | 14 | 6 | 10 | 12 | 12 | 12 | 12 |  | 50 Ohms | TOP=L2:L3=L2/L4:L6=L5/L7:BOTTOM=L7 |
| ADM6315_PM8536_RST# | OTHERS | BUS | 7 | 5 | 5 | 10 | 5 | 14 | 6 | 10 | 12 | 12 | 12 | 12 |  | 50 Ohms | TOP=L2:L3=L2/L4:L6=L5/L7:BOTTOM=L7 |
| ADM6315_PM8536_RST# | OTHERS | BUS | 8 | 4.75 | 5 | 10 | 5 | 14 | 6 | 9.5 | 12 | 12 | 12 | 12 |  | 50 Ohms | TOP=L2:L3=L2/L4:L6=L5/L7:BOTTOM=L7 |
| AS_ROMA0_R | OTHERS | BUS | 1 | 4.75 | 5 | 10 | 5 | 14 | 6 | 9.5 | 12 | 12 | 12 | 12 |  | 50 Ohms | TOP=L2:L3=L2/L4:L6=L5/L7:BOTTOM=L7 |
| AS_ROMA0_R | OTHERS | BUS | 2 | 5 | 5 | 10 | 5 | 14 | 6 | 10 | 12 | 12 | 12 | 12 |  | 50 Ohms | TOP=L2:L3=L2/L4:L6=L5/L7:BOTTOM=L7 |
| AS_ROMA0_R | OTHERS | BUS | 3 | 5 | 5 | 10 | 5 | 14 | 6 | 10 | 12 | 12 | 12 | 12 |  | 50 Ohms | TOP=L2:L3=L2/L4:L6=L5/L7:BOTTOM=L7 |
| AS_ROMA0_R | OTHERS | BUS | 4 | 5 | 5 | 10 | 5 | 14 | 6 | 10 | 12 | 12 | 12 | 12 |  | 50 Ohms | TOP=L2:L3=L2/L4:L6=L5/L7:BOTTOM=L7 |
| AS_ROMA0_R | OTHERS | BUS | 5 | 5 | 5 | 10 | 5 | 14 | 6 | 10 | 12 | 12 | 12 | 12 |  | 50 Ohms | TOP=L2:L3=L2/L4:L6=L5/L7:BOTTOM=L7 |
| AS_ROMA0_R | OTHERS | BUS | 6 | 5 | 5 | 10 | 5 | 14 | 6 | 10 | 12 | 12 | 12 | 12 |  | 50 Ohms | TOP=L2:L3=L2/L4:L6=L5/L7:BOTTOM=L7 |
| AS_ROMA0_R | OTHERS | BUS | 7 | 5 | 5 | 10 | 5 | 14 | 6 | 10 | 12 | 12 | 12 | 12 |  | 50 Ohms | TOP=L2:L3=L2/L4:L6=L5/L7:BOTTOM=L7 |
| AS_ROMA0_R | OTHERS | BUS | 8 | 4.75 | 5 | 10 | 5 | 14 | 6 | 9.5 | 12 | 12 | 12 | 12 |  | 50 Ohms | TOP=L2:L3=L2/L4:L6=L5/L7:BOTTOM=L7 |
| AVS_ENB | OTHERS | BUS | 1 | 4.75 | 5 | 10 | 5 | 14 | 6 | 9.5 | 12 | 12 | 12 | 12 |  | 50 Ohms | TOP=L2:L3=L2/L4:L6=L5/L7:BOTTOM=L7 |
| AVS_ENB | OTHERS | BUS | 2 | 5 | 5 | 10 | 5 | 14 | 6 | 10 | 12 | 12 | 12 | 12 |  | 50 Ohms | TOP=L2:L3=L2/L4:L6=L5/L7:BOTTOM=L7 |
| AVS_ENB | OTHERS | BUS | 3 | 5 | 5 | 10 | 5 | 14 | 6 | 10 | 12 | 12 | 12 | 12 |  | 50 Ohms | TOP=L2:L3=L2/L4:L6=L5/L7:BOTTOM=L7 |
| AVS_ENB | OTHERS | BUS | 4 | 5 | 5 | 10 | 5 | 14 | 6 | 10 | 12 | 12 | 12 | 12 |  | 50 Ohms | TOP=L2:L3=L2/L4:L6=L5/L7:BOTTOM=L7 |
| AVS_ENB | OTHERS | BUS | 5 | 5 | 5 | 10 | 5 | 14 | 6 | 10 | 12 | 12 | 12 | 12 |  | 50 Ohms | TOP=L2:L3=L2/L4:L6=L5/L7:BOTTOM=L7 |
| AVS_ENB | OTHERS | BUS | 6 | 5 | 5 | 10 | 5 | 14 | 6 | 10 | 12 | 12 | 12 | 12 |  | 50 Ohms | TOP=L2:L3=L2/L4:L6=L5/L7:BOTTOM=L7 |
| AVS_ENB | OTHERS | BUS | 7 | 5 | 5 | 10 | 5 | 14 | 6 | 10 | 12 | 12 | 12 | 12 |  | 50 Ohms | TOP=L2:L3=L2/L4:L6=L5/L7:BOTTOM=L7 |
| AVS_ENB | OTHERS | BUS | 8 | 4.75 | 5 | 10 | 5 | 14 | 6 | 9.5 | 12 | 12 | 12 | 12 |  | 50 Ohms | TOP=L2:L3=L2/L4:L6=L5/L7:BOTTOM=L7 |
| AVS_ENB_R | OTHERS | BUS | 1 | 4.75 | 5 | 10 | 5 | 14 | 6 | 9.5 | 12 | 12 | 12 | 12 |  | 50 Ohms | TOP=L2:L3=L2/L4:L6=L5/L7:BOTTOM=L7 |
| AVS_ENB_R | OTHERS | BUS | 2 | 5 | 5 | 10 | 5 | 14 | 6 | 10 | 12 | 12 | 12 | 12 |  | 50 Ohms | TOP=L2:L3=L2/L4:L6=L5/L7:BOTTOM=L7 |
| AVS_ENB_R | OTHERS | BUS | 3 | 5 | 5 | 10 | 5 | 14 | 6 | 10 | 12 | 12 | 12 | 12 |  | 50 Ohms | TOP=L2:L3=L2/L4:L6=L5/L7:BOTTOM=L7 |
| AVS_ENB_R | OTHERS | BUS | 4 | 5 | 5 | 10 | 5 | 14 | 6 | 10 | 12 | 12 | 12 | 12 |  | 50 Ohms | TOP=L2:L3=L2/L4:L6=L5/L7:BOTTOM=L7 |
| AVS_ENB_R | OTHERS | BUS | 5 | 5 | 5 | 10 | 5 | 14 | 6 | 10 | 12 | 12 | 12 | 12 |  | 50 Ohms | TOP=L2:L3=L2/L4:L6=L5/L7:BOTTOM=L7 |
| AVS_ENB_R | OTHERS | BUS | 6 | 5 | 5 | 10 | 5 | 14 | 6 | 10 | 12 | 12 | 12 | 12 |  | 50 Ohms | TOP=L2:L3=L2/L4:L6=L5/L7:BOTTOM=L7 |
| AVS_ENB_R | OTHERS | BUS | 7 | 5 | 5 | 10 | 5 | 14 | 6 | 10 | 12 | 12 | 12 | 12 |  | 50 Ohms | TOP=L2:L3=L2/L4:L6=L5/L7:BOTTOM=L7 |
| AVS_ENB_R | OTHERS | BUS | 8 | 4.75 | 5 | 10 | 5 | 14 | 6 | 9.5 | 12 | 12 | 12 | 12 |  | 50 Ohms | TOP=L2:L3=L2/L4:L6=L5/L7:BOTTOM=L7 |
| AVS_ENB1_R | OTHERS | BUS | 1 | 4.75 | 5 | 10 | 5 | 14 | 6 | 9.5 | 12 | 12 | 12 | 12 |  | 50 Ohms | TOP=L2:L3=L2/L4:L6=L5/L7:BOTTOM=L7 |
| AVS_ENB1_R | OTHERS | BUS | 2 | 5 | 5 | 10 | 5 | 14 | 6 | 10 | 12 | 12 | 12 | 12 |  | 50 Ohms | TOP=L2:L3=L2/L4:L6=L5/L7:BOTTOM=L7 |
| AVS_ENB1_R | OTHERS | BUS | 3 | 5 | 5 | 10 | 5 | 14 | 6 | 10 | 12 | 12 | 12 | 12 |  | 50 Ohms | TOP=L2:L3=L2/L4:L6=L5/L7:BOTTOM=L7 |
| AVS_ENB1_R | OTHERS | BUS | 4 | 5 | 5 | 10 | 5 | 14 | 6 | 10 | 12 | 12 | 12 | 12 |  | 50 Ohms | TOP=L2:L3=L2/L4:L6=L5/L7:BOTTOM=L7 |
| AVS_ENB1_R | OTHERS | BUS | 5 | 5 | 5 | 10 | 5 | 14 | 6 | 10 | 12 | 12 | 12 | 12 |  | 50 Ohms | TOP=L2:L3=L2/L4:L6=L5/L7:BOTTOM=L7 |
| AVS_ENB1_R | OTHERS | BUS | 6 | 5 | 5 | 10 | 5 | 14 | 6 | 10 | 12 | 12 | 12 | 12 |  | 50 Ohms | TOP=L2:L3=L2/L4:L6=L5/L7:BOTTOM=L7 |
| AVS_ENB1_R | OTHERS | BUS | 7 | 5 | 5 | 10 | 5 | 14 | 6 | 10 | 12 | 12 | 12 | 12 |  | 50 Ohms | TOP=L2:L3=L2/L4:L6=L5/L7:BOTTOM=L7 |
| AVS_ENB1_R | OTHERS | BUS | 8 | 4.75 | 5 | 10 | 5 | 14 | 6 | 9.5 | 12 | 12 | 12 | 12 |  | 50 Ohms | TOP=L2:L3=L2/L4:L6=L5/L7:BOTTOM=L7 |
| AVS_ENB2_R | OTHERS | BUS | 1 | 4.75 | 5 | 10 | 5 | 14 | 6 | 9.5 | 12 | 12 | 12 | 12 |  | 50 Ohms | TOP=L2:L3=L2/L4:L6=L5/L7:BOTTOM=L7 |
| AVS_ENB2_R | OTHERS | BUS | 2 | 5 | 5 | 10 | 5 | 14 | 6 | 10 | 12 | 12 | 12 | 12 |  | 50 Ohms | TOP=L2:L3=L2/L4:L6=L5/L7:BOTTOM=L7 |
| AVS_ENB2_R | OTHERS | BUS | 3 | 5 | 5 | 10 | 5 | 14 | 6 | 10 | 12 | 12 | 12 | 12 |  | 50 Ohms | TOP=L2:L3=L2/L4:L6=L5/L7:BOTTOM=L7 |
| AVS_ENB2_R | OTHERS | BUS | 4 | 5 | 5 | 10 | 5 | 14 | 6 | 10 | 12 | 12 | 12 | 12 |  | 50 Ohms | TOP=L2:L3=L2/L4:L6=L5/L7:BOTTOM=L7 |
| AVS_ENB2_R | OTHERS | BUS | 5 | 5 | 5 | 10 | 5 | 14 | 6 | 10 | 12 | 12 | 12 | 12 |  | 50 Ohms | TOP=L2:L3=L2/L4:L6=L5/L7:BOTTOM=L7 |
| AVS_ENB2_R | OTHERS | BUS | 6 | 5 | 5 | 10 | 5 | 14 | 6 | 10 | 12 | 12 | 12 | 12 |  | 50 Ohms | TOP=L2:L3=L2/L4:L6=L5/L7:BOTTOM=L7 |
| AVS_ENB2_R | OTHERS | BUS | 7 | 5 | 5 | 10 | 5 | 14 | 6 | 10 | 12 | 12 | 12 | 12 |  | 50 Ohms | TOP=L2:L3=L2/L4:L6=L5/L7:BOTTOM=L7 |
| AVS_ENB2_R | OTHERS | BUS | 8 | 4.75 | 5 | 10 | 5 | 14 | 6 | 9.5 | 12 | 12 | 12 | 12 |  | 50 Ohms | TOP=L2:L3=L2/L4:L6=L5/L7:BOTTOM=L7 |
| BMC_ADD1 | OTHERS | BUS | 1 | 4.75 | 5 | 10 | 5 | 14 | 6 | 9.5 | 12 | 12 | 12 | 12 |  | 50 Ohms | TOP=L2:L3=L2/L4:L6=L5/L7:BOTTOM=L7 |
| BMC_ADD1 | OTHERS | BUS | 2 | 5 | 5 | 10 | 5 | 14 | 6 | 10 | 12 | 12 | 12 | 12 |  | 50 Ohms | TOP=L2:L3=L2/L4:L6=L5/L7:BOTTOM=L7 |
| BMC_ADD1 | OTHERS | BUS | 3 | 5 | 5 | 10 | 5 | 14 | 6 | 10 | 12 | 12 | 12 | 12 |  | 50 Ohms | TOP=L2:L3=L2/L4:L6=L5/L7:BOTTOM=L7 |
| BMC_ADD1 | OTHERS | BUS | 4 | 5 | 5 | 10 | 5 | 14 | 6 | 10 | 12 | 12 | 12 | 12 |  | 50 Ohms | TOP=L2:L3=L2/L4:L6=L5/L7:BOTTOM=L7 |
| BMC_ADD1 | OTHERS | BUS | 5 | 5 | 5 | 10 | 5 | 14 | 6 | 10 | 12 | 12 | 12 | 12 |  | 50 Ohms | TOP=L2:L3=L2/L4:L6=L5/L7:BOTTOM=L7 |
| BMC_ADD1 | OTHERS | BUS | 6 | 5 | 5 | 10 | 5 | 14 | 6 | 10 | 12 | 12 | 12 | 12 |  | 50 Ohms | TOP=L2:L3=L2/L4:L6=L5/L7:BOTTOM=L7 |
| BMC_ADD1 | OTHERS | BUS | 7 | 5 | 5 | 10 | 5 | 14 | 6 | 10 | 12 | 12 | 12 | 12 |  | 50 Ohms | TOP=L2:L3=L2/L4:L6=L5/L7:BOTTOM=L7 |
| BMC_ADD1 | OTHERS | BUS | 8 | 4.75 | 5 | 10 | 5 | 14 | 6 | 9.5 | 12 | 12 | 12 | 12 |  | 50 Ohms | TOP=L2:L3=L2/L4:L6=L5/L7:BOTTOM=L7 |
| BMC_ADD1_GND | OTHERS | BUS | 1 | 4.75 | 5 | 10 | 5 | 14 | 6 | 9.5 | 12 | 12 | 12 | 12 |  | 50 Ohms | TOP=L2:L3=L2/L4:L6=L5/L7:BOTTOM=L7 |
| BMC_ADD1_GND | OTHERS | BUS | 2 | 5 | 5 | 10 | 5 | 14 | 6 | 10 | 12 | 12 | 12 | 12 |  | 50 Ohms | TOP=L2:L3=L2/L4:L6=L5/L7:BOTTOM=L7 |
| BMC_ADD1_GND | OTHERS | BUS | 3 | 5 | 5 | 10 | 5 | 14 | 6 | 10 | 12 | 12 | 12 | 12 |  | 50 Ohms | TOP=L2:L3=L2/L4:L6=L5/L7:BOTTOM=L7 |
| BMC_ADD1_GND | OTHERS | BUS | 4 | 5 | 5 | 10 | 5 | 14 | 6 | 10 | 12 | 12 | 12 | 12 |  | 50 Ohms | TOP=L2:L3=L2/L4:L6=L5/L7:BOTTOM=L7 |
| BMC_ADD1_GND | OTHERS | BUS | 5 | 5 | 5 | 10 | 5 | 14 | 6 | 10 | 12 | 12 | 12 | 12 |  | 50 Ohms | TOP=L2:L3=L2/L4:L6=L5/L7:BOTTOM=L7 |
| BMC_ADD1_GND | OTHERS | BUS | 6 | 5 | 5 | 10 | 5 | 14 | 6 | 10 | 12 | 12 | 12 | 12 |  | 50 Ohms | TOP=L2:L3=L2/L4:L6=L5/L7:BOTTOM=L7 |
| BMC_ADD1_GND | OTHERS | BUS | 7 | 5 | 5 | 10 | 5 | 14 | 6 | 10 | 12 | 12 | 12 | 12 |  | 50 Ohms | TOP=L2:L3=L2/L4:L6=L5/L7:BOTTOM=L7 |
| BMC_ADD1_GND | OTHERS | BUS | 8 | 4.75 | 5 | 10 | 5 | 14 | 6 | 9.5 | 12 | 12 | 12 | 12 |  | 50 Ohms | TOP=L2:L3=L2/L4:L6=L5/L7:BOTTOM=L7 |
| BMC_ADD1_PWR | OTHERS | BUS | 1 | 4.75 | 5 | 10 | 5 | 14 | 6 | 9.5 | 12 | 12 | 12 | 12 |  | 50 Ohms | TOP=L2:L3=L2/L4:L6=L5/L7:BOTTOM=L7 |
| BMC_ADD1_PWR | OTHERS | BUS | 2 | 5 | 5 | 10 | 5 | 14 | 6 | 10 | 12 | 12 | 12 | 12 |  | 50 Ohms | TOP=L2:L3=L2/L4:L6=L5/L7:BOTTOM=L7 |
| BMC_ADD1_PWR | OTHERS | BUS | 3 | 5 | 5 | 10 | 5 | 14 | 6 | 10 | 12 | 12 | 12 | 12 |  | 50 Ohms | TOP=L2:L3=L2/L4:L6=L5/L7:BOTTOM=L7 |
| BMC_ADD1_PWR | OTHERS | BUS | 4 | 5 | 5 | 10 | 5 | 14 | 6 | 10 | 12 | 12 | 12 | 12 |  | 50 Ohms | TOP=L2:L3=L2/L4:L6=L5/L7:BOTTOM=L7 |
| BMC_ADD1_PWR | OTHERS | BUS | 5 | 5 | 5 | 10 | 5 | 14 | 6 | 10 | 12 | 12 | 12 | 12 |  | 50 Ohms | TOP=L2:L3=L2/L4:L6=L5/L7:BOTTOM=L7 |
| BMC_ADD1_PWR | OTHERS | BUS | 6 | 5 | 5 | 10 | 5 | 14 | 6 | 10 | 12 | 12 | 12 | 12 |  | 50 Ohms | TOP=L2:L3=L2/L4:L6=L5/L7:BOTTOM=L7 |
| BMC_ADD1_PWR | OTHERS | BUS | 7 | 5 | 5 | 10 | 5 | 14 | 6 | 10 | 12 | 12 | 12 | 12 |  | 50 Ohms | TOP=L2:L3=L2/L4:L6=L5/L7:BOTTOM=L7 |
| BMC_ADD1_PWR | OTHERS | BUS | 8 | 4.75 | 5 | 10 | 5 | 14 | 6 | 9.5 | 12 | 12 | 12 | 12 |  | 50 Ohms | TOP=L2:L3=L2/L4:L6=L5/L7:BOTTOM=L7 |
| BMC_ADD1_R | OTHERS | BUS | 1 | 4.75 | 5 | 10 | 5 | 14 | 6 | 9.5 | 12 | 12 | 12 | 12 |  | 50 Ohms | TOP=L2:L3=L2/L4:L6=L5/L7:BOTTOM=L7 |
| BMC_ADD1_R | OTHERS | BUS | 2 | 5 | 5 | 10 | 5 | 14 | 6 | 10 | 12 | 12 | 12 | 12 |  | 50 Ohms | TOP=L2:L3=L2/L4:L6=L5/L7:BOTTOM=L7 |
| BMC_ADD1_R | OTHERS | BUS | 3 | 5 | 5 | 10 | 5 | 14 | 6 | 10 | 12 | 12 | 12 | 12 |  | 50 Ohms | TOP=L2:L3=L2/L4:L6=L5/L7:BOTTOM=L7 |
| BMC_ADD1_R | OTHERS | BUS | 4 | 5 | 5 | 10 | 5 | 14 | 6 | 10 | 12 | 12 | 12 | 12 |  | 50 Ohms | TOP=L2:L3=L2/L4:L6=L5/L7:BOTTOM=L7 |
| BMC_ADD1_R | OTHERS | BUS | 5 | 5 | 5 | 10 | 5 | 14 | 6 | 10 | 12 | 12 | 12 | 12 |  | 50 Ohms | TOP=L2:L3=L2/L4:L6=L5/L7:BOTTOM=L7 |
| BMC_ADD1_R | OTHERS | BUS | 6 | 5 | 5 | 10 | 5 | 14 | 6 | 10 | 12 | 12 | 12 | 12 |  | 50 Ohms | TOP=L2:L3=L2/L4:L6=L5/L7:BOTTOM=L7 |
| BMC_ADD1_R | OTHERS | BUS | 7 | 5 | 5 | 10 | 5 | 14 | 6 | 10 | 12 | 12 | 12 | 12 |  | 50 Ohms | TOP=L2:L3=L2/L4:L6=L5/L7:BOTTOM=L7 |
| BMC_ADD1_R | OTHERS | BUS | 8 | 4.75 | 5 | 10 | 5 | 14 | 6 | 9.5 | 12 | 12 | 12 | 12 |  | 50 Ohms | TOP=L2:L3=L2/L4:L6=L5/L7:BOTTOM=L7 |
| BMC_ADD2 | OTHERS | BUS | 1 | 4.75 | 5 | 10 | 5 | 14 | 6 | 9.5 | 12 | 12 | 12 | 12 |  | 50 Ohms | TOP=L2:L3=L2/L4:L6=L5/L7:BOTTOM=L7 |
| BMC_ADD2 | OTHERS | BUS | 2 | 5 | 5 | 10 | 5 | 14 | 6 | 10 | 12 | 12 | 12 | 12 |  | 50 Ohms | TOP=L2:L3=L2/L4:L6=L5/L7:BOTTOM=L7 |
| BMC_ADD2 | OTHERS | BUS | 3 | 5 | 5 | 10 | 5 | 14 | 6 | 10 | 12 | 12 | 12 | 12 |  | 50 Ohms | TOP=L2:L3=L2/L4:L6=L5/L7:BOTTOM=L7 |
| BMC_ADD2 | OTHERS | BUS | 4 | 5 | 5 | 10 | 5 | 14 | 6 | 10 | 12 | 12 | 12 | 12 |  | 50 Ohms | TOP=L2:L3=L2/L4:L6=L5/L7:BOTTOM=L7 |
| BMC_ADD2 | OTHERS | BUS | 5 | 5 | 5 | 10 | 5 | 14 | 6 | 10 | 12 | 12 | 12 | 12 |  | 50 Ohms | TOP=L2:L3=L2/L4:L6=L5/L7:BOTTOM=L7 |
| BMC_ADD2 | OTHERS | BUS | 6 | 5 | 5 | 10 | 5 | 14 | 6 | 10 | 12 | 12 | 12 | 12 |  | 50 Ohms | TOP=L2:L3=L2/L4:L6=L5/L7:BOTTOM=L7 |
| BMC_ADD2 | OTHERS | BUS | 7 | 5 | 5 | 10 | 5 | 14 | 6 | 10 | 12 | 12 | 12 | 12 |  | 50 Ohms | TOP=L2:L3=L2/L4:L6=L5/L7:BOTTOM=L7 |
| BMC_ADD2 | OTHERS | BUS | 8 | 4.75 | 5 | 10 | 5 | 14 | 6 | 9.5 | 12 | 12 | 12 | 12 |  | 50 Ohms | TOP=L2:L3=L2/L4:L6=L5/L7:BOTTOM=L7 |
| BMC_ADD2_GND | OTHERS | BUS | 1 | 4.75 | 5 | 10 | 5 | 14 | 6 | 9.5 | 12 | 12 | 12 | 12 |  | 50 Ohms | TOP=L2:L3=L2/L4:L6=L5/L7:BOTTOM=L7 |
| BMC_ADD2_GND | OTHERS | BUS | 2 | 5 | 5 | 10 | 5 | 14 | 6 | 10 | 12 | 12 | 12 | 12 |  | 50 Ohms | TOP=L2:L3=L2/L4:L6=L5/L7:BOTTOM=L7 |
| BMC_ADD2_GND | OTHERS | BUS | 3 | 5 | 5 | 10 | 5 | 14 | 6 | 10 | 12 | 12 | 12 | 12 |  | 50 Ohms | TOP=L2:L3=L2/L4:L6=L5/L7:BOTTOM=L7 |
| BMC_ADD2_GND | OTHERS | BUS | 4 | 5 | 5 | 10 | 5 | 14 | 6 | 10 | 12 | 12 | 12 | 12 |  | 50 Ohms | TOP=L2:L3=L2/L4:L6=L5/L7:BOTTOM=L7 |
| BMC_ADD2_GND | OTHERS | BUS | 5 | 5 | 5 | 10 | 5 | 14 | 6 | 10 | 12 | 12 | 12 | 12 |  | 50 Ohms | TOP=L2:L3=L2/L4:L6=L5/L7:BOTTOM=L7 |
| BMC_ADD2_GND | OTHERS | BUS | 6 | 5 | 5 | 10 | 5 | 14 | 6 | 10 | 12 | 12 | 12 | 12 |  | 50 Ohms | TOP=L2:L3=L2/L4:L6=L5/L7:BOTTOM=L7 |
| BMC_ADD2_GND | OTHERS | BUS | 7 | 5 | 5 | 10 | 5 | 14 | 6 | 10 | 12 | 12 | 12 | 12 |  | 50 Ohms | TOP=L2:L3=L2/L4:L6=L5/L7:BOTTOM=L7 |
| BMC_ADD2_GND | OTHERS | BUS | 8 | 4.75 | 5 | 10 | 5 | 14 | 6 | 9.5 | 12 | 12 | 12 | 12 |  | 50 Ohms | TOP=L2:L3=L2/L4:L6=L5/L7:BOTTOM=L7 |
| BMC_ADD2_PWR | OTHERS | BUS | 1 | 4.75 | 5 | 10 | 5 | 14 | 6 | 9.5 | 12 | 12 | 12 | 12 |  | 50 Ohms | TOP=L2:L3=L2/L4:L6=L5/L7:BOTTOM=L7 |
| BMC_ADD2_PWR | OTHERS | BUS | 2 | 5 | 5 | 10 | 5 | 14 | 6 | 10 | 12 | 12 | 12 | 12 |  | 50 Ohms | TOP=L2:L3=L2/L4:L6=L5/L7:BOTTOM=L7 |
| BMC_ADD2_PWR | OTHERS | BUS | 3 | 5 | 5 | 10 | 5 | 14 | 6 | 10 | 12 | 12 | 12 | 12 |  | 50 Ohms | TOP=L2:L3=L2/L4:L6=L5/L7:BOTTOM=L7 |
| BMC_ADD2_PWR | OTHERS | BUS | 4 | 5 | 5 | 10 | 5 | 14 | 6 | 10 | 12 | 12 | 12 | 12 |  | 50 Ohms | TOP=L2:L3=L2/L4:L6=L5/L7:BOTTOM=L7 |
| BMC_ADD2_PWR | OTHERS | BUS | 5 | 5 | 5 | 10 | 5 | 14 | 6 | 10 | 12 | 12 | 12 | 12 |  | 50 Ohms | TOP=L2:L3=L2/L4:L6=L5/L7:BOTTOM=L7 |
| BMC_ADD2_PWR | OTHERS | BUS | 6 | 5 | 5 | 10 | 5 | 14 | 6 | 10 | 12 | 12 | 12 | 12 |  | 50 Ohms | TOP=L2:L3=L2/L4:L6=L5/L7:BOTTOM=L7 |
| BMC_ADD2_PWR | OTHERS | BUS | 7 | 5 | 5 | 10 | 5 | 14 | 6 | 10 | 12 | 12 | 12 | 12 |  | 50 Ohms | TOP=L2:L3=L2/L4:L6=L5/L7:BOTTOM=L7 |
| BMC_ADD2_PWR | OTHERS | BUS | 8 | 4.75 | 5 | 10 | 5 | 14 | 6 | 9.5 | 12 | 12 | 12 | 12 |  | 50 Ohms | TOP=L2:L3=L2/L4:L6=L5/L7:BOTTOM=L7 |
| BMC_ADD2_R | OTHERS | BUS | 1 | 4.75 | 5 | 10 | 5 | 14 | 6 | 9.5 | 12 | 12 | 12 | 12 |  | 50 Ohms | TOP=L2:L3=L2/L4:L6=L5/L7:BOTTOM=L7 |
| BMC_ADD2_R | OTHERS | BUS | 2 | 5 | 5 | 10 | 5 | 14 | 6 | 10 | 12 | 12 | 12 | 12 |  | 50 Ohms | TOP=L2:L3=L2/L4:L6=L5/L7:BOTTOM=L7 |
| BMC_ADD2_R | OTHERS | BUS | 3 | 5 | 5 | 10 | 5 | 14 | 6 | 10 | 12 | 12 | 12 | 12 |  | 50 Ohms | TOP=L2:L3=L2/L4:L6=L5/L7:BOTTOM=L7 |
| BMC_ADD2_R | OTHERS | BUS | 4 | 5 | 5 | 10 | 5 | 14 | 6 | 10 | 12 | 12 | 12 | 12 |  | 50 Ohms | TOP=L2:L3=L2/L4:L6=L5/L7:BOTTOM=L7 |
| BMC_ADD2_R | OTHERS | BUS | 5 | 5 | 5 | 10 | 5 | 14 | 6 | 10 | 12 | 12 | 12 | 12 |  | 50 Ohms | TOP=L2:L3=L2/L4:L6=L5/L7:BOTTOM=L7 |
| BMC_ADD2_R | OTHERS | BUS | 6 | 5 | 5 | 10 | 5 | 14 | 6 | 10 | 12 | 12 | 12 | 12 |  | 50 Ohms | TOP=L2:L3=L2/L4:L6=L5/L7:BOTTOM=L7 |
| BMC_ADD2_R | OTHERS | BUS | 7 | 5 | 5 | 10 | 5 | 14 | 6 | 10 | 12 | 12 | 12 | 12 |  | 50 Ohms | TOP=L2:L3=L2/L4:L6=L5/L7:BOTTOM=L7 |
| BMC_ADD2_R | OTHERS | BUS | 8 | 4.75 | 5 | 10 | 5 | 14 | 6 | 9.5 | 12 | 12 | 12 | 12 |  | 50 Ohms | TOP=L2:L3=L2/L4:L6=L5/L7:BOTTOM=L7 |
| BMC_CONSOLE_LED0_R | OTHERS | BUS | 1 | 4.75 | 5 | 10 | 5 | 14 | 6 | 9.5 | 12 | 12 | 12 | 12 |  | 50 Ohms | TOP=L2:L3=L2/L4:L6=L5/L7:BOTTOM=L7 |
| BMC_CONSOLE_LED0_R | OTHERS | BUS | 2 | 5 | 5 | 10 | 5 | 14 | 6 | 10 | 12 | 12 | 12 | 12 |  | 50 Ohms | TOP=L2:L3=L2/L4:L6=L5/L7:BOTTOM=L7 |
| BMC_CONSOLE_LED0_R | OTHERS | BUS | 3 | 5 | 5 | 10 | 5 | 14 | 6 | 10 | 12 | 12 | 12 | 12 |  | 50 Ohms | TOP=L2:L3=L2/L4:L6=L5/L7:BOTTOM=L7 |
| BMC_CONSOLE_LED0_R | OTHERS | BUS | 4 | 5 | 5 | 10 | 5 | 14 | 6 | 10 | 12 | 12 | 12 | 12 |  | 50 Ohms | TOP=L2:L3=L2/L4:L6=L5/L7:BOTTOM=L7 |
| BMC_CONSOLE_LED0_R | OTHERS | BUS | 5 | 5 | 5 | 10 | 5 | 14 | 6 | 10 | 12 | 12 | 12 | 12 |  | 50 Ohms | TOP=L2:L3=L2/L4:L6=L5/L7:BOTTOM=L7 |
| BMC_CONSOLE_LED0_R | OTHERS | BUS | 6 | 5 | 5 | 10 | 5 | 14 | 6 | 10 | 12 | 12 | 12 | 12 |  | 50 Ohms | TOP=L2:L3=L2/L4:L6=L5/L7:BOTTOM=L7 |
| BMC_CONSOLE_LED0_R | OTHERS | BUS | 7 | 5 | 5 | 10 | 5 | 14 | 6 | 10 | 12 | 12 | 12 | 12 |  | 50 Ohms | TOP=L2:L3=L2/L4:L6=L5/L7:BOTTOM=L7 |
| BMC_CONSOLE_LED0_R | OTHERS | BUS | 8 | 4.75 | 5 | 10 | 5 | 14 | 6 | 9.5 | 12 | 12 | 12 | 12 |  | 50 Ohms | TOP=L2:L3=L2/L4:L6=L5/L7:BOTTOM=L7 |
| BMC_CPU_DIS | OTHERS | BUS | 1 | 4.75 | 5 | 10 | 5 | 14 | 6 | 9.5 | 12 | 12 | 12 | 12 |  | 50 Ohms | TOP=L2:L3=L2/L4:L6=L5/L7:BOTTOM=L7 |
| BMC_CPU_DIS | OTHERS | BUS | 2 | 5 | 5 | 10 | 5 | 14 | 6 | 10 | 12 | 12 | 12 | 12 |  | 50 Ohms | TOP=L2:L3=L2/L4:L6=L5/L7:BOTTOM=L7 |
| BMC_CPU_DIS | OTHERS | BUS | 3 | 5 | 5 | 10 | 5 | 14 | 6 | 10 | 12 | 12 | 12 | 12 |  | 50 Ohms | TOP=L2:L3=L2/L4:L6=L5/L7:BOTTOM=L7 |
| BMC_CPU_DIS | OTHERS | BUS | 4 | 5 | 5 | 10 | 5 | 14 | 6 | 10 | 12 | 12 | 12 | 12 |  | 50 Ohms | TOP=L2:L3=L2/L4:L6=L5/L7:BOTTOM=L7 |
| BMC_CPU_DIS | OTHERS | BUS | 5 | 5 | 5 | 10 | 5 | 14 | 6 | 10 | 12 | 12 | 12 | 12 |  | 50 Ohms | TOP=L2:L3=L2/L4:L6=L5/L7:BOTTOM=L7 |
| BMC_CPU_DIS | OTHERS | BUS | 6 | 5 | 5 | 10 | 5 | 14 | 6 | 10 | 12 | 12 | 12 | 12 |  | 50 Ohms | TOP=L2:L3=L2/L4:L6=L5/L7:BOTTOM=L7 |
| BMC_CPU_DIS | OTHERS | BUS | 7 | 5 | 5 | 10 | 5 | 14 | 6 | 10 | 12 | 12 | 12 | 12 |  | 50 Ohms | TOP=L2:L3=L2/L4:L6=L5/L7:BOTTOM=L7 |
| BMC_CPU_DIS | OTHERS | BUS | 8 | 4.75 | 5 | 10 | 5 | 14 | 6 | 9.5 | 12 | 12 | 12 | 12 |  | 50 Ohms | TOP=L2:L3=L2/L4:L6=L5/L7:BOTTOM=L7 |
| BMC_CPU_EN | OTHERS | BUS | 1 | 4.75 | 5 | 10 | 5 | 14 | 6 | 9.5 | 12 | 12 | 12 | 12 |  | 50 Ohms | TOP=L2:L3=L2/L4:L6=L5/L7:BOTTOM=L7 |
| BMC_CPU_EN | OTHERS | BUS | 2 | 5 | 5 | 10 | 5 | 14 | 6 | 10 | 12 | 12 | 12 | 12 |  | 50 Ohms | TOP=L2:L3=L2/L4:L6=L5/L7:BOTTOM=L7 |
| BMC_CPU_EN | OTHERS | BUS | 3 | 5 | 5 | 10 | 5 | 14 | 6 | 10 | 12 | 12 | 12 | 12 |  | 50 Ohms | TOP=L2:L3=L2/L4:L6=L5/L7:BOTTOM=L7 |
| BMC_CPU_EN | OTHERS | BUS | 4 | 5 | 5 | 10 | 5 | 14 | 6 | 10 | 12 | 12 | 12 | 12 |  | 50 Ohms | TOP=L2:L3=L2/L4:L6=L5/L7:BOTTOM=L7 |
| BMC_CPU_EN | OTHERS | BUS | 5 | 5 | 5 | 10 | 5 | 14 | 6 | 10 | 12 | 12 | 12 | 12 |  | 50 Ohms | TOP=L2:L3=L2/L4:L6=L5/L7:BOTTOM=L7 |
| BMC_CPU_EN | OTHERS | BUS | 6 | 5 | 5 | 10 | 5 | 14 | 6 | 10 | 12 | 12 | 12 | 12 |  | 50 Ohms | TOP=L2:L3=L2/L4:L6=L5/L7:BOTTOM=L7 |
| BMC_CPU_EN | OTHERS | BUS | 7 | 5 | 5 | 10 | 5 | 14 | 6 | 10 | 12 | 12 | 12 | 12 |  | 50 Ohms | TOP=L2:L3=L2/L4:L6=L5/L7:BOTTOM=L7 |
| BMC_CPU_EN | OTHERS | BUS | 8 | 4.75 | 5 | 10 | 5 | 14 | 6 | 9.5 | 12 | 12 | 12 | 12 |  | 50 Ohms | TOP=L2:L3=L2/L4:L6=L5/L7:BOTTOM=L7 |
| BMC_DDR3_RST_N | OTHERS | BUS | 1 | 4.75 | 5 | 10 | 5 | 14 | 6 | 9.5 | 12 | 12 | 12 | 12 |  | 50 Ohms | TOP=L2:L3=L2/L4:L6=L5/L7:BOTTOM=L7 |
| BMC_DDR3_RST_N | OTHERS | BUS | 2 | 5 | 5 | 10 | 5 | 14 | 6 | 10 | 12 | 12 | 12 | 12 |  | 50 Ohms | TOP=L2:L3=L2/L4:L6=L5/L7:BOTTOM=L7 |
| BMC_DDR3_RST_N | OTHERS | BUS | 3 | 5 | 5 | 10 | 5 | 14 | 6 | 10 | 12 | 12 | 12 | 12 |  | 50 Ohms | TOP=L2:L3=L2/L4:L6=L5/L7:BOTTOM=L7 |
| BMC_DDR3_RST_N | OTHERS | BUS | 4 | 5 | 5 | 10 | 5 | 14 | 6 | 10 | 12 | 12 | 12 | 12 |  | 50 Ohms | TOP=L2:L3=L2/L4:L6=L5/L7:BOTTOM=L7 |
| BMC_DDR3_RST_N | OTHERS | BUS | 5 | 5 | 5 | 10 | 5 | 14 | 6 | 10 | 12 | 12 | 12 | 12 |  | 50 Ohms | TOP=L2:L3=L2/L4:L6=L5/L7:BOTTOM=L7 |
| BMC_DDR3_RST_N | OTHERS | BUS | 6 | 5 | 5 | 10 | 5 | 14 | 6 | 10 | 12 | 12 | 12 | 12 |  | 50 Ohms | TOP=L2:L3=L2/L4:L6=L5/L7:BOTTOM=L7 |
| BMC_DDR3_RST_N | OTHERS | BUS | 7 | 5 | 5 | 10 | 5 | 14 | 6 | 10 | 12 | 12 | 12 | 12 |  | 50 Ohms | TOP=L2:L3=L2/L4:L6=L5/L7:BOTTOM=L7 |
| BMC_DDR3_RST_N | OTHERS | BUS | 8 | 4.75 | 5 | 10 | 5 | 14 | 6 | 9.5 | 12 | 12 | 12 | 12 |  | 50 Ohms | TOP=L2:L3=L2/L4:L6=L5/L7:BOTTOM=L7 |
| BMC_ENCLOSURE_LED | OTHERS | BUS | 1 | 4.75 | 5 | 10 | 5 | 14 | 6 | 9.5 | 12 | 12 | 12 | 12 |  | 50 Ohms | TOP=L2:L3=L2/L4:L6=L5/L7:BOTTOM=L7 |
| BMC_ENCLOSURE_LED | OTHERS | BUS | 2 | 5 | 5 | 10 | 5 | 14 | 6 | 10 | 12 | 12 | 12 | 12 |  | 50 Ohms | TOP=L2:L3=L2/L4:L6=L5/L7:BOTTOM=L7 |
| BMC_ENCLOSURE_LED | OTHERS | BUS | 3 | 5 | 5 | 10 | 5 | 14 | 6 | 10 | 12 | 12 | 12 | 12 |  | 50 Ohms | TOP=L2:L3=L2/L4:L6=L5/L7:BOTTOM=L7 |
| BMC_ENCLOSURE_LED | OTHERS | BUS | 4 | 5 | 5 | 10 | 5 | 14 | 6 | 10 | 12 | 12 | 12 | 12 |  | 50 Ohms | TOP=L2:L3=L2/L4:L6=L5/L7:BOTTOM=L7 |
| BMC_ENCLOSURE_LED | OTHERS | BUS | 5 | 5 | 5 | 10 | 5 | 14 | 6 | 10 | 12 | 12 | 12 | 12 |  | 50 Ohms | TOP=L2:L3=L2/L4:L6=L5/L7:BOTTOM=L7 |
| BMC_ENCLOSURE_LED | OTHERS | BUS | 6 | 5 | 5 | 10 | 5 | 14 | 6 | 10 | 12 | 12 | 12 | 12 |  | 50 Ohms | TOP=L2:L3=L2/L4:L6=L5/L7:BOTTOM=L7 |
| BMC_ENCLOSURE_LED | OTHERS | BUS | 7 | 5 | 5 | 10 | 5 | 14 | 6 | 10 | 12 | 12 | 12 | 12 |  | 50 Ohms | TOP=L2:L3=L2/L4:L6=L5/L7:BOTTOM=L7 |
| BMC_ENCLOSURE_LED | OTHERS | BUS | 8 | 4.75 | 5 | 10 | 5 | 14 | 6 | 9.5 | 12 | 12 | 12 | 12 |  | 50 Ohms | TOP=L2:L3=L2/L4:L6=L5/L7:BOTTOM=L7 |
| BMC_ENCLOSURE_LED_R | OTHERS | BUS | 1 | 4.75 | 5 | 10 | 5 | 14 | 6 | 9.5 | 12 | 12 | 12 | 12 |  | 50 Ohms | TOP=L2:L3=L2/L4:L6=L5/L7:BOTTOM=L7 |
| BMC_ENCLOSURE_LED_R | OTHERS | BUS | 2 | 5 | 5 | 10 | 5 | 14 | 6 | 10 | 12 | 12 | 12 | 12 |  | 50 Ohms | TOP=L2:L3=L2/L4:L6=L5/L7:BOTTOM=L7 |
| BMC_ENCLOSURE_LED_R | OTHERS | BUS | 3 | 5 | 5 | 10 | 5 | 14 | 6 | 10 | 12 | 12 | 12 | 12 |  | 50 Ohms | TOP=L2:L3=L2/L4:L6=L5/L7:BOTTOM=L7 |
| BMC_ENCLOSURE_LED_R | OTHERS | BUS | 4 | 5 | 5 | 10 | 5 | 14 | 6 | 10 | 12 | 12 | 12 | 12 |  | 50 Ohms | TOP=L2:L3=L2/L4:L6=L5/L7:BOTTOM=L7 |
| BMC_ENCLOSURE_LED_R | OTHERS | BUS | 5 | 5 | 5 | 10 | 5 | 14 | 6 | 10 | 12 | 12 | 12 | 12 |  | 50 Ohms | TOP=L2:L3=L2/L4:L6=L5/L7:BOTTOM=L7 |
| BMC_ENCLOSURE_LED_R | OTHERS | BUS | 6 | 5 | 5 | 10 | 5 | 14 | 6 | 10 | 12 | 12 | 12 | 12 |  | 50 Ohms | TOP=L2:L3=L2/L4:L6=L5/L7:BOTTOM=L7 |
| BMC_ENCLOSURE_LED_R | OTHERS | BUS | 7 | 5 | 5 | 10 | 5 | 14 | 6 | 10 | 12 | 12 | 12 | 12 |  | 50 Ohms | TOP=L2:L3=L2/L4:L6=L5/L7:BOTTOM=L7 |
| BMC_ENCLOSURE_LED_R | OTHERS | BUS | 8 | 4.75 | 5 | 10 | 5 | 14 | 6 | 9.5 | 12 | 12 | 12 | 12 |  | 50 Ohms | TOP=L2:L3=L2/L4:L6=L5/L7:BOTTOM=L7 |
| BMC_FW_DET_BOARD_VER_0 | OTHERS | BUS | 1 | 4.75 | 5 | 10 | 5 | 14 | 6 | 9.5 | 12 | 12 | 12 | 12 |  | 50 Ohms | TOP=L2:L3=L2/L4:L6=L5/L7:BOTTOM=L7 |
| BMC_FW_DET_BOARD_VER_0 | OTHERS | BUS | 2 | 5 | 5 | 10 | 5 | 14 | 6 | 10 | 12 | 12 | 12 | 12 |  | 50 Ohms | TOP=L2:L3=L2/L4:L6=L5/L7:BOTTOM=L7 |
| BMC_FW_DET_BOARD_VER_0 | OTHERS | BUS | 3 | 5 | 5 | 10 | 5 | 14 | 6 | 10 | 12 | 12 | 12 | 12 |  | 50 Ohms | TOP=L2:L3=L2/L4:L6=L5/L7:BOTTOM=L7 |
| BMC_FW_DET_BOARD_VER_0 | OTHERS | BUS | 4 | 5 | 5 | 10 | 5 | 14 | 6 | 10 | 12 | 12 | 12 | 12 |  | 50 Ohms | TOP=L2:L3=L2/L4:L6=L5/L7:BOTTOM=L7 |
| BMC_FW_DET_BOARD_VER_0 | OTHERS | BUS | 5 | 5 | 5 | 10 | 5 | 14 | 6 | 10 | 12 | 12 | 12 | 12 |  | 50 Ohms | TOP=L2:L3=L2/L4:L6=L5/L7:BOTTOM=L7 |
| BMC_FW_DET_BOARD_VER_0 | OTHERS | BUS | 6 | 5 | 5 | 10 | 5 | 14 | 6 | 10 | 12 | 12 | 12 | 12 |  | 50 Ohms | TOP=L2:L3=L2/L4:L6=L5/L7:BOTTOM=L7 |
| BMC_FW_DET_BOARD_VER_0 | OTHERS | BUS | 7 | 5 | 5 | 10 | 5 | 14 | 6 | 10 | 12 | 12 | 12 | 12 |  | 50 Ohms | TOP=L2:L3=L2/L4:L6=L5/L7:BOTTOM=L7 |
| BMC_FW_DET_BOARD_VER_0 | OTHERS | BUS | 8 | 4.75 | 5 | 10 | 5 | 14 | 6 | 9.5 | 12 | 12 | 12 | 12 |  | 50 Ohms | TOP=L2:L3=L2/L4:L6=L5/L7:BOTTOM=L7 |
| BMC_FW_DET_BOARD_VER_1 | OTHERS | BUS | 1 | 4.75 | 5 | 10 | 5 | 14 | 6 | 9.5 | 12 | 12 | 12 | 12 |  | 50 Ohms | TOP=L2:L3=L2/L4:L6=L5/L7:BOTTOM=L7 |
| BMC_FW_DET_BOARD_VER_1 | OTHERS | BUS | 2 | 5 | 5 | 10 | 5 | 14 | 6 | 10 | 12 | 12 | 12 | 12 |  | 50 Ohms | TOP=L2:L3=L2/L4:L6=L5/L7:BOTTOM=L7 |
| BMC_FW_DET_BOARD_VER_1 | OTHERS | BUS | 3 | 5 | 5 | 10 | 5 | 14 | 6 | 10 | 12 | 12 | 12 | 12 |  | 50 Ohms | TOP=L2:L3=L2/L4:L6=L5/L7:BOTTOM=L7 |
| BMC_FW_DET_BOARD_VER_1 | OTHERS | BUS | 4 | 5 | 5 | 10 | 5 | 14 | 6 | 10 | 12 | 12 | 12 | 12 |  | 50 Ohms | TOP=L2:L3=L2/L4:L6=L5/L7:BOTTOM=L7 |
| BMC_FW_DET_BOARD_VER_1 | OTHERS | BUS | 5 | 5 | 5 | 10 | 5 | 14 | 6 | 10 | 12 | 12 | 12 | 12 |  | 50 Ohms | TOP=L2:L3=L2/L4:L6=L5/L7:BOTTOM=L7 |
| BMC_FW_DET_BOARD_VER_1 | OTHERS | BUS | 6 | 5 | 5 | 10 | 5 | 14 | 6 | 10 | 12 | 12 | 12 | 12 |  | 50 Ohms | TOP=L2:L3=L2/L4:L6=L5/L7:BOTTOM=L7 |
| BMC_FW_DET_BOARD_VER_1 | OTHERS | BUS | 7 | 5 | 5 | 10 | 5 | 14 | 6 | 10 | 12 | 12 | 12 | 12 |  | 50 Ohms | TOP=L2:L3=L2/L4:L6=L5/L7:BOTTOM=L7 |
| BMC_FW_DET_BOARD_VER_1 | OTHERS | BUS | 8 | 4.75 | 5 | 10 | 5 | 14 | 6 | 9.5 | 12 | 12 | 12 | 12 |  | 50 Ohms | TOP=L2:L3=L2/L4:L6=L5/L7:BOTTOM=L7 |
| BMC_FW_DET_BOARD_VER_2 | OTHERS | BUS | 1 | 4.75 | 5 | 10 | 5 | 14 | 6 | 9.5 | 12 | 12 | 12 | 12 |  | 50 Ohms | TOP=L2:L3=L2/L4:L6=L5/L7:BOTTOM=L7 |
| BMC_FW_DET_BOARD_VER_2 | OTHERS | BUS | 2 | 5 | 5 | 10 | 5 | 14 | 6 | 10 | 12 | 12 | 12 | 12 |  | 50 Ohms | TOP=L2:L3=L2/L4:L6=L5/L7:BOTTOM=L7 |
| BMC_FW_DET_BOARD_VER_2 | OTHERS | BUS | 3 | 5 | 5 | 10 | 5 | 14 | 6 | 10 | 12 | 12 | 12 | 12 |  | 50 Ohms | TOP=L2:L3=L2/L4:L6=L5/L7:BOTTOM=L7 |
| BMC_FW_DET_BOARD_VER_2 | OTHERS | BUS | 4 | 5 | 5 | 10 | 5 | 14 | 6 | 10 | 12 | 12 | 12 | 12 |  | 50 Ohms | TOP=L2:L3=L2/L4:L6=L5/L7:BOTTOM=L7 |
| BMC_FW_DET_BOARD_VER_2 | OTHERS | BUS | 5 | 5 | 5 | 10 | 5 | 14 | 6 | 10 | 12 | 12 | 12 | 12 |  | 50 Ohms | TOP=L2:L3=L2/L4:L6=L5/L7:BOTTOM=L7 |
| BMC_FW_DET_BOARD_VER_2 | OTHERS | BUS | 6 | 5 | 5 | 10 | 5 | 14 | 6 | 10 | 12 | 12 | 12 | 12 |  | 50 Ohms | TOP=L2:L3=L2/L4:L6=L5/L7:BOTTOM=L7 |
| BMC_FW_DET_BOARD_VER_2 | OTHERS | BUS | 7 | 5 | 5 | 10 | 5 | 14 | 6 | 10 | 12 | 12 | 12 | 12 |  | 50 Ohms | TOP=L2:L3=L2/L4:L6=L5/L7:BOTTOM=L7 |
| BMC_FW_DET_BOARD_VER_2 | OTHERS | BUS | 8 | 4.75 | 5 | 10 | 5 | 14 | 6 | 9.5 | 12 | 12 | 12 | 12 |  | 50 Ohms | TOP=L2:L3=L2/L4:L6=L5/L7:BOTTOM=L7 |
| BMC_I210_PERST_N | OTHERS | BUS | 1 | 4.75 | 5 | 10 | 5 | 14 | 6 | 9.5 | 12 | 12 | 12 | 12 |  | 50 Ohms | TOP=L2:L3=L2/L4:L6=L5/L7:BOTTOM=L7 |
| BMC_I210_PERST_N | OTHERS | BUS | 2 | 5 | 5 | 10 | 5 | 14 | 6 | 10 | 12 | 12 | 12 | 12 |  | 50 Ohms | TOP=L2:L3=L2/L4:L6=L5/L7:BOTTOM=L7 |
| BMC_I210_PERST_N | OTHERS | BUS | 3 | 5 | 5 | 10 | 5 | 14 | 6 | 10 | 12 | 12 | 12 | 12 |  | 50 Ohms | TOP=L2:L3=L2/L4:L6=L5/L7:BOTTOM=L7 |
| BMC_I210_PERST_N | OTHERS | BUS | 4 | 5 | 5 | 10 | 5 | 14 | 6 | 10 | 12 | 12 | 12 | 12 |  | 50 Ohms | TOP=L2:L3=L2/L4:L6=L5/L7:BOTTOM=L7 |
| BMC_I210_PERST_N | OTHERS | BUS | 5 | 5 | 5 | 10 | 5 | 14 | 6 | 10 | 12 | 12 | 12 | 12 |  | 50 Ohms | TOP=L2:L3=L2/L4:L6=L5/L7:BOTTOM=L7 |
| BMC_I210_PERST_N | OTHERS | BUS | 6 | 5 | 5 | 10 | 5 | 14 | 6 | 10 | 12 | 12 | 12 | 12 |  | 50 Ohms | TOP=L2:L3=L2/L4:L6=L5/L7:BOTTOM=L7 |
| BMC_I210_PERST_N | OTHERS | BUS | 7 | 5 | 5 | 10 | 5 | 14 | 6 | 10 | 12 | 12 | 12 | 12 |  | 50 Ohms | TOP=L2:L3=L2/L4:L6=L5/L7:BOTTOM=L7 |
| BMC_I210_PERST_N | OTHERS | BUS | 8 | 4.75 | 5 | 10 | 5 | 14 | 6 | 9.5 | 12 | 12 | 12 | 12 |  | 50 Ohms | TOP=L2:L3=L2/L4:L6=L5/L7:BOTTOM=L7 |
| BMC_I2C5_BUF_READY | OTHERS | BUS | 1 | 4.75 | 5 | 10 | 5 | 14 | 6 | 9.5 | 12 | 12 | 12 | 12 |  | 50 Ohms | TOP=L2:L3=L2/L4:L6=L5/L7:BOTTOM=L7 |
| BMC_I2C5_BUF_READY | OTHERS | BUS | 2 | 5 | 5 | 10 | 5 | 14 | 6 | 10 | 12 | 12 | 12 | 12 |  | 50 Ohms | TOP=L2:L3=L2/L4:L6=L5/L7:BOTTOM=L7 |
| BMC_I2C5_BUF_READY | OTHERS | BUS | 3 | 5 | 5 | 10 | 5 | 14 | 6 | 10 | 12 | 12 | 12 | 12 |  | 50 Ohms | TOP=L2:L3=L2/L4:L6=L5/L7:BOTTOM=L7 |
| BMC_I2C5_BUF_READY | OTHERS | BUS | 4 | 5 | 5 | 10 | 5 | 14 | 6 | 10 | 12 | 12 | 12 | 12 |  | 50 Ohms | TOP=L2:L3=L2/L4:L6=L5/L7:BOTTOM=L7 |
| BMC_I2C5_BUF_READY | OTHERS | BUS | 5 | 5 | 5 | 10 | 5 | 14 | 6 | 10 | 12 | 12 | 12 | 12 |  | 50 Ohms | TOP=L2:L3=L2/L4:L6=L5/L7:BOTTOM=L7 |
| BMC_I2C5_BUF_READY | OTHERS | BUS | 6 | 5 | 5 | 10 | 5 | 14 | 6 | 10 | 12 | 12 | 12 | 12 |  | 50 Ohms | TOP=L2:L3=L2/L4:L6=L5/L7:BOTTOM=L7 |
| BMC_I2C5_BUF_READY | OTHERS | BUS | 7 | 5 | 5 | 10 | 5 | 14 | 6 | 10 | 12 | 12 | 12 | 12 |  | 50 Ohms | TOP=L2:L3=L2/L4:L6=L5/L7:BOTTOM=L7 |
| BMC_I2C5_BUF_READY | OTHERS | BUS | 8 | 4.75 | 5 | 10 | 5 | 14 | 6 | 9.5 | 12 | 12 | 12 | 12 |  | 50 Ohms | TOP=L2:L3=L2/L4:L6=L5/L7:BOTTOM=L7 |
| BMC_ID_LED | OTHERS | BUS | 1 | 4.75 | 5 | 10 | 5 | 14 | 6 | 9.5 | 12 | 12 | 12 | 12 |  | 50 Ohms | TOP=L2:L3=L2/L4:L6=L5/L7:BOTTOM=L7 |
| BMC_ID_LED | OTHERS | BUS | 2 | 5 | 5 | 10 | 5 | 14 | 6 | 10 | 12 | 12 | 12 | 12 |  | 50 Ohms | TOP=L2:L3=L2/L4:L6=L5/L7:BOTTOM=L7 |
| BMC_ID_LED | OTHERS | BUS | 3 | 5 | 5 | 10 | 5 | 14 | 6 | 10 | 12 | 12 | 12 | 12 |  | 50 Ohms | TOP=L2:L3=L2/L4:L6=L5/L7:BOTTOM=L7 |
| BMC_ID_LED | OTHERS | BUS | 4 | 5 | 5 | 10 | 5 | 14 | 6 | 10 | 12 | 12 | 12 | 12 |  | 50 Ohms | TOP=L2:L3=L2/L4:L6=L5/L7:BOTTOM=L7 |
| BMC_ID_LED | OTHERS | BUS | 5 | 5 | 5 | 10 | 5 | 14 | 6 | 10 | 12 | 12 | 12 | 12 |  | 50 Ohms | TOP=L2:L3=L2/L4:L6=L5/L7:BOTTOM=L7 |
| BMC_ID_LED | OTHERS | BUS | 6 | 5 | 5 | 10 | 5 | 14 | 6 | 10 | 12 | 12 | 12 | 12 |  | 50 Ohms | TOP=L2:L3=L2/L4:L6=L5/L7:BOTTOM=L7 |
| BMC_ID_LED | OTHERS | BUS | 7 | 5 | 5 | 10 | 5 | 14 | 6 | 10 | 12 | 12 | 12 | 12 |  | 50 Ohms | TOP=L2:L3=L2/L4:L6=L5/L7:BOTTOM=L7 |
| BMC_ID_LED | OTHERS | BUS | 8 | 4.75 | 5 | 10 | 5 | 14 | 6 | 9.5 | 12 | 12 | 12 | 12 |  | 50 Ohms | TOP=L2:L3=L2/L4:L6=L5/L7:BOTTOM=L7 |
| BMC_ID_LED_R | OTHERS | BUS | 1 | 4.75 | 5 | 10 | 5 | 14 | 6 | 9.5 | 12 | 12 | 12 | 12 |  | 50 Ohms | TOP=L2:L3=L2/L4:L6=L5/L7:BOTTOM=L7 |
| BMC_ID_LED_R | OTHERS | BUS | 2 | 5 | 5 | 10 | 5 | 14 | 6 | 10 | 12 | 12 | 12 | 12 |  | 50 Ohms | TOP=L2:L3=L2/L4:L6=L5/L7:BOTTOM=L7 |
| BMC_ID_LED_R | OTHERS | BUS | 3 | 5 | 5 | 10 | 5 | 14 | 6 | 10 | 12 | 12 | 12 | 12 |  | 50 Ohms | TOP=L2:L3=L2/L4:L6=L5/L7:BOTTOM=L7 |
| BMC_ID_LED_R | OTHERS | BUS | 4 | 5 | 5 | 10 | 5 | 14 | 6 | 10 | 12 | 12 | 12 | 12 |  | 50 Ohms | TOP=L2:L3=L2/L4:L6=L5/L7:BOTTOM=L7 |
| BMC_ID_LED_R | OTHERS | BUS | 5 | 5 | 5 | 10 | 5 | 14 | 6 | 10 | 12 | 12 | 12 | 12 |  | 50 Ohms | TOP=L2:L3=L2/L4:L6=L5/L7:BOTTOM=L7 |
| BMC_ID_LED_R | OTHERS | BUS | 6 | 5 | 5 | 10 | 5 | 14 | 6 | 10 | 12 | 12 | 12 | 12 |  | 50 Ohms | TOP=L2:L3=L2/L4:L6=L5/L7:BOTTOM=L7 |
| BMC_ID_LED_R | OTHERS | BUS | 7 | 5 | 5 | 10 | 5 | 14 | 6 | 10 | 12 | 12 | 12 | 12 |  | 50 Ohms | TOP=L2:L3=L2/L4:L6=L5/L7:BOTTOM=L7 |
| BMC_ID_LED_R | OTHERS | BUS | 8 | 4.75 | 5 | 10 | 5 | 14 | 6 | 9.5 | 12 | 12 | 12 | 12 |  | 50 Ohms | TOP=L2:L3=L2/L4:L6=L5/L7:BOTTOM=L7 |
| BMC_INT_N | OTHERS | BUS | 1 | 4.75 | 5 | 10 | 5 | 14 | 6 | 9.5 | 12 | 12 | 12 | 12 |  | 50 Ohms | TOP=L2:L3=L2/L4:L6=L5/L7:BOTTOM=L7 |
| BMC_INT_N | OTHERS | BUS | 2 | 5 | 5 | 10 | 5 | 14 | 6 | 10 | 12 | 12 | 12 | 12 |  | 50 Ohms | TOP=L2:L3=L2/L4:L6=L5/L7:BOTTOM=L7 |
| BMC_INT_N | OTHERS | BUS | 3 | 5 | 5 | 10 | 5 | 14 | 6 | 10 | 12 | 12 | 12 | 12 |  | 50 Ohms | TOP=L2:L3=L2/L4:L6=L5/L7:BOTTOM=L7 |
| BMC_INT_N | OTHERS | BUS | 4 | 5 | 5 | 10 | 5 | 14 | 6 | 10 | 12 | 12 | 12 | 12 |  | 50 Ohms | TOP=L2:L3=L2/L4:L6=L5/L7:BOTTOM=L7 |
| BMC_INT_N | OTHERS | BUS | 5 | 5 | 5 | 10 | 5 | 14 | 6 | 10 | 12 | 12 | 12 | 12 |  | 50 Ohms | TOP=L2:L3=L2/L4:L6=L5/L7:BOTTOM=L7 |
| BMC_INT_N | OTHERS | BUS | 6 | 5 | 5 | 10 | 5 | 14 | 6 | 10 | 12 | 12 | 12 | 12 |  | 50 Ohms | TOP=L2:L3=L2/L4:L6=L5/L7:BOTTOM=L7 |
| BMC_INT_N | OTHERS | BUS | 7 | 5 | 5 | 10 | 5 | 14 | 6 | 10 | 12 | 12 | 12 | 12 |  | 50 Ohms | TOP=L2:L3=L2/L4:L6=L5/L7:BOTTOM=L7 |
| BMC_INT_N | OTHERS | BUS | 8 | 4.75 | 5 | 10 | 5 | 14 | 6 | 9.5 | 12 | 12 | 12 | 12 |  | 50 Ohms | TOP=L2:L3=L2/L4:L6=L5/L7:BOTTOM=L7 |
| BMC_JTAG_L_EN | OTHERS | BUS | 1 | 4.75 | 5 | 10 | 5 | 14 | 6 | 9.5 | 12 | 12 | 12 | 12 |  | 50 Ohms | TOP=L2:L3=L2/L4:L6=L5/L7:BOTTOM=L7 |
| BMC_JTAG_L_EN | OTHERS | BUS | 2 | 5 | 5 | 10 | 5 | 14 | 6 | 10 | 12 | 12 | 12 | 12 |  | 50 Ohms | TOP=L2:L3=L2/L4:L6=L5/L7:BOTTOM=L7 |
| BMC_JTAG_L_EN | OTHERS | BUS | 3 | 5 | 5 | 10 | 5 | 14 | 6 | 10 | 12 | 12 | 12 | 12 |  | 50 Ohms | TOP=L2:L3=L2/L4:L6=L5/L7:BOTTOM=L7 |
| BMC_JTAG_L_EN | OTHERS | BUS | 4 | 5 | 5 | 10 | 5 | 14 | 6 | 10 | 12 | 12 | 12 | 12 |  | 50 Ohms | TOP=L2:L3=L2/L4:L6=L5/L7:BOTTOM=L7 |
| BMC_JTAG_L_EN | OTHERS | BUS | 5 | 5 | 5 | 10 | 5 | 14 | 6 | 10 | 12 | 12 | 12 | 12 |  | 50 Ohms | TOP=L2:L3=L2/L4:L6=L5/L7:BOTTOM=L7 |
| BMC_JTAG_L_EN | OTHERS | BUS | 6 | 5 | 5 | 10 | 5 | 14 | 6 | 10 | 12 | 12 | 12 | 12 |  | 50 Ohms | TOP=L2:L3=L2/L4:L6=L5/L7:BOTTOM=L7 |
| BMC_JTAG_L_EN | OTHERS | BUS | 7 | 5 | 5 | 10 | 5 | 14 | 6 | 10 | 12 | 12 | 12 | 12 |  | 50 Ohms | TOP=L2:L3=L2/L4:L6=L5/L7:BOTTOM=L7 |
| BMC_JTAG_L_EN | OTHERS | BUS | 8 | 4.75 | 5 | 10 | 5 | 14 | 6 | 9.5 | 12 | 12 | 12 | 12 |  | 50 Ohms | TOP=L2:L3=L2/L4:L6=L5/L7:BOTTOM=L7 |
| BMC_JTAG_L_EN_R | OTHERS | BUS | 1 | 4.75 | 5 | 10 | 5 | 14 | 6 | 9.5 | 12 | 12 | 12 | 12 |  | 50 Ohms | TOP=L2:L3=L2/L4:L6=L5/L7:BOTTOM=L7 |
| BMC_JTAG_L_EN_R | OTHERS | BUS | 2 | 5 | 5 | 10 | 5 | 14 | 6 | 10 | 12 | 12 | 12 | 12 |  | 50 Ohms | TOP=L2:L3=L2/L4:L6=L5/L7:BOTTOM=L7 |
| BMC_JTAG_L_EN_R | OTHERS | BUS | 3 | 5 | 5 | 10 | 5 | 14 | 6 | 10 | 12 | 12 | 12 | 12 |  | 50 Ohms | TOP=L2:L3=L2/L4:L6=L5/L7:BOTTOM=L7 |
| BMC_JTAG_L_EN_R | OTHERS | BUS | 4 | 5 | 5 | 10 | 5 | 14 | 6 | 10 | 12 | 12 | 12 | 12 |  | 50 Ohms | TOP=L2:L3=L2/L4:L6=L5/L7:BOTTOM=L7 |
| BMC_JTAG_L_EN_R | OTHERS | BUS | 5 | 5 | 5 | 10 | 5 | 14 | 6 | 10 | 12 | 12 | 12 | 12 |  | 50 Ohms | TOP=L2:L3=L2/L4:L6=L5/L7:BOTTOM=L7 |
| BMC_JTAG_L_EN_R | OTHERS | BUS | 6 | 5 | 5 | 10 | 5 | 14 | 6 | 10 | 12 | 12 | 12 | 12 |  | 50 Ohms | TOP=L2:L3=L2/L4:L6=L5/L7:BOTTOM=L7 |
| BMC_JTAG_L_EN_R | OTHERS | BUS | 7 | 5 | 5 | 10 | 5 | 14 | 6 | 10 | 12 | 12 | 12 | 12 |  | 50 Ohms | TOP=L2:L3=L2/L4:L6=L5/L7:BOTTOM=L7 |
| BMC_JTAG_L_EN_R | OTHERS | BUS | 8 | 4.75 | 5 | 10 | 5 | 14 | 6 | 9.5 | 12 | 12 | 12 | 12 |  | 50 Ohms | TOP=L2:L3=L2/L4:L6=L5/L7:BOTTOM=L7 |
| BMC_MIOZ | OTHERS | BUS | 1 | 4.75 | 5 | 10 | 5 | 14 | 6 | 9.5 | 12 | 12 | 12 | 12 |  | 50 Ohms | TOP=L2:L3=L2/L4:L6=L5/L7:BOTTOM=L7 |
| BMC_MIOZ | OTHERS | BUS | 2 | 5 | 5 | 10 | 5 | 14 | 6 | 10 | 12 | 12 | 12 | 12 |  | 50 Ohms | TOP=L2:L3=L2/L4:L6=L5/L7:BOTTOM=L7 |
| BMC_MIOZ | OTHERS | BUS | 3 | 5 | 5 | 10 | 5 | 14 | 6 | 10 | 12 | 12 | 12 | 12 |  | 50 Ohms | TOP=L2:L3=L2/L4:L6=L5/L7:BOTTOM=L7 |
| BMC_MIOZ | OTHERS | BUS | 4 | 5 | 5 | 10 | 5 | 14 | 6 | 10 | 12 | 12 | 12 | 12 |  | 50 Ohms | TOP=L2:L3=L2/L4:L6=L5/L7:BOTTOM=L7 |
| BMC_MIOZ | OTHERS | BUS | 5 | 5 | 5 | 10 | 5 | 14 | 6 | 10 | 12 | 12 | 12 | 12 |  | 50 Ohms | TOP=L2:L3=L2/L4:L6=L5/L7:BOTTOM=L7 |
| BMC_MIOZ | OTHERS | BUS | 6 | 5 | 5 | 10 | 5 | 14 | 6 | 10 | 12 | 12 | 12 | 12 |  | 50 Ohms | TOP=L2:L3=L2/L4:L6=L5/L7:BOTTOM=L7 |
| BMC_MIOZ | OTHERS | BUS | 7 | 5 | 5 | 10 | 5 | 14 | 6 | 10 | 12 | 12 | 12 | 12 |  | 50 Ohms | TOP=L2:L3=L2/L4:L6=L5/L7:BOTTOM=L7 |
| BMC_MIOZ | OTHERS | BUS | 8 | 4.75 | 5 | 10 | 5 | 14 | 6 | 9.5 | 12 | 12 | 12 | 12 |  | 50 Ohms | TOP=L2:L3=L2/L4:L6=L5/L7:BOTTOM=L7 |
| BMC_PEREXT | OTHERS | BUS | 1 | 4.75 | 5 | 10 | 5 | 14 | 6 | 9.5 | 12 | 12 | 12 | 12 |  | 50 Ohms | TOP=L2:L3=L2/L4:L6=L5/L7:BOTTOM=L7 |
| BMC_PEREXT | OTHERS | BUS | 2 | 5 | 5 | 10 | 5 | 14 | 6 | 10 | 12 | 12 | 12 | 12 |  | 50 Ohms | TOP=L2:L3=L2/L4:L6=L5/L7:BOTTOM=L7 |
| BMC_PEREXT | OTHERS | BUS | 3 | 5 | 5 | 10 | 5 | 14 | 6 | 10 | 12 | 12 | 12 | 12 |  | 50 Ohms | TOP=L2:L3=L2/L4:L6=L5/L7:BOTTOM=L7 |
| BMC_PEREXT | OTHERS | BUS | 4 | 5 | 5 | 10 | 5 | 14 | 6 | 10 | 12 | 12 | 12 | 12 |  | 50 Ohms | TOP=L2:L3=L2/L4:L6=L5/L7:BOTTOM=L7 |
| BMC_PEREXT | OTHERS | BUS | 5 | 5 | 5 | 10 | 5 | 14 | 6 | 10 | 12 | 12 | 12 | 12 |  | 50 Ohms | TOP=L2:L3=L2/L4:L6=L5/L7:BOTTOM=L7 |
| BMC_PEREXT | OTHERS | BUS | 6 | 5 | 5 | 10 | 5 | 14 | 6 | 10 | 12 | 12 | 12 | 12 |  | 50 Ohms | TOP=L2:L3=L2/L4:L6=L5/L7:BOTTOM=L7 |
| BMC_PEREXT | OTHERS | BUS | 7 | 5 | 5 | 10 | 5 | 14 | 6 | 10 | 12 | 12 | 12 | 12 |  | 50 Ohms | TOP=L2:L3=L2/L4:L6=L5/L7:BOTTOM=L7 |
| BMC_PEREXT | OTHERS | BUS | 8 | 4.75 | 5 | 10 | 5 | 14 | 6 | 9.5 | 12 | 12 | 12 | 12 |  | 50 Ohms | TOP=L2:L3=L2/L4:L6=L5/L7:BOTTOM=L7 |
| BMC_PERST#_R | OTHERS | BUS | 1 | 4.75 | 5 | 10 | 5 | 14 | 6 | 9.5 | 12 | 12 | 12 | 12 |  | 50 Ohms | TOP=L2:L3=L2/L4:L6=L5/L7:BOTTOM=L7 |
| BMC_PERST#_R | OTHERS | BUS | 2 | 5 | 5 | 10 | 5 | 14 | 6 | 10 | 12 | 12 | 12 | 12 |  | 50 Ohms | TOP=L2:L3=L2/L4:L6=L5/L7:BOTTOM=L7 |
| BMC_PERST#_R | OTHERS | BUS | 3 | 5 | 5 | 10 | 5 | 14 | 6 | 10 | 12 | 12 | 12 | 12 |  | 50 Ohms | TOP=L2:L3=L2/L4:L6=L5/L7:BOTTOM=L7 |
| BMC_PERST#_R | OTHERS | BUS | 4 | 5 | 5 | 10 | 5 | 14 | 6 | 10 | 12 | 12 | 12 | 12 |  | 50 Ohms | TOP=L2:L3=L2/L4:L6=L5/L7:BOTTOM=L7 |
| BMC_PERST#_R | OTHERS | BUS | 5 | 5 | 5 | 10 | 5 | 14 | 6 | 10 | 12 | 12 | 12 | 12 |  | 50 Ohms | TOP=L2:L3=L2/L4:L6=L5/L7:BOTTOM=L7 |
| BMC_PERST#_R | OTHERS | BUS | 6 | 5 | 5 | 10 | 5 | 14 | 6 | 10 | 12 | 12 | 12 | 12 |  | 50 Ohms | TOP=L2:L3=L2/L4:L6=L5/L7:BOTTOM=L7 |
| BMC_PERST#_R | OTHERS | BUS | 7 | 5 | 5 | 10 | 5 | 14 | 6 | 10 | 12 | 12 | 12 | 12 |  | 50 Ohms | TOP=L2:L3=L2/L4:L6=L5/L7:BOTTOM=L7 |
| BMC_PERST#_R | OTHERS | BUS | 8 | 4.75 | 5 | 10 | 5 | 14 | 6 | 9.5 | 12 | 12 | 12 | 12 |  | 50 Ohms | TOP=L2:L3=L2/L4:L6=L5/L7:BOTTOM=L7 |
| BMC_PERST#15 | OTHERS | BUS | 1 | 4.75 | 5 | 10 | 5 | 14 | 6 | 9.5 | 12 | 12 | 12 | 12 |  | 50 Ohms | TOP=L2:L3=L2/L4:L6=L5/L7:BOTTOM=L7 |
| BMC_PERST#15 | OTHERS | BUS | 2 | 5 | 5 | 10 | 5 | 14 | 6 | 10 | 12 | 12 | 12 | 12 |  | 50 Ohms | TOP=L2:L3=L2/L4:L6=L5/L7:BOTTOM=L7 |
| BMC_PERST#15 | OTHERS | BUS | 3 | 5 | 5 | 10 | 5 | 14 | 6 | 10 | 12 | 12 | 12 | 12 |  | 50 Ohms | TOP=L2:L3=L2/L4:L6=L5/L7:BOTTOM=L7 |
| BMC_PERST#15 | OTHERS | BUS | 4 | 5 | 5 | 10 | 5 | 14 | 6 | 10 | 12 | 12 | 12 | 12 |  | 50 Ohms | TOP=L2:L3=L2/L4:L6=L5/L7:BOTTOM=L7 |
| BMC_PERST#15 | OTHERS | BUS | 5 | 5 | 5 | 10 | 5 | 14 | 6 | 10 | 12 | 12 | 12 | 12 |  | 50 Ohms | TOP=L2:L3=L2/L4:L6=L5/L7:BOTTOM=L7 |
| BMC_PERST#15 | OTHERS | BUS | 6 | 5 | 5 | 10 | 5 | 14 | 6 | 10 | 12 | 12 | 12 | 12 |  | 50 Ohms | TOP=L2:L3=L2/L4:L6=L5/L7:BOTTOM=L7 |
| BMC_PERST#15 | OTHERS | BUS | 7 | 5 | 5 | 10 | 5 | 14 | 6 | 10 | 12 | 12 | 12 | 12 |  | 50 Ohms | TOP=L2:L3=L2/L4:L6=L5/L7:BOTTOM=L7 |
| BMC_PERST#15 | OTHERS | BUS | 8 | 4.75 | 5 | 10 | 5 | 14 | 6 | 9.5 | 12 | 12 | 12 | 12 |  | 50 Ohms | TOP=L2:L3=L2/L4:L6=L5/L7:BOTTOM=L7 |
| BMC_RESET#_DDR3 | OTHERS | BUS | 1 | 4.75 | 5 | 10 | 5 | 14 | 6 | 9.5 | 12 | 12 | 12 | 12 |  | 50 Ohms | TOP=L2:L3=L2/L4:L6=L5/L7:BOTTOM=L7 |
| BMC_RESET#_DDR3 | OTHERS | BUS | 2 | 5 | 5 | 10 | 5 | 14 | 6 | 10 | 12 | 12 | 12 | 12 |  | 50 Ohms | TOP=L2:L3=L2/L4:L6=L5/L7:BOTTOM=L7 |
| BMC_RESET#_DDR3 | OTHERS | BUS | 3 | 5 | 5 | 10 | 5 | 14 | 6 | 10 | 12 | 12 | 12 | 12 |  | 50 Ohms | TOP=L2:L3=L2/L4:L6=L5/L7:BOTTOM=L7 |
| BMC_RESET#_DDR3 | OTHERS | BUS | 4 | 5 | 5 | 10 | 5 | 14 | 6 | 10 | 12 | 12 | 12 | 12 |  | 50 Ohms | TOP=L2:L3=L2/L4:L6=L5/L7:BOTTOM=L7 |
| BMC_RESET#_DDR3 | OTHERS | BUS | 5 | 5 | 5 | 10 | 5 | 14 | 6 | 10 | 12 | 12 | 12 | 12 |  | 50 Ohms | TOP=L2:L3=L2/L4:L6=L5/L7:BOTTOM=L7 |
| BMC_RESET#_DDR3 | OTHERS | BUS | 6 | 5 | 5 | 10 | 5 | 14 | 6 | 10 | 12 | 12 | 12 | 12 |  | 50 Ohms | TOP=L2:L3=L2/L4:L6=L5/L7:BOTTOM=L7 |
| BMC_RESET#_DDR3 | OTHERS | BUS | 7 | 5 | 5 | 10 | 5 | 14 | 6 | 10 | 12 | 12 | 12 | 12 |  | 50 Ohms | TOP=L2:L3=L2/L4:L6=L5/L7:BOTTOM=L7 |
| BMC_RESET#_DDR3 | OTHERS | BUS | 8 | 4.75 | 5 | 10 | 5 | 14 | 6 | 9.5 | 12 | 12 | 12 | 12 |  | 50 Ohms | TOP=L2:L3=L2/L4:L6=L5/L7:BOTTOM=L7 |
| BMC_RESET#_DDR3_BUF | OTHERS | BUS | 1 | 4.75 | 5 | 10 | 5 | 14 | 6 | 9.5 | 12 | 12 | 12 | 12 |  | 50 Ohms | TOP=L2:L3=L2/L4:L6=L5/L7:BOTTOM=L7 |
| BMC_RESET#_DDR3_BUF | OTHERS | BUS | 2 | 5 | 5 | 10 | 5 | 14 | 6 | 10 | 12 | 12 | 12 | 12 |  | 50 Ohms | TOP=L2:L3=L2/L4:L6=L5/L7:BOTTOM=L7 |
| BMC_RESET#_DDR3_BUF | OTHERS | BUS | 3 | 5 | 5 | 10 | 5 | 14 | 6 | 10 | 12 | 12 | 12 | 12 |  | 50 Ohms | TOP=L2:L3=L2/L4:L6=L5/L7:BOTTOM=L7 |
| BMC_RESET#_DDR3_BUF | OTHERS | BUS | 4 | 5 | 5 | 10 | 5 | 14 | 6 | 10 | 12 | 12 | 12 | 12 |  | 50 Ohms | TOP=L2:L3=L2/L4:L6=L5/L7:BOTTOM=L7 |
| BMC_RESET#_DDR3_BUF | OTHERS | BUS | 5 | 5 | 5 | 10 | 5 | 14 | 6 | 10 | 12 | 12 | 12 | 12 |  | 50 Ohms | TOP=L2:L3=L2/L4:L6=L5/L7:BOTTOM=L7 |
| BMC_RESET#_DDR3_BUF | OTHERS | BUS | 6 | 5 | 5 | 10 | 5 | 14 | 6 | 10 | 12 | 12 | 12 | 12 |  | 50 Ohms | TOP=L2:L3=L2/L4:L6=L5/L7:BOTTOM=L7 |
| BMC_RESET#_DDR3_BUF | OTHERS | BUS | 7 | 5 | 5 | 10 | 5 | 14 | 6 | 10 | 12 | 12 | 12 | 12 |  | 50 Ohms | TOP=L2:L3=L2/L4:L6=L5/L7:BOTTOM=L7 |
| BMC_RESET#_DDR3_BUF | OTHERS | BUS | 8 | 4.75 | 5 | 10 | 5 | 14 | 6 | 9.5 | 12 | 12 | 12 | 12 |  | 50 Ohms | TOP=L2:L3=L2/L4:L6=L5/L7:BOTTOM=L7 |
| BMC_RXCK_R | OTHERS | BUS | 1 | 4.75 | 5 | 10 | 5 | 14 | 6 | 9.5 | 12 | 12 | 12 | 12 |  | 50 Ohms | TOP=L2:L3=L2/L4:L6=L5/L7:BOTTOM=L7 |
| BMC_RXCK_R | OTHERS | BUS | 2 | 5 | 5 | 10 | 5 | 14 | 6 | 10 | 12 | 12 | 12 | 12 |  | 50 Ohms | TOP=L2:L3=L2/L4:L6=L5/L7:BOTTOM=L7 |
| BMC_RXCK_R | OTHERS | BUS | 3 | 5 | 5 | 10 | 5 | 14 | 6 | 10 | 12 | 12 | 12 | 12 |  | 50 Ohms | TOP=L2:L3=L2/L4:L6=L5/L7:BOTTOM=L7 |
| BMC_RXCK_R | OTHERS | BUS | 4 | 5 | 5 | 10 | 5 | 14 | 6 | 10 | 12 | 12 | 12 | 12 |  | 50 Ohms | TOP=L2:L3=L2/L4:L6=L5/L7:BOTTOM=L7 |
| BMC_RXCK_R | OTHERS | BUS | 5 | 5 | 5 | 10 | 5 | 14 | 6 | 10 | 12 | 12 | 12 | 12 |  | 50 Ohms | TOP=L2:L3=L2/L4:L6=L5/L7:BOTTOM=L7 |
| BMC_RXCK_R | OTHERS | BUS | 6 | 5 | 5 | 10 | 5 | 14 | 6 | 10 | 12 | 12 | 12 | 12 |  | 50 Ohms | TOP=L2:L3=L2/L4:L6=L5/L7:BOTTOM=L7 |
| BMC_RXCK_R | OTHERS | BUS | 7 | 5 | 5 | 10 | 5 | 14 | 6 | 10 | 12 | 12 | 12 | 12 |  | 50 Ohms | TOP=L2:L3=L2/L4:L6=L5/L7:BOTTOM=L7 |
| BMC_RXCK_R | OTHERS | BUS | 8 | 4.75 | 5 | 10 | 5 | 14 | 6 | 9.5 | 12 | 12 | 12 | 12 |  | 50 Ohms | TOP=L2:L3=L2/L4:L6=L5/L7:BOTTOM=L7 |
| BMC_SELF_HW_RST | OTHERS | BUS | 1 | 4.75 | 5 | 10 | 5 | 14 | 6 | 9.5 | 12 | 12 | 12 | 12 |  | 50 Ohms | TOP=L2:L3=L2/L4:L6=L5/L7:BOTTOM=L7 |
| BMC_SELF_HW_RST | OTHERS | BUS | 2 | 5 | 5 | 10 | 5 | 14 | 6 | 10 | 12 | 12 | 12 | 12 |  | 50 Ohms | TOP=L2:L3=L2/L4:L6=L5/L7:BOTTOM=L7 |
| BMC_SELF_HW_RST | OTHERS | BUS | 3 | 5 | 5 | 10 | 5 | 14 | 6 | 10 | 12 | 12 | 12 | 12 |  | 50 Ohms | TOP=L2:L3=L2/L4:L6=L5/L7:BOTTOM=L7 |
| BMC_SELF_HW_RST | OTHERS | BUS | 4 | 5 | 5 | 10 | 5 | 14 | 6 | 10 | 12 | 12 | 12 | 12 |  | 50 Ohms | TOP=L2:L3=L2/L4:L6=L5/L7:BOTTOM=L7 |
| BMC_SELF_HW_RST | OTHERS | BUS | 5 | 5 | 5 | 10 | 5 | 14 | 6 | 10 | 12 | 12 | 12 | 12 |  | 50 Ohms | TOP=L2:L3=L2/L4:L6=L5/L7:BOTTOM=L7 |
| BMC_SELF_HW_RST | OTHERS | BUS | 6 | 5 | 5 | 10 | 5 | 14 | 6 | 10 | 12 | 12 | 12 | 12 |  | 50 Ohms | TOP=L2:L3=L2/L4:L6=L5/L7:BOTTOM=L7 |
| BMC_SELF_HW_RST | OTHERS | BUS | 7 | 5 | 5 | 10 | 5 | 14 | 6 | 10 | 12 | 12 | 12 | 12 |  | 50 Ohms | TOP=L2:L3=L2/L4:L6=L5/L7:BOTTOM=L7 |
| BMC_SELF_HW_RST | OTHERS | BUS | 8 | 4.75 | 5 | 10 | 5 | 14 | 6 | 9.5 | 12 | 12 | 12 | 12 |  | 50 Ohms | TOP=L2:L3=L2/L4:L6=L5/L7:BOTTOM=L7 |
| BMC_SELF_HW_RST_R | OTHERS | BUS | 1 | 4.75 | 5 | 10 | 5 | 14 | 6 | 9.5 | 12 | 12 | 12 | 12 |  | 50 Ohms | TOP=L2:L3=L2/L4:L6=L5/L7:BOTTOM=L7 |
| BMC_SELF_HW_RST_R | OTHERS | BUS | 2 | 5 | 5 | 10 | 5 | 14 | 6 | 10 | 12 | 12 | 12 | 12 |  | 50 Ohms | TOP=L2:L3=L2/L4:L6=L5/L7:BOTTOM=L7 |
| BMC_SELF_HW_RST_R | OTHERS | BUS | 3 | 5 | 5 | 10 | 5 | 14 | 6 | 10 | 12 | 12 | 12 | 12 |  | 50 Ohms | TOP=L2:L3=L2/L4:L6=L5/L7:BOTTOM=L7 |
| BMC_SELF_HW_RST_R | OTHERS | BUS | 4 | 5 | 5 | 10 | 5 | 14 | 6 | 10 | 12 | 12 | 12 | 12 |  | 50 Ohms | TOP=L2:L3=L2/L4:L6=L5/L7:BOTTOM=L7 |
| BMC_SELF_HW_RST_R | OTHERS | BUS | 5 | 5 | 5 | 10 | 5 | 14 | 6 | 10 | 12 | 12 | 12 | 12 |  | 50 Ohms | TOP=L2:L3=L2/L4:L6=L5/L7:BOTTOM=L7 |
| BMC_SELF_HW_RST_R | OTHERS | BUS | 6 | 5 | 5 | 10 | 5 | 14 | 6 | 10 | 12 | 12 | 12 | 12 |  | 50 Ohms | TOP=L2:L3=L2/L4:L6=L5/L7:BOTTOM=L7 |
| BMC_SELF_HW_RST_R | OTHERS | BUS | 7 | 5 | 5 | 10 | 5 | 14 | 6 | 10 | 12 | 12 | 12 | 12 |  | 50 Ohms | TOP=L2:L3=L2/L4:L6=L5/L7:BOTTOM=L7 |
| BMC_SELF_HW_RST_R | OTHERS | BUS | 8 | 4.75 | 5 | 10 | 5 | 14 | 6 | 9.5 | 12 | 12 | 12 | 12 |  | 50 Ohms | TOP=L2:L3=L2/L4:L6=L5/L7:BOTTOM=L7 |
| BMC_SELF_TRAY | OTHERS | BUS | 1 | 4.75 | 5 | 10 | 5 | 14 | 6 | 9.5 | 12 | 12 | 12 | 12 |  | 50 Ohms | TOP=L2:L3=L2/L4:L6=L5/L7:BOTTOM=L7 |
| BMC_SELF_TRAY | OTHERS | BUS | 2 | 5 | 5 | 10 | 5 | 14 | 6 | 10 | 12 | 12 | 12 | 12 |  | 50 Ohms | TOP=L2:L3=L2/L4:L6=L5/L7:BOTTOM=L7 |
| BMC_SELF_TRAY | OTHERS | BUS | 3 | 5 | 5 | 10 | 5 | 14 | 6 | 10 | 12 | 12 | 12 | 12 |  | 50 Ohms | TOP=L2:L3=L2/L4:L6=L5/L7:BOTTOM=L7 |
| BMC_SELF_TRAY | OTHERS | BUS | 4 | 5 | 5 | 10 | 5 | 14 | 6 | 10 | 12 | 12 | 12 | 12 |  | 50 Ohms | TOP=L2:L3=L2/L4:L6=L5/L7:BOTTOM=L7 |
| BMC_SELF_TRAY | OTHERS | BUS | 5 | 5 | 5 | 10 | 5 | 14 | 6 | 10 | 12 | 12 | 12 | 12 |  | 50 Ohms | TOP=L2:L3=L2/L4:L6=L5/L7:BOTTOM=L7 |
| BMC_SELF_TRAY | OTHERS | BUS | 6 | 5 | 5 | 10 | 5 | 14 | 6 | 10 | 12 | 12 | 12 | 12 |  | 50 Ohms | TOP=L2:L3=L2/L4:L6=L5/L7:BOTTOM=L7 |
| BMC_SELF_TRAY | OTHERS | BUS | 7 | 5 | 5 | 10 | 5 | 14 | 6 | 10 | 12 | 12 | 12 | 12 |  | 50 Ohms | TOP=L2:L3=L2/L4:L6=L5/L7:BOTTOM=L7 |
| BMC_SELF_TRAY | OTHERS | BUS | 8 | 4.75 | 5 | 10 | 5 | 14 | 6 | 9.5 | 12 | 12 | 12 | 12 |  | 50 Ohms | TOP=L2:L3=L2/L4:L6=L5/L7:BOTTOM=L7 |
| BMC_SELF_TRAY_R | OTHERS | BUS | 1 | 4.75 | 5 | 10 | 5 | 14 | 6 | 9.5 | 12 | 12 | 12 | 12 |  | 50 Ohms | TOP=L2:L3=L2/L4:L6=L5/L7:BOTTOM=L7 |
| BMC_SELF_TRAY_R | OTHERS | BUS | 2 | 5 | 5 | 10 | 5 | 14 | 6 | 10 | 12 | 12 | 12 | 12 |  | 50 Ohms | TOP=L2:L3=L2/L4:L6=L5/L7:BOTTOM=L7 |
| BMC_SELF_TRAY_R | OTHERS | BUS | 3 | 5 | 5 | 10 | 5 | 14 | 6 | 10 | 12 | 12 | 12 | 12 |  | 50 Ohms | TOP=L2:L3=L2/L4:L6=L5/L7:BOTTOM=L7 |
| BMC_SELF_TRAY_R | OTHERS | BUS | 4 | 5 | 5 | 10 | 5 | 14 | 6 | 10 | 12 | 12 | 12 | 12 |  | 50 Ohms | TOP=L2:L3=L2/L4:L6=L5/L7:BOTTOM=L7 |
| BMC_SELF_TRAY_R | OTHERS | BUS | 5 | 5 | 5 | 10 | 5 | 14 | 6 | 10 | 12 | 12 | 12 | 12 |  | 50 Ohms | TOP=L2:L3=L2/L4:L6=L5/L7:BOTTOM=L7 |
| BMC_SELF_TRAY_R | OTHERS | BUS | 6 | 5 | 5 | 10 | 5 | 14 | 6 | 10 | 12 | 12 | 12 | 12 |  | 50 Ohms | TOP=L2:L3=L2/L4:L6=L5/L7:BOTTOM=L7 |
| BMC_SELF_TRAY_R | OTHERS | BUS | 7 | 5 | 5 | 10 | 5 | 14 | 6 | 10 | 12 | 12 | 12 | 12 |  | 50 Ohms | TOP=L2:L3=L2/L4:L6=L5/L7:BOTTOM=L7 |
| BMC_SELF_TRAY_R | OTHERS | BUS | 8 | 4.75 | 5 | 10 | 5 | 14 | 6 | 9.5 | 12 | 12 | 12 | 12 |  | 50 Ohms | TOP=L2:L3=L2/L4:L6=L5/L7:BOTTOM=L7 |
| BMC_SSD_RST#0 | OTHERS | BUS | 1 | 4.75 | 5 | 10 | 5 | 14 | 6 | 9.5 | 12 | 12 | 12 | 12 |  | 50 Ohms | TOP=L2:L3=L2/L4:L6=L5/L7:BOTTOM=L7 |
| BMC_SSD_RST#0 | OTHERS | BUS | 2 | 5 | 5 | 10 | 5 | 14 | 6 | 10 | 12 | 12 | 12 | 12 |  | 50 Ohms | TOP=L2:L3=L2/L4:L6=L5/L7:BOTTOM=L7 |
| BMC_SSD_RST#0 | OTHERS | BUS | 3 | 5 | 5 | 10 | 5 | 14 | 6 | 10 | 12 | 12 | 12 | 12 |  | 50 Ohms | TOP=L2:L3=L2/L4:L6=L5/L7:BOTTOM=L7 |
| BMC_SSD_RST#0 | OTHERS | BUS | 4 | 5 | 5 | 10 | 5 | 14 | 6 | 10 | 12 | 12 | 12 | 12 |  | 50 Ohms | TOP=L2:L3=L2/L4:L6=L5/L7:BOTTOM=L7 |
| BMC_SSD_RST#0 | OTHERS | BUS | 5 | 5 | 5 | 10 | 5 | 14 | 6 | 10 | 12 | 12 | 12 | 12 |  | 50 Ohms | TOP=L2:L3=L2/L4:L6=L5/L7:BOTTOM=L7 |
| BMC_SSD_RST#0 | OTHERS | BUS | 6 | 5 | 5 | 10 | 5 | 14 | 6 | 10 | 12 | 12 | 12 | 12 |  | 50 Ohms | TOP=L2:L3=L2/L4:L6=L5/L7:BOTTOM=L7 |
| BMC_SSD_RST#0 | OTHERS | BUS | 7 | 5 | 5 | 10 | 5 | 14 | 6 | 10 | 12 | 12 | 12 | 12 |  | 50 Ohms | TOP=L2:L3=L2/L4:L6=L5/L7:BOTTOM=L7 |
| BMC_SSD_RST#0 | OTHERS | BUS | 8 | 4.75 | 5 | 10 | 5 | 14 | 6 | 9.5 | 12 | 12 | 12 | 12 |  | 50 Ohms | TOP=L2:L3=L2/L4:L6=L5/L7:BOTTOM=L7 |
| BMC_SSD_RST#0_A0 | OTHERS | BUS | 1 | 4.75 | 5 | 10 | 5 | 14 | 6 | 9.5 | 12 | 12 | 12 | 12 |  | 50 Ohms | TOP=L2:L3=L2/L4:L6=L5/L7:BOTTOM=L7 |
| BMC_SSD_RST#0_A0 | OTHERS | BUS | 2 | 5 | 5 | 10 | 5 | 14 | 6 | 10 | 12 | 12 | 12 | 12 |  | 50 Ohms | TOP=L2:L3=L2/L4:L6=L5/L7:BOTTOM=L7 |
| BMC_SSD_RST#0_A0 | OTHERS | BUS | 3 | 5 | 5 | 10 | 5 | 14 | 6 | 10 | 12 | 12 | 12 | 12 |  | 50 Ohms | TOP=L2:L3=L2/L4:L6=L5/L7:BOTTOM=L7 |
| BMC_SSD_RST#0_A0 | OTHERS | BUS | 4 | 5 | 5 | 10 | 5 | 14 | 6 | 10 | 12 | 12 | 12 | 12 |  | 50 Ohms | TOP=L2:L3=L2/L4:L6=L5/L7:BOTTOM=L7 |
| BMC_SSD_RST#0_A0 | OTHERS | BUS | 5 | 5 | 5 | 10 | 5 | 14 | 6 | 10 | 12 | 12 | 12 | 12 |  | 50 Ohms | TOP=L2:L3=L2/L4:L6=L5/L7:BOTTOM=L7 |
| BMC_SSD_RST#0_A0 | OTHERS | BUS | 6 | 5 | 5 | 10 | 5 | 14 | 6 | 10 | 12 | 12 | 12 | 12 |  | 50 Ohms | TOP=L2:L3=L2/L4:L6=L5/L7:BOTTOM=L7 |
| BMC_SSD_RST#0_A0 | OTHERS | BUS | 7 | 5 | 5 | 10 | 5 | 14 | 6 | 10 | 12 | 12 | 12 | 12 |  | 50 Ohms | TOP=L2:L3=L2/L4:L6=L5/L7:BOTTOM=L7 |
| BMC_SSD_RST#0_A0 | OTHERS | BUS | 8 | 4.75 | 5 | 10 | 5 | 14 | 6 | 9.5 | 12 | 12 | 12 | 12 |  | 50 Ohms | TOP=L2:L3=L2/L4:L6=L5/L7:BOTTOM=L7 |
| BMC_SSD_RST#0_A1 | OTHERS | BUS | 1 | 4.75 | 5 | 10 | 5 | 14 | 6 | 9.5 | 12 | 12 | 12 | 12 |  | 50 Ohms | TOP=L2:L3=L2/L4:L6=L5/L7:BOTTOM=L7 |
| BMC_SSD_RST#0_A1 | OTHERS | BUS | 2 | 5 | 5 | 10 | 5 | 14 | 6 | 10 | 12 | 12 | 12 | 12 |  | 50 Ohms | TOP=L2:L3=L2/L4:L6=L5/L7:BOTTOM=L7 |
| BMC_SSD_RST#0_A1 | OTHERS | BUS | 3 | 5 | 5 | 10 | 5 | 14 | 6 | 10 | 12 | 12 | 12 | 12 |  | 50 Ohms | TOP=L2:L3=L2/L4:L6=L5/L7:BOTTOM=L7 |
| BMC_SSD_RST#0_A1 | OTHERS | BUS | 4 | 5 | 5 | 10 | 5 | 14 | 6 | 10 | 12 | 12 | 12 | 12 |  | 50 Ohms | TOP=L2:L3=L2/L4:L6=L5/L7:BOTTOM=L7 |
| BMC_SSD_RST#0_A1 | OTHERS | BUS | 5 | 5 | 5 | 10 | 5 | 14 | 6 | 10 | 12 | 12 | 12 | 12 |  | 50 Ohms | TOP=L2:L3=L2/L4:L6=L5/L7:BOTTOM=L7 |
| BMC_SSD_RST#0_A1 | OTHERS | BUS | 6 | 5 | 5 | 10 | 5 | 14 | 6 | 10 | 12 | 12 | 12 | 12 |  | 50 Ohms | TOP=L2:L3=L2/L4:L6=L5/L7:BOTTOM=L7 |
| BMC_SSD_RST#0_A1 | OTHERS | BUS | 7 | 5 | 5 | 10 | 5 | 14 | 6 | 10 | 12 | 12 | 12 | 12 |  | 50 Ohms | TOP=L2:L3=L2/L4:L6=L5/L7:BOTTOM=L7 |
| BMC_SSD_RST#0_A1 | OTHERS | BUS | 8 | 4.75 | 5 | 10 | 5 | 14 | 6 | 9.5 | 12 | 12 | 12 | 12 |  | 50 Ohms | TOP=L2:L3=L2/L4:L6=L5/L7:BOTTOM=L7 |
| BMC_SSD_RST#0_A10 | OTHERS | BUS | 1 | 4.75 | 5 | 10 | 5 | 14 | 6 | 9.5 | 12 | 12 | 12 | 12 |  | 50 Ohms | TOP=L2:L3=L2/L4:L6=L5/L7:BOTTOM=L7 |
| BMC_SSD_RST#0_A10 | OTHERS | BUS | 2 | 5 | 5 | 10 | 5 | 14 | 6 | 10 | 12 | 12 | 12 | 12 |  | 50 Ohms | TOP=L2:L3=L2/L4:L6=L5/L7:BOTTOM=L7 |
| BMC_SSD_RST#0_A10 | OTHERS | BUS | 3 | 5 | 5 | 10 | 5 | 14 | 6 | 10 | 12 | 12 | 12 | 12 |  | 50 Ohms | TOP=L2:L3=L2/L4:L6=L5/L7:BOTTOM=L7 |
| BMC_SSD_RST#0_A10 | OTHERS | BUS | 4 | 5 | 5 | 10 | 5 | 14 | 6 | 10 | 12 | 12 | 12 | 12 |  | 50 Ohms | TOP=L2:L3=L2/L4:L6=L5/L7:BOTTOM=L7 |
| BMC_SSD_RST#0_A10 | OTHERS | BUS | 5 | 5 | 5 | 10 | 5 | 14 | 6 | 10 | 12 | 12 | 12 | 12 |  | 50 Ohms | TOP=L2:L3=L2/L4:L6=L5/L7:BOTTOM=L7 |
| BMC_SSD_RST#0_A10 | OTHERS | BUS | 6 | 5 | 5 | 10 | 5 | 14 | 6 | 10 | 12 | 12 | 12 | 12 |  | 50 Ohms | TOP=L2:L3=L2/L4:L6=L5/L7:BOTTOM=L7 |
| BMC_SSD_RST#0_A10 | OTHERS | BUS | 7 | 5 | 5 | 10 | 5 | 14 | 6 | 10 | 12 | 12 | 12 | 12 |  | 50 Ohms | TOP=L2:L3=L2/L4:L6=L5/L7:BOTTOM=L7 |
| BMC_SSD_RST#0_A10 | OTHERS | BUS | 8 | 4.75 | 5 | 10 | 5 | 14 | 6 | 9.5 | 12 | 12 | 12 | 12 |  | 50 Ohms | TOP=L2:L3=L2/L4:L6=L5/L7:BOTTOM=L7 |
| BMC_SSD_RST#0_A11 | OTHERS | BUS | 1 | 4.75 | 5 | 10 | 5 | 14 | 6 | 9.5 | 12 | 12 | 12 | 12 |  | 50 Ohms | TOP=L2:L3=L2/L4:L6=L5/L7:BOTTOM=L7 |
| BMC_SSD_RST#0_A11 | OTHERS | BUS | 2 | 5 | 5 | 10 | 5 | 14 | 6 | 10 | 12 | 12 | 12 | 12 |  | 50 Ohms | TOP=L2:L3=L2/L4:L6=L5/L7:BOTTOM=L7 |
| BMC_SSD_RST#0_A11 | OTHERS | BUS | 3 | 5 | 5 | 10 | 5 | 14 | 6 | 10 | 12 | 12 | 12 | 12 |  | 50 Ohms | TOP=L2:L3=L2/L4:L6=L5/L7:BOTTOM=L7 |
| BMC_SSD_RST#0_A11 | OTHERS | BUS | 4 | 5 | 5 | 10 | 5 | 14 | 6 | 10 | 12 | 12 | 12 | 12 |  | 50 Ohms | TOP=L2:L3=L2/L4:L6=L5/L7:BOTTOM=L7 |
| BMC_SSD_RST#0_A11 | OTHERS | BUS | 5 | 5 | 5 | 10 | 5 | 14 | 6 | 10 | 12 | 12 | 12 | 12 |  | 50 Ohms | TOP=L2:L3=L2/L4:L6=L5/L7:BOTTOM=L7 |
| BMC_SSD_RST#0_A11 | OTHERS | BUS | 6 | 5 | 5 | 10 | 5 | 14 | 6 | 10 | 12 | 12 | 12 | 12 |  | 50 Ohms | TOP=L2:L3=L2/L4:L6=L5/L7:BOTTOM=L7 |
| BMC_SSD_RST#0_A11 | OTHERS | BUS | 7 | 5 | 5 | 10 | 5 | 14 | 6 | 10 | 12 | 12 | 12 | 12 |  | 50 Ohms | TOP=L2:L3=L2/L4:L6=L5/L7:BOTTOM=L7 |
| BMC_SSD_RST#0_A11 | OTHERS | BUS | 8 | 4.75 | 5 | 10 | 5 | 14 | 6 | 9.5 | 12 | 12 | 12 | 12 |  | 50 Ohms | TOP=L2:L3=L2/L4:L6=L5/L7:BOTTOM=L7 |
| BMC_SSD_RST#0_A12 | OTHERS | BUS | 1 | 4.75 | 5 | 10 | 5 | 14 | 6 | 9.5 | 12 | 12 | 12 | 12 |  | 50 Ohms | TOP=L2:L3=L2/L4:L6=L5/L7:BOTTOM=L7 |
| BMC_SSD_RST#0_A12 | OTHERS | BUS | 2 | 5 | 5 | 10 | 5 | 14 | 6 | 10 | 12 | 12 | 12 | 12 |  | 50 Ohms | TOP=L2:L3=L2/L4:L6=L5/L7:BOTTOM=L7 |
| BMC_SSD_RST#0_A12 | OTHERS | BUS | 3 | 5 | 5 | 10 | 5 | 14 | 6 | 10 | 12 | 12 | 12 | 12 |  | 50 Ohms | TOP=L2:L3=L2/L4:L6=L5/L7:BOTTOM=L7 |
| BMC_SSD_RST#0_A12 | OTHERS | BUS | 4 | 5 | 5 | 10 | 5 | 14 | 6 | 10 | 12 | 12 | 12 | 12 |  | 50 Ohms | TOP=L2:L3=L2/L4:L6=L5/L7:BOTTOM=L7 |
| BMC_SSD_RST#0_A12 | OTHERS | BUS | 5 | 5 | 5 | 10 | 5 | 14 | 6 | 10 | 12 | 12 | 12 | 12 |  | 50 Ohms | TOP=L2:L3=L2/L4:L6=L5/L7:BOTTOM=L7 |
| BMC_SSD_RST#0_A12 | OTHERS | BUS | 6 | 5 | 5 | 10 | 5 | 14 | 6 | 10 | 12 | 12 | 12 | 12 |  | 50 Ohms | TOP=L2:L3=L2/L4:L6=L5/L7:BOTTOM=L7 |
| BMC_SSD_RST#0_A12 | OTHERS | BUS | 7 | 5 | 5 | 10 | 5 | 14 | 6 | 10 | 12 | 12 | 12 | 12 |  | 50 Ohms | TOP=L2:L3=L2/L4:L6=L5/L7:BOTTOM=L7 |
| BMC_SSD_RST#0_A12 | OTHERS | BUS | 8 | 4.75 | 5 | 10 | 5 | 14 | 6 | 9.5 | 12 | 12 | 12 | 12 |  | 50 Ohms | TOP=L2:L3=L2/L4:L6=L5/L7:BOTTOM=L7 |
| BMC_SSD_RST#0_A13 | OTHERS | BUS | 1 | 4.75 | 5 | 10 | 5 | 14 | 6 | 9.5 | 12 | 12 | 12 | 12 |  | 50 Ohms | TOP=L2:L3=L2/L4:L6=L5/L7:BOTTOM=L7 |
| BMC_SSD_RST#0_A13 | OTHERS | BUS | 2 | 5 | 5 | 10 | 5 | 14 | 6 | 10 | 12 | 12 | 12 | 12 |  | 50 Ohms | TOP=L2:L3=L2/L4:L6=L5/L7:BOTTOM=L7 |
| BMC_SSD_RST#0_A13 | OTHERS | BUS | 3 | 5 | 5 | 10 | 5 | 14 | 6 | 10 | 12 | 12 | 12 | 12 |  | 50 Ohms | TOP=L2:L3=L2/L4:L6=L5/L7:BOTTOM=L7 |
| BMC_SSD_RST#0_A13 | OTHERS | BUS | 4 | 5 | 5 | 10 | 5 | 14 | 6 | 10 | 12 | 12 | 12 | 12 |  | 50 Ohms | TOP=L2:L3=L2/L4:L6=L5/L7:BOTTOM=L7 |
| BMC_SSD_RST#0_A13 | OTHERS | BUS | 5 | 5 | 5 | 10 | 5 | 14 | 6 | 10 | 12 | 12 | 12 | 12 |  | 50 Ohms | TOP=L2:L3=L2/L4:L6=L5/L7:BOTTOM=L7 |
| BMC_SSD_RST#0_A13 | OTHERS | BUS | 6 | 5 | 5 | 10 | 5 | 14 | 6 | 10 | 12 | 12 | 12 | 12 |  | 50 Ohms | TOP=L2:L3=L2/L4:L6=L5/L7:BOTTOM=L7 |
| BMC_SSD_RST#0_A13 | OTHERS | BUS | 7 | 5 | 5 | 10 | 5 | 14 | 6 | 10 | 12 | 12 | 12 | 12 |  | 50 Ohms | TOP=L2:L3=L2/L4:L6=L5/L7:BOTTOM=L7 |
| BMC_SSD_RST#0_A13 | OTHERS | BUS | 8 | 4.75 | 5 | 10 | 5 | 14 | 6 | 9.5 | 12 | 12 | 12 | 12 |  | 50 Ohms | TOP=L2:L3=L2/L4:L6=L5/L7:BOTTOM=L7 |
| BMC_SSD_RST#0_A14 | OTHERS | BUS | 1 | 4.75 | 5 | 10 | 5 | 14 | 6 | 9.5 | 12 | 12 | 12 | 12 |  | 50 Ohms | TOP=L2:L3=L2/L4:L6=L5/L7:BOTTOM=L7 |
| BMC_SSD_RST#0_A14 | OTHERS | BUS | 2 | 5 | 5 | 10 | 5 | 14 | 6 | 10 | 12 | 12 | 12 | 12 |  | 50 Ohms | TOP=L2:L3=L2/L4:L6=L5/L7:BOTTOM=L7 |
| BMC_SSD_RST#0_A14 | OTHERS | BUS | 3 | 5 | 5 | 10 | 5 | 14 | 6 | 10 | 12 | 12 | 12 | 12 |  | 50 Ohms | TOP=L2:L3=L2/L4:L6=L5/L7:BOTTOM=L7 |
| BMC_SSD_RST#0_A14 | OTHERS | BUS | 4 | 5 | 5 | 10 | 5 | 14 | 6 | 10 | 12 | 12 | 12 | 12 |  | 50 Ohms | TOP=L2:L3=L2/L4:L6=L5/L7:BOTTOM=L7 |
| BMC_SSD_RST#0_A14 | OTHERS | BUS | 5 | 5 | 5 | 10 | 5 | 14 | 6 | 10 | 12 | 12 | 12 | 12 |  | 50 Ohms | TOP=L2:L3=L2/L4:L6=L5/L7:BOTTOM=L7 |
| BMC_SSD_RST#0_A14 | OTHERS | BUS | 6 | 5 | 5 | 10 | 5 | 14 | 6 | 10 | 12 | 12 | 12 | 12 |  | 50 Ohms | TOP=L2:L3=L2/L4:L6=L5/L7:BOTTOM=L7 |
| BMC_SSD_RST#0_A14 | OTHERS | BUS | 7 | 5 | 5 | 10 | 5 | 14 | 6 | 10 | 12 | 12 | 12 | 12 |  | 50 Ohms | TOP=L2:L3=L2/L4:L6=L5/L7:BOTTOM=L7 |
| BMC_SSD_RST#0_A14 | OTHERS | BUS | 8 | 4.75 | 5 | 10 | 5 | 14 | 6 | 9.5 | 12 | 12 | 12 | 12 |  | 50 Ohms | TOP=L2:L3=L2/L4:L6=L5/L7:BOTTOM=L7 |
| BMC_SSD_RST#0_A2 | OTHERS | BUS | 1 | 4.75 | 5 | 10 | 5 | 14 | 6 | 9.5 | 12 | 12 | 12 | 12 |  | 50 Ohms | TOP=L2:L3=L2/L4:L6=L5/L7:BOTTOM=L7 |
| BMC_SSD_RST#0_A2 | OTHERS | BUS | 2 | 5 | 5 | 10 | 5 | 14 | 6 | 10 | 12 | 12 | 12 | 12 |  | 50 Ohms | TOP=L2:L3=L2/L4:L6=L5/L7:BOTTOM=L7 |
| BMC_SSD_RST#0_A2 | OTHERS | BUS | 3 | 5 | 5 | 10 | 5 | 14 | 6 | 10 | 12 | 12 | 12 | 12 |  | 50 Ohms | TOP=L2:L3=L2/L4:L6=L5/L7:BOTTOM=L7 |
| BMC_SSD_RST#0_A2 | OTHERS | BUS | 4 | 5 | 5 | 10 | 5 | 14 | 6 | 10 | 12 | 12 | 12 | 12 |  | 50 Ohms | TOP=L2:L3=L2/L4:L6=L5/L7:BOTTOM=L7 |
| BMC_SSD_RST#0_A2 | OTHERS | BUS | 5 | 5 | 5 | 10 | 5 | 14 | 6 | 10 | 12 | 12 | 12 | 12 |  | 50 Ohms | TOP=L2:L3=L2/L4:L6=L5/L7:BOTTOM=L7 |
| BMC_SSD_RST#0_A2 | OTHERS | BUS | 6 | 5 | 5 | 10 | 5 | 14 | 6 | 10 | 12 | 12 | 12 | 12 |  | 50 Ohms | TOP=L2:L3=L2/L4:L6=L5/L7:BOTTOM=L7 |
| BMC_SSD_RST#0_A2 | OTHERS | BUS | 7 | 5 | 5 | 10 | 5 | 14 | 6 | 10 | 12 | 12 | 12 | 12 |  | 50 Ohms | TOP=L2:L3=L2/L4:L6=L5/L7:BOTTOM=L7 |
| BMC_SSD_RST#0_A2 | OTHERS | BUS | 8 | 4.75 | 5 | 10 | 5 | 14 | 6 | 9.5 | 12 | 12 | 12 | 12 |  | 50 Ohms | TOP=L2:L3=L2/L4:L6=L5/L7:BOTTOM=L7 |
| BMC_SSD_RST#0_A3 | OTHERS | BUS | 1 | 4.75 | 5 | 10 | 5 | 14 | 6 | 9.5 | 12 | 12 | 12 | 12 |  | 50 Ohms | TOP=L2:L3=L2/L4:L6=L5/L7:BOTTOM=L7 |
| BMC_SSD_RST#0_A3 | OTHERS | BUS | 2 | 5 | 5 | 10 | 5 | 14 | 6 | 10 | 12 | 12 | 12 | 12 |  | 50 Ohms | TOP=L2:L3=L2/L4:L6=L5/L7:BOTTOM=L7 |
| BMC_SSD_RST#0_A3 | OTHERS | BUS | 3 | 5 | 5 | 10 | 5 | 14 | 6 | 10 | 12 | 12 | 12 | 12 |  | 50 Ohms | TOP=L2:L3=L2/L4:L6=L5/L7:BOTTOM=L7 |
| BMC_SSD_RST#0_A3 | OTHERS | BUS | 4 | 5 | 5 | 10 | 5 | 14 | 6 | 10 | 12 | 12 | 12 | 12 |  | 50 Ohms | TOP=L2:L3=L2/L4:L6=L5/L7:BOTTOM=L7 |
| BMC_SSD_RST#0_A3 | OTHERS | BUS | 5 | 5 | 5 | 10 | 5 | 14 | 6 | 10 | 12 | 12 | 12 | 12 |  | 50 Ohms | TOP=L2:L3=L2/L4:L6=L5/L7:BOTTOM=L7 |
| BMC_SSD_RST#0_A3 | OTHERS | BUS | 6 | 5 | 5 | 10 | 5 | 14 | 6 | 10 | 12 | 12 | 12 | 12 |  | 50 Ohms | TOP=L2:L3=L2/L4:L6=L5/L7:BOTTOM=L7 |
| BMC_SSD_RST#0_A3 | OTHERS | BUS | 7 | 5 | 5 | 10 | 5 | 14 | 6 | 10 | 12 | 12 | 12 | 12 |  | 50 Ohms | TOP=L2:L3=L2/L4:L6=L5/L7:BOTTOM=L7 |
| BMC_SSD_RST#0_A3 | OTHERS | BUS | 8 | 4.75 | 5 | 10 | 5 | 14 | 6 | 9.5 | 12 | 12 | 12 | 12 |  | 50 Ohms | TOP=L2:L3=L2/L4:L6=L5/L7:BOTTOM=L7 |
| BMC_SSD_RST#0_A4 | OTHERS | BUS | 1 | 4.75 | 5 | 10 | 5 | 14 | 6 | 9.5 | 12 | 12 | 12 | 12 |  | 50 Ohms | TOP=L2:L3=L2/L4:L6=L5/L7:BOTTOM=L7 |
| BMC_SSD_RST#0_A4 | OTHERS | BUS | 2 | 5 | 5 | 10 | 5 | 14 | 6 | 10 | 12 | 12 | 12 | 12 |  | 50 Ohms | TOP=L2:L3=L2/L4:L6=L5/L7:BOTTOM=L7 |
| BMC_SSD_RST#0_A4 | OTHERS | BUS | 3 | 5 | 5 | 10 | 5 | 14 | 6 | 10 | 12 | 12 | 12 | 12 |  | 50 Ohms | TOP=L2:L3=L2/L4:L6=L5/L7:BOTTOM=L7 |
| BMC_SSD_RST#0_A4 | OTHERS | BUS | 4 | 5 | 5 | 10 | 5 | 14 | 6 | 10 | 12 | 12 | 12 | 12 |  | 50 Ohms | TOP=L2:L3=L2/L4:L6=L5/L7:BOTTOM=L7 |
| BMC_SSD_RST#0_A4 | OTHERS | BUS | 5 | 5 | 5 | 10 | 5 | 14 | 6 | 10 | 12 | 12 | 12 | 12 |  | 50 Ohms | TOP=L2:L3=L2/L4:L6=L5/L7:BOTTOM=L7 |
| BMC_SSD_RST#0_A4 | OTHERS | BUS | 6 | 5 | 5 | 10 | 5 | 14 | 6 | 10 | 12 | 12 | 12 | 12 |  | 50 Ohms | TOP=L2:L3=L2/L4:L6=L5/L7:BOTTOM=L7 |
| BMC_SSD_RST#0_A4 | OTHERS | BUS | 7 | 5 | 5 | 10 | 5 | 14 | 6 | 10 | 12 | 12 | 12 | 12 |  | 50 Ohms | TOP=L2:L3=L2/L4:L6=L5/L7:BOTTOM=L7 |
| BMC_SSD_RST#0_A4 | OTHERS | BUS | 8 | 4.75 | 5 | 10 | 5 | 14 | 6 | 9.5 | 12 | 12 | 12 | 12 |  | 50 Ohms | TOP=L2:L3=L2/L4:L6=L5/L7:BOTTOM=L7 |
| BMC_SSD_RST#0_A5 | OTHERS | BUS | 1 | 4.75 | 5 | 10 | 5 | 14 | 6 | 9.5 | 12 | 12 | 12 | 12 |  | 50 Ohms | TOP=L2:L3=L2/L4:L6=L5/L7:BOTTOM=L7 |
| BMC_SSD_RST#0_A5 | OTHERS | BUS | 2 | 5 | 5 | 10 | 5 | 14 | 6 | 10 | 12 | 12 | 12 | 12 |  | 50 Ohms | TOP=L2:L3=L2/L4:L6=L5/L7:BOTTOM=L7 |
| BMC_SSD_RST#0_A5 | OTHERS | BUS | 3 | 5 | 5 | 10 | 5 | 14 | 6 | 10 | 12 | 12 | 12 | 12 |  | 50 Ohms | TOP=L2:L3=L2/L4:L6=L5/L7:BOTTOM=L7 |
| BMC_SSD_RST#0_A5 | OTHERS | BUS | 4 | 5 | 5 | 10 | 5 | 14 | 6 | 10 | 12 | 12 | 12 | 12 |  | 50 Ohms | TOP=L2:L3=L2/L4:L6=L5/L7:BOTTOM=L7 |
| BMC_SSD_RST#0_A5 | OTHERS | BUS | 5 | 5 | 5 | 10 | 5 | 14 | 6 | 10 | 12 | 12 | 12 | 12 |  | 50 Ohms | TOP=L2:L3=L2/L4:L6=L5/L7:BOTTOM=L7 |
| BMC_SSD_RST#0_A5 | OTHERS | BUS | 6 | 5 | 5 | 10 | 5 | 14 | 6 | 10 | 12 | 12 | 12 | 12 |  | 50 Ohms | TOP=L2:L3=L2/L4:L6=L5/L7:BOTTOM=L7 |
| BMC_SSD_RST#0_A5 | OTHERS | BUS | 7 | 5 | 5 | 10 | 5 | 14 | 6 | 10 | 12 | 12 | 12 | 12 |  | 50 Ohms | TOP=L2:L3=L2/L4:L6=L5/L7:BOTTOM=L7 |
| BMC_SSD_RST#0_A5 | OTHERS | BUS | 8 | 4.75 | 5 | 10 | 5 | 14 | 6 | 9.5 | 12 | 12 | 12 | 12 |  | 50 Ohms | TOP=L2:L3=L2/L4:L6=L5/L7:BOTTOM=L7 |
| BMC_SSD_RST#0_A6 | OTHERS | BUS | 1 | 4.75 | 5 | 10 | 5 | 14 | 6 | 9.5 | 12 | 12 | 12 | 12 |  | 50 Ohms | TOP=L2:L3=L2/L4:L6=L5/L7:BOTTOM=L7 |
| BMC_SSD_RST#0_A6 | OTHERS | BUS | 2 | 5 | 5 | 10 | 5 | 14 | 6 | 10 | 12 | 12 | 12 | 12 |  | 50 Ohms | TOP=L2:L3=L2/L4:L6=L5/L7:BOTTOM=L7 |
| BMC_SSD_RST#0_A6 | OTHERS | BUS | 3 | 5 | 5 | 10 | 5 | 14 | 6 | 10 | 12 | 12 | 12 | 12 |  | 50 Ohms | TOP=L2:L3=L2/L4:L6=L5/L7:BOTTOM=L7 |
| BMC_SSD_RST#0_A6 | OTHERS | BUS | 4 | 5 | 5 | 10 | 5 | 14 | 6 | 10 | 12 | 12 | 12 | 12 |  | 50 Ohms | TOP=L2:L3=L2/L4:L6=L5/L7:BOTTOM=L7 |
| BMC_SSD_RST#0_A6 | OTHERS | BUS | 5 | 5 | 5 | 10 | 5 | 14 | 6 | 10 | 12 | 12 | 12 | 12 |  | 50 Ohms | TOP=L2:L3=L2/L4:L6=L5/L7:BOTTOM=L7 |
| BMC_SSD_RST#0_A6 | OTHERS | BUS | 6 | 5 | 5 | 10 | 5 | 14 | 6 | 10 | 12 | 12 | 12 | 12 |  | 50 Ohms | TOP=L2:L3=L2/L4:L6=L5/L7:BOTTOM=L7 |
| BMC_SSD_RST#0_A6 | OTHERS | BUS | 7 | 5 | 5 | 10 | 5 | 14 | 6 | 10 | 12 | 12 | 12 | 12 |  | 50 Ohms | TOP=L2:L3=L2/L4:L6=L5/L7:BOTTOM=L7 |
| BMC_SSD_RST#0_A6 | OTHERS | BUS | 8 | 4.75 | 5 | 10 | 5 | 14 | 6 | 9.5 | 12 | 12 | 12 | 12 |  | 50 Ohms | TOP=L2:L3=L2/L4:L6=L5/L7:BOTTOM=L7 |
| BMC_SSD_RST#0_A7 | OTHERS | BUS | 1 | 4.75 | 5 | 10 | 5 | 14 | 6 | 9.5 | 12 | 12 | 12 | 12 |  | 50 Ohms | TOP=L2:L3=L2/L4:L6=L5/L7:BOTTOM=L7 |
| BMC_SSD_RST#0_A7 | OTHERS | BUS | 2 | 5 | 5 | 10 | 5 | 14 | 6 | 10 | 12 | 12 | 12 | 12 |  | 50 Ohms | TOP=L2:L3=L2/L4:L6=L5/L7:BOTTOM=L7 |
| BMC_SSD_RST#0_A7 | OTHERS | BUS | 3 | 5 | 5 | 10 | 5 | 14 | 6 | 10 | 12 | 12 | 12 | 12 |  | 50 Ohms | TOP=L2:L3=L2/L4:L6=L5/L7:BOTTOM=L7 |
| BMC_SSD_RST#0_A7 | OTHERS | BUS | 4 | 5 | 5 | 10 | 5 | 14 | 6 | 10 | 12 | 12 | 12 | 12 |  | 50 Ohms | TOP=L2:L3=L2/L4:L6=L5/L7:BOTTOM=L7 |
| BMC_SSD_RST#0_A7 | OTHERS | BUS | 5 | 5 | 5 | 10 | 5 | 14 | 6 | 10 | 12 | 12 | 12 | 12 |  | 50 Ohms | TOP=L2:L3=L2/L4:L6=L5/L7:BOTTOM=L7 |
| BMC_SSD_RST#0_A7 | OTHERS | BUS | 6 | 5 | 5 | 10 | 5 | 14 | 6 | 10 | 12 | 12 | 12 | 12 |  | 50 Ohms | TOP=L2:L3=L2/L4:L6=L5/L7:BOTTOM=L7 |
| BMC_SSD_RST#0_A7 | OTHERS | BUS | 7 | 5 | 5 | 10 | 5 | 14 | 6 | 10 | 12 | 12 | 12 | 12 |  | 50 Ohms | TOP=L2:L3=L2/L4:L6=L5/L7:BOTTOM=L7 |
| BMC_SSD_RST#0_A7 | OTHERS | BUS | 8 | 4.75 | 5 | 10 | 5 | 14 | 6 | 9.5 | 12 | 12 | 12 | 12 |  | 50 Ohms | TOP=L2:L3=L2/L4:L6=L5/L7:BOTTOM=L7 |
| BMC_SSD_RST#0_A8 | OTHERS | BUS | 1 | 4.75 | 5 | 10 | 5 | 14 | 6 | 9.5 | 12 | 12 | 12 | 12 |  | 50 Ohms | TOP=L2:L3=L2/L4:L6=L5/L7:BOTTOM=L7 |
| BMC_SSD_RST#0_A8 | OTHERS | BUS | 2 | 5 | 5 | 10 | 5 | 14 | 6 | 10 | 12 | 12 | 12 | 12 |  | 50 Ohms | TOP=L2:L3=L2/L4:L6=L5/L7:BOTTOM=L7 |
| BMC_SSD_RST#0_A8 | OTHERS | BUS | 3 | 5 | 5 | 10 | 5 | 14 | 6 | 10 | 12 | 12 | 12 | 12 |  | 50 Ohms | TOP=L2:L3=L2/L4:L6=L5/L7:BOTTOM=L7 |
| BMC_SSD_RST#0_A8 | OTHERS | BUS | 4 | 5 | 5 | 10 | 5 | 14 | 6 | 10 | 12 | 12 | 12 | 12 |  | 50 Ohms | TOP=L2:L3=L2/L4:L6=L5/L7:BOTTOM=L7 |
| BMC_SSD_RST#0_A8 | OTHERS | BUS | 5 | 5 | 5 | 10 | 5 | 14 | 6 | 10 | 12 | 12 | 12 | 12 |  | 50 Ohms | TOP=L2:L3=L2/L4:L6=L5/L7:BOTTOM=L7 |
| BMC_SSD_RST#0_A8 | OTHERS | BUS | 6 | 5 | 5 | 10 | 5 | 14 | 6 | 10 | 12 | 12 | 12 | 12 |  | 50 Ohms | TOP=L2:L3=L2/L4:L6=L5/L7:BOTTOM=L7 |
| BMC_SSD_RST#0_A8 | OTHERS | BUS | 7 | 5 | 5 | 10 | 5 | 14 | 6 | 10 | 12 | 12 | 12 | 12 |  | 50 Ohms | TOP=L2:L3=L2/L4:L6=L5/L7:BOTTOM=L7 |
| BMC_SSD_RST#0_A8 | OTHERS | BUS | 8 | 4.75 | 5 | 10 | 5 | 14 | 6 | 9.5 | 12 | 12 | 12 | 12 |  | 50 Ohms | TOP=L2:L3=L2/L4:L6=L5/L7:BOTTOM=L7 |
| BMC_SSD_RST#0_A9 | OTHERS | BUS | 1 | 4.75 | 5 | 10 | 5 | 14 | 6 | 9.5 | 12 | 12 | 12 | 12 |  | 50 Ohms | TOP=L2:L3=L2/L4:L6=L5/L7:BOTTOM=L7 |
| BMC_SSD_RST#0_A9 | OTHERS | BUS | 2 | 5 | 5 | 10 | 5 | 14 | 6 | 10 | 12 | 12 | 12 | 12 |  | 50 Ohms | TOP=L2:L3=L2/L4:L6=L5/L7:BOTTOM=L7 |
| BMC_SSD_RST#0_A9 | OTHERS | BUS | 3 | 5 | 5 | 10 | 5 | 14 | 6 | 10 | 12 | 12 | 12 | 12 |  | 50 Ohms | TOP=L2:L3=L2/L4:L6=L5/L7:BOTTOM=L7 |
| BMC_SSD_RST#0_A9 | OTHERS | BUS | 4 | 5 | 5 | 10 | 5 | 14 | 6 | 10 | 12 | 12 | 12 | 12 |  | 50 Ohms | TOP=L2:L3=L2/L4:L6=L5/L7:BOTTOM=L7 |
| BMC_SSD_RST#0_A9 | OTHERS | BUS | 5 | 5 | 5 | 10 | 5 | 14 | 6 | 10 | 12 | 12 | 12 | 12 |  | 50 Ohms | TOP=L2:L3=L2/L4:L6=L5/L7:BOTTOM=L7 |
| BMC_SSD_RST#0_A9 | OTHERS | BUS | 6 | 5 | 5 | 10 | 5 | 14 | 6 | 10 | 12 | 12 | 12 | 12 |  | 50 Ohms | TOP=L2:L3=L2/L4:L6=L5/L7:BOTTOM=L7 |
| BMC_SSD_RST#0_A9 | OTHERS | BUS | 7 | 5 | 5 | 10 | 5 | 14 | 6 | 10 | 12 | 12 | 12 | 12 |  | 50 Ohms | TOP=L2:L3=L2/L4:L6=L5/L7:BOTTOM=L7 |
| BMC_SSD_RST#0_A9 | OTHERS | BUS | 8 | 4.75 | 5 | 10 | 5 | 14 | 6 | 9.5 | 12 | 12 | 12 | 12 |  | 50 Ohms | TOP=L2:L3=L2/L4:L6=L5/L7:BOTTOM=L7 |
| BMC_SSD_RST#1 | OTHERS | BUS | 1 | 4.75 | 5 | 10 | 5 | 14 | 6 | 9.5 | 12 | 12 | 12 | 12 |  | 50 Ohms | TOP=L2:L3=L2/L4:L6=L5/L7:BOTTOM=L7 |
| BMC_SSD_RST#1 | OTHERS | BUS | 2 | 5 | 5 | 10 | 5 | 14 | 6 | 10 | 12 | 12 | 12 | 12 |  | 50 Ohms | TOP=L2:L3=L2/L4:L6=L5/L7:BOTTOM=L7 |
| BMC_SSD_RST#1 | OTHERS | BUS | 3 | 5 | 5 | 10 | 5 | 14 | 6 | 10 | 12 | 12 | 12 | 12 |  | 50 Ohms | TOP=L2:L3=L2/L4:L6=L5/L7:BOTTOM=L7 |
| BMC_SSD_RST#1 | OTHERS | BUS | 4 | 5 | 5 | 10 | 5 | 14 | 6 | 10 | 12 | 12 | 12 | 12 |  | 50 Ohms | TOP=L2:L3=L2/L4:L6=L5/L7:BOTTOM=L7 |
| BMC_SSD_RST#1 | OTHERS | BUS | 5 | 5 | 5 | 10 | 5 | 14 | 6 | 10 | 12 | 12 | 12 | 12 |  | 50 Ohms | TOP=L2:L3=L2/L4:L6=L5/L7:BOTTOM=L7 |
| BMC_SSD_RST#1 | OTHERS | BUS | 6 | 5 | 5 | 10 | 5 | 14 | 6 | 10 | 12 | 12 | 12 | 12 |  | 50 Ohms | TOP=L2:L3=L2/L4:L6=L5/L7:BOTTOM=L7 |
| BMC_SSD_RST#1 | OTHERS | BUS | 7 | 5 | 5 | 10 | 5 | 14 | 6 | 10 | 12 | 12 | 12 | 12 |  | 50 Ohms | TOP=L2:L3=L2/L4:L6=L5/L7:BOTTOM=L7 |
| BMC_SSD_RST#1 | OTHERS | BUS | 8 | 4.75 | 5 | 10 | 5 | 14 | 6 | 9.5 | 12 | 12 | 12 | 12 |  | 50 Ohms | TOP=L2:L3=L2/L4:L6=L5/L7:BOTTOM=L7 |
| BMC_SSD_RST#10 | OTHERS | BUS | 1 | 4.75 | 5 | 10 | 5 | 14 | 6 | 9.5 | 12 | 12 | 12 | 12 |  | 50 Ohms | TOP=L2:L3=L2/L4:L6=L5/L7:BOTTOM=L7 |
| BMC_SSD_RST#10 | OTHERS | BUS | 2 | 5 | 5 | 10 | 5 | 14 | 6 | 10 | 12 | 12 | 12 | 12 |  | 50 Ohms | TOP=L2:L3=L2/L4:L6=L5/L7:BOTTOM=L7 |
| BMC_SSD_RST#10 | OTHERS | BUS | 3 | 5 | 5 | 10 | 5 | 14 | 6 | 10 | 12 | 12 | 12 | 12 |  | 50 Ohms | TOP=L2:L3=L2/L4:L6=L5/L7:BOTTOM=L7 |
| BMC_SSD_RST#10 | OTHERS | BUS | 4 | 5 | 5 | 10 | 5 | 14 | 6 | 10 | 12 | 12 | 12 | 12 |  | 50 Ohms | TOP=L2:L3=L2/L4:L6=L5/L7:BOTTOM=L7 |
| BMC_SSD_RST#10 | OTHERS | BUS | 5 | 5 | 5 | 10 | 5 | 14 | 6 | 10 | 12 | 12 | 12 | 12 |  | 50 Ohms | TOP=L2:L3=L2/L4:L6=L5/L7:BOTTOM=L7 |
| BMC_SSD_RST#10 | OTHERS | BUS | 6 | 5 | 5 | 10 | 5 | 14 | 6 | 10 | 12 | 12 | 12 | 12 |  | 50 Ohms | TOP=L2:L3=L2/L4:L6=L5/L7:BOTTOM=L7 |
| BMC_SSD_RST#10 | OTHERS | BUS | 7 | 5 | 5 | 10 | 5 | 14 | 6 | 10 | 12 | 12 | 12 | 12 |  | 50 Ohms | TOP=L2:L3=L2/L4:L6=L5/L7:BOTTOM=L7 |
| BMC_SSD_RST#10 | OTHERS | BUS | 8 | 4.75 | 5 | 10 | 5 | 14 | 6 | 9.5 | 12 | 12 | 12 | 12 |  | 50 Ohms | TOP=L2:L3=L2/L4:L6=L5/L7:BOTTOM=L7 |
| BMC_SSD_RST#11 | OTHERS | BUS | 1 | 4.75 | 5 | 10 | 5 | 14 | 6 | 9.5 | 12 | 12 | 12 | 12 |  | 50 Ohms | TOP=L2:L3=L2/L4:L6=L5/L7:BOTTOM=L7 |
| BMC_SSD_RST#11 | OTHERS | BUS | 2 | 5 | 5 | 10 | 5 | 14 | 6 | 10 | 12 | 12 | 12 | 12 |  | 50 Ohms | TOP=L2:L3=L2/L4:L6=L5/L7:BOTTOM=L7 |
| BMC_SSD_RST#11 | OTHERS | BUS | 3 | 5 | 5 | 10 | 5 | 14 | 6 | 10 | 12 | 12 | 12 | 12 |  | 50 Ohms | TOP=L2:L3=L2/L4:L6=L5/L7:BOTTOM=L7 |
| BMC_SSD_RST#11 | OTHERS | BUS | 4 | 5 | 5 | 10 | 5 | 14 | 6 | 10 | 12 | 12 | 12 | 12 |  | 50 Ohms | TOP=L2:L3=L2/L4:L6=L5/L7:BOTTOM=L7 |
| BMC_SSD_RST#11 | OTHERS | BUS | 5 | 5 | 5 | 10 | 5 | 14 | 6 | 10 | 12 | 12 | 12 | 12 |  | 50 Ohms | TOP=L2:L3=L2/L4:L6=L5/L7:BOTTOM=L7 |
| BMC_SSD_RST#11 | OTHERS | BUS | 6 | 5 | 5 | 10 | 5 | 14 | 6 | 10 | 12 | 12 | 12 | 12 |  | 50 Ohms | TOP=L2:L3=L2/L4:L6=L5/L7:BOTTOM=L7 |
| BMC_SSD_RST#11 | OTHERS | BUS | 7 | 5 | 5 | 10 | 5 | 14 | 6 | 10 | 12 | 12 | 12 | 12 |  | 50 Ohms | TOP=L2:L3=L2/L4:L6=L5/L7:BOTTOM=L7 |
| BMC_SSD_RST#11 | OTHERS | BUS | 8 | 4.75 | 5 | 10 | 5 | 14 | 6 | 9.5 | 12 | 12 | 12 | 12 |  | 50 Ohms | TOP=L2:L3=L2/L4:L6=L5/L7:BOTTOM=L7 |
| BMC_SSD_RST#12 | OTHERS | BUS | 1 | 4.75 | 5 | 10 | 5 | 14 | 6 | 9.5 | 12 | 12 | 12 | 12 |  | 50 Ohms | TOP=L2:L3=L2/L4:L6=L5/L7:BOTTOM=L7 |
| BMC_SSD_RST#12 | OTHERS | BUS | 2 | 5 | 5 | 10 | 5 | 14 | 6 | 10 | 12 | 12 | 12 | 12 |  | 50 Ohms | TOP=L2:L3=L2/L4:L6=L5/L7:BOTTOM=L7 |
| BMC_SSD_RST#12 | OTHERS | BUS | 3 | 5 | 5 | 10 | 5 | 14 | 6 | 10 | 12 | 12 | 12 | 12 |  | 50 Ohms | TOP=L2:L3=L2/L4:L6=L5/L7:BOTTOM=L7 |
| BMC_SSD_RST#12 | OTHERS | BUS | 4 | 5 | 5 | 10 | 5 | 14 | 6 | 10 | 12 | 12 | 12 | 12 |  | 50 Ohms | TOP=L2:L3=L2/L4:L6=L5/L7:BOTTOM=L7 |
| BMC_SSD_RST#12 | OTHERS | BUS | 5 | 5 | 5 | 10 | 5 | 14 | 6 | 10 | 12 | 12 | 12 | 12 |  | 50 Ohms | TOP=L2:L3=L2/L4:L6=L5/L7:BOTTOM=L7 |
| BMC_SSD_RST#12 | OTHERS | BUS | 6 | 5 | 5 | 10 | 5 | 14 | 6 | 10 | 12 | 12 | 12 | 12 |  | 50 Ohms | TOP=L2:L3=L2/L4:L6=L5/L7:BOTTOM=L7 |
| BMC_SSD_RST#12 | OTHERS | BUS | 7 | 5 | 5 | 10 | 5 | 14 | 6 | 10 | 12 | 12 | 12 | 12 |  | 50 Ohms | TOP=L2:L3=L2/L4:L6=L5/L7:BOTTOM=L7 |
| BMC_SSD_RST#12 | OTHERS | BUS | 8 | 4.75 | 5 | 10 | 5 | 14 | 6 | 9.5 | 12 | 12 | 12 | 12 |  | 50 Ohms | TOP=L2:L3=L2/L4:L6=L5/L7:BOTTOM=L7 |
| BMC_SSD_RST#13 | OTHERS | BUS | 1 | 4.75 | 5 | 10 | 5 | 14 | 6 | 9.5 | 12 | 12 | 12 | 12 |  | 50 Ohms | TOP=L2:L3=L2/L4:L6=L5/L7:BOTTOM=L7 |
| BMC_SSD_RST#13 | OTHERS | BUS | 2 | 5 | 5 | 10 | 5 | 14 | 6 | 10 | 12 | 12 | 12 | 12 |  | 50 Ohms | TOP=L2:L3=L2/L4:L6=L5/L7:BOTTOM=L7 |
| BMC_SSD_RST#13 | OTHERS | BUS | 3 | 5 | 5 | 10 | 5 | 14 | 6 | 10 | 12 | 12 | 12 | 12 |  | 50 Ohms | TOP=L2:L3=L2/L4:L6=L5/L7:BOTTOM=L7 |
| BMC_SSD_RST#13 | OTHERS | BUS | 4 | 5 | 5 | 10 | 5 | 14 | 6 | 10 | 12 | 12 | 12 | 12 |  | 50 Ohms | TOP=L2:L3=L2/L4:L6=L5/L7:BOTTOM=L7 |
| BMC_SSD_RST#13 | OTHERS | BUS | 5 | 5 | 5 | 10 | 5 | 14 | 6 | 10 | 12 | 12 | 12 | 12 |  | 50 Ohms | TOP=L2:L3=L2/L4:L6=L5/L7:BOTTOM=L7 |
| BMC_SSD_RST#13 | OTHERS | BUS | 6 | 5 | 5 | 10 | 5 | 14 | 6 | 10 | 12 | 12 | 12 | 12 |  | 50 Ohms | TOP=L2:L3=L2/L4:L6=L5/L7:BOTTOM=L7 |
| BMC_SSD_RST#13 | OTHERS | BUS | 7 | 5 | 5 | 10 | 5 | 14 | 6 | 10 | 12 | 12 | 12 | 12 |  | 50 Ohms | TOP=L2:L3=L2/L4:L6=L5/L7:BOTTOM=L7 |
| BMC_SSD_RST#13 | OTHERS | BUS | 8 | 4.75 | 5 | 10 | 5 | 14 | 6 | 9.5 | 12 | 12 | 12 | 12 |  | 50 Ohms | TOP=L2:L3=L2/L4:L6=L5/L7:BOTTOM=L7 |
| BMC_SSD_RST#14 | OTHERS | BUS | 1 | 4.75 | 5 | 10 | 5 | 14 | 6 | 9.5 | 12 | 12 | 12 | 12 |  | 50 Ohms | TOP=L2:L3=L2/L4:L6=L5/L7:BOTTOM=L7 |
| BMC_SSD_RST#14 | OTHERS | BUS | 2 | 5 | 5 | 10 | 5 | 14 | 6 | 10 | 12 | 12 | 12 | 12 |  | 50 Ohms | TOP=L2:L3=L2/L4:L6=L5/L7:BOTTOM=L7 |
| BMC_SSD_RST#14 | OTHERS | BUS | 3 | 5 | 5 | 10 | 5 | 14 | 6 | 10 | 12 | 12 | 12 | 12 |  | 50 Ohms | TOP=L2:L3=L2/L4:L6=L5/L7:BOTTOM=L7 |
| BMC_SSD_RST#14 | OTHERS | BUS | 4 | 5 | 5 | 10 | 5 | 14 | 6 | 10 | 12 | 12 | 12 | 12 |  | 50 Ohms | TOP=L2:L3=L2/L4:L6=L5/L7:BOTTOM=L7 |
| BMC_SSD_RST#14 | OTHERS | BUS | 5 | 5 | 5 | 10 | 5 | 14 | 6 | 10 | 12 | 12 | 12 | 12 |  | 50 Ohms | TOP=L2:L3=L2/L4:L6=L5/L7:BOTTOM=L7 |
| BMC_SSD_RST#14 | OTHERS | BUS | 6 | 5 | 5 | 10 | 5 | 14 | 6 | 10 | 12 | 12 | 12 | 12 |  | 50 Ohms | TOP=L2:L3=L2/L4:L6=L5/L7:BOTTOM=L7 |
| BMC_SSD_RST#14 | OTHERS | BUS | 7 | 5 | 5 | 10 | 5 | 14 | 6 | 10 | 12 | 12 | 12 | 12 |  | 50 Ohms | TOP=L2:L3=L2/L4:L6=L5/L7:BOTTOM=L7 |
| BMC_SSD_RST#14 | OTHERS | BUS | 8 | 4.75 | 5 | 10 | 5 | 14 | 6 | 9.5 | 12 | 12 | 12 | 12 |  | 50 Ohms | TOP=L2:L3=L2/L4:L6=L5/L7:BOTTOM=L7 |
| BMC_SSD_RST#2 | OTHERS | BUS | 1 | 4.75 | 5 | 10 | 5 | 14 | 6 | 9.5 | 12 | 12 | 12 | 12 |  | 50 Ohms | TOP=L2:L3=L2/L4:L6=L5/L7:BOTTOM=L7 |
| BMC_SSD_RST#2 | OTHERS | BUS | 2 | 5 | 5 | 10 | 5 | 14 | 6 | 10 | 12 | 12 | 12 | 12 |  | 50 Ohms | TOP=L2:L3=L2/L4:L6=L5/L7:BOTTOM=L7 |
| BMC_SSD_RST#2 | OTHERS | BUS | 3 | 5 | 5 | 10 | 5 | 14 | 6 | 10 | 12 | 12 | 12 | 12 |  | 50 Ohms | TOP=L2:L3=L2/L4:L6=L5/L7:BOTTOM=L7 |
| BMC_SSD_RST#2 | OTHERS | BUS | 4 | 5 | 5 | 10 | 5 | 14 | 6 | 10 | 12 | 12 | 12 | 12 |  | 50 Ohms | TOP=L2:L3=L2/L4:L6=L5/L7:BOTTOM=L7 |
| BMC_SSD_RST#2 | OTHERS | BUS | 5 | 5 | 5 | 10 | 5 | 14 | 6 | 10 | 12 | 12 | 12 | 12 |  | 50 Ohms | TOP=L2:L3=L2/L4:L6=L5/L7:BOTTOM=L7 |
| BMC_SSD_RST#2 | OTHERS | BUS | 6 | 5 | 5 | 10 | 5 | 14 | 6 | 10 | 12 | 12 | 12 | 12 |  | 50 Ohms | TOP=L2:L3=L2/L4:L6=L5/L7:BOTTOM=L7 |
| BMC_SSD_RST#2 | OTHERS | BUS | 7 | 5 | 5 | 10 | 5 | 14 | 6 | 10 | 12 | 12 | 12 | 12 |  | 50 Ohms | TOP=L2:L3=L2/L4:L6=L5/L7:BOTTOM=L7 |
| BMC_SSD_RST#2 | OTHERS | BUS | 8 | 4.75 | 5 | 10 | 5 | 14 | 6 | 9.5 | 12 | 12 | 12 | 12 |  | 50 Ohms | TOP=L2:L3=L2/L4:L6=L5/L7:BOTTOM=L7 |
| BMC_SSD_RST#3 | OTHERS | BUS | 1 | 4.75 | 5 | 10 | 5 | 14 | 6 | 9.5 | 12 | 12 | 12 | 12 |  | 50 Ohms | TOP=L2:L3=L2/L4:L6=L5/L7:BOTTOM=L7 |
| BMC_SSD_RST#3 | OTHERS | BUS | 2 | 5 | 5 | 10 | 5 | 14 | 6 | 10 | 12 | 12 | 12 | 12 |  | 50 Ohms | TOP=L2:L3=L2/L4:L6=L5/L7:BOTTOM=L7 |
| BMC_SSD_RST#3 | OTHERS | BUS | 3 | 5 | 5 | 10 | 5 | 14 | 6 | 10 | 12 | 12 | 12 | 12 |  | 50 Ohms | TOP=L2:L3=L2/L4:L6=L5/L7:BOTTOM=L7 |
| BMC_SSD_RST#3 | OTHERS | BUS | 4 | 5 | 5 | 10 | 5 | 14 | 6 | 10 | 12 | 12 | 12 | 12 |  | 50 Ohms | TOP=L2:L3=L2/L4:L6=L5/L7:BOTTOM=L7 |
| BMC_SSD_RST#3 | OTHERS | BUS | 5 | 5 | 5 | 10 | 5 | 14 | 6 | 10 | 12 | 12 | 12 | 12 |  | 50 Ohms | TOP=L2:L3=L2/L4:L6=L5/L7:BOTTOM=L7 |
| BMC_SSD_RST#3 | OTHERS | BUS | 6 | 5 | 5 | 10 | 5 | 14 | 6 | 10 | 12 | 12 | 12 | 12 |  | 50 Ohms | TOP=L2:L3=L2/L4:L6=L5/L7:BOTTOM=L7 |
| BMC_SSD_RST#3 | OTHERS | BUS | 7 | 5 | 5 | 10 | 5 | 14 | 6 | 10 | 12 | 12 | 12 | 12 |  | 50 Ohms | TOP=L2:L3=L2/L4:L6=L5/L7:BOTTOM=L7 |
| BMC_SSD_RST#3 | OTHERS | BUS | 8 | 4.75 | 5 | 10 | 5 | 14 | 6 | 9.5 | 12 | 12 | 12 | 12 |  | 50 Ohms | TOP=L2:L3=L2/L4:L6=L5/L7:BOTTOM=L7 |
| BMC_SSD_RST#4 | OTHERS | BUS | 1 | 4.75 | 5 | 10 | 5 | 14 | 6 | 9.5 | 12 | 12 | 12 | 12 |  | 50 Ohms | TOP=L2:L3=L2/L4:L6=L5/L7:BOTTOM=L7 |
| BMC_SSD_RST#4 | OTHERS | BUS | 2 | 5 | 5 | 10 | 5 | 14 | 6 | 10 | 12 | 12 | 12 | 12 |  | 50 Ohms | TOP=L2:L3=L2/L4:L6=L5/L7:BOTTOM=L7 |
| BMC_SSD_RST#4 | OTHERS | BUS | 3 | 5 | 5 | 10 | 5 | 14 | 6 | 10 | 12 | 12 | 12 | 12 |  | 50 Ohms | TOP=L2:L3=L2/L4:L6=L5/L7:BOTTOM=L7 |
| BMC_SSD_RST#4 | OTHERS | BUS | 4 | 5 | 5 | 10 | 5 | 14 | 6 | 10 | 12 | 12 | 12 | 12 |  | 50 Ohms | TOP=L2:L3=L2/L4:L6=L5/L7:BOTTOM=L7 |
| BMC_SSD_RST#4 | OTHERS | BUS | 5 | 5 | 5 | 10 | 5 | 14 | 6 | 10 | 12 | 12 | 12 | 12 |  | 50 Ohms | TOP=L2:L3=L2/L4:L6=L5/L7:BOTTOM=L7 |
| BMC_SSD_RST#4 | OTHERS | BUS | 6 | 5 | 5 | 10 | 5 | 14 | 6 | 10 | 12 | 12 | 12 | 12 |  | 50 Ohms | TOP=L2:L3=L2/L4:L6=L5/L7:BOTTOM=L7 |
| BMC_SSD_RST#4 | OTHERS | BUS | 7 | 5 | 5 | 10 | 5 | 14 | 6 | 10 | 12 | 12 | 12 | 12 |  | 50 Ohms | TOP=L2:L3=L2/L4:L6=L5/L7:BOTTOM=L7 |
| BMC_SSD_RST#4 | OTHERS | BUS | 8 | 4.75 | 5 | 10 | 5 | 14 | 6 | 9.5 | 12 | 12 | 12 | 12 |  | 50 Ohms | TOP=L2:L3=L2/L4:L6=L5/L7:BOTTOM=L7 |
| BMC_SSD_RST#5 | OTHERS | BUS | 1 | 4.75 | 5 | 10 | 5 | 14 | 6 | 9.5 | 12 | 12 | 12 | 12 |  | 50 Ohms | TOP=L2:L3=L2/L4:L6=L5/L7:BOTTOM=L7 |
| BMC_SSD_RST#5 | OTHERS | BUS | 2 | 5 | 5 | 10 | 5 | 14 | 6 | 10 | 12 | 12 | 12 | 12 |  | 50 Ohms | TOP=L2:L3=L2/L4:L6=L5/L7:BOTTOM=L7 |
| BMC_SSD_RST#5 | OTHERS | BUS | 3 | 5 | 5 | 10 | 5 | 14 | 6 | 10 | 12 | 12 | 12 | 12 |  | 50 Ohms | TOP=L2:L3=L2/L4:L6=L5/L7:BOTTOM=L7 |
| BMC_SSD_RST#5 | OTHERS | BUS | 4 | 5 | 5 | 10 | 5 | 14 | 6 | 10 | 12 | 12 | 12 | 12 |  | 50 Ohms | TOP=L2:L3=L2/L4:L6=L5/L7:BOTTOM=L7 |
| BMC_SSD_RST#5 | OTHERS | BUS | 5 | 5 | 5 | 10 | 5 | 14 | 6 | 10 | 12 | 12 | 12 | 12 |  | 50 Ohms | TOP=L2:L3=L2/L4:L6=L5/L7:BOTTOM=L7 |
| BMC_SSD_RST#5 | OTHERS | BUS | 6 | 5 | 5 | 10 | 5 | 14 | 6 | 10 | 12 | 12 | 12 | 12 |  | 50 Ohms | TOP=L2:L3=L2/L4:L6=L5/L7:BOTTOM=L7 |
| BMC_SSD_RST#5 | OTHERS | BUS | 7 | 5 | 5 | 10 | 5 | 14 | 6 | 10 | 12 | 12 | 12 | 12 |  | 50 Ohms | TOP=L2:L3=L2/L4:L6=L5/L7:BOTTOM=L7 |
| BMC_SSD_RST#5 | OTHERS | BUS | 8 | 4.75 | 5 | 10 | 5 | 14 | 6 | 9.5 | 12 | 12 | 12 | 12 |  | 50 Ohms | TOP=L2:L3=L2/L4:L6=L5/L7:BOTTOM=L7 |
| BMC_SSD_RST#6 | OTHERS | BUS | 1 | 4.75 | 5 | 10 | 5 | 14 | 6 | 9.5 | 12 | 12 | 12 | 12 |  | 50 Ohms | TOP=L2:L3=L2/L4:L6=L5/L7:BOTTOM=L7 |
| BMC_SSD_RST#6 | OTHERS | BUS | 2 | 5 | 5 | 10 | 5 | 14 | 6 | 10 | 12 | 12 | 12 | 12 |  | 50 Ohms | TOP=L2:L3=L2/L4:L6=L5/L7:BOTTOM=L7 |
| BMC_SSD_RST#6 | OTHERS | BUS | 3 | 5 | 5 | 10 | 5 | 14 | 6 | 10 | 12 | 12 | 12 | 12 |  | 50 Ohms | TOP=L2:L3=L2/L4:L6=L5/L7:BOTTOM=L7 |
| BMC_SSD_RST#6 | OTHERS | BUS | 4 | 5 | 5 | 10 | 5 | 14 | 6 | 10 | 12 | 12 | 12 | 12 |  | 50 Ohms | TOP=L2:L3=L2/L4:L6=L5/L7:BOTTOM=L7 |
| BMC_SSD_RST#6 | OTHERS | BUS | 5 | 5 | 5 | 10 | 5 | 14 | 6 | 10 | 12 | 12 | 12 | 12 |  | 50 Ohms | TOP=L2:L3=L2/L4:L6=L5/L7:BOTTOM=L7 |
| BMC_SSD_RST#6 | OTHERS | BUS | 6 | 5 | 5 | 10 | 5 | 14 | 6 | 10 | 12 | 12 | 12 | 12 |  | 50 Ohms | TOP=L2:L3=L2/L4:L6=L5/L7:BOTTOM=L7 |
| BMC_SSD_RST#6 | OTHERS | BUS | 7 | 5 | 5 | 10 | 5 | 14 | 6 | 10 | 12 | 12 | 12 | 12 |  | 50 Ohms | TOP=L2:L3=L2/L4:L6=L5/L7:BOTTOM=L7 |
| BMC_SSD_RST#6 | OTHERS | BUS | 8 | 4.75 | 5 | 10 | 5 | 14 | 6 | 9.5 | 12 | 12 | 12 | 12 |  | 50 Ohms | TOP=L2:L3=L2/L4:L6=L5/L7:BOTTOM=L7 |
| BMC_SSD_RST#7 | OTHERS | BUS | 1 | 4.75 | 5 | 10 | 5 | 14 | 6 | 9.5 | 12 | 12 | 12 | 12 |  | 50 Ohms | TOP=L2:L3=L2/L4:L6=L5/L7:BOTTOM=L7 |
| BMC_SSD_RST#7 | OTHERS | BUS | 2 | 5 | 5 | 10 | 5 | 14 | 6 | 10 | 12 | 12 | 12 | 12 |  | 50 Ohms | TOP=L2:L3=L2/L4:L6=L5/L7:BOTTOM=L7 |
| BMC_SSD_RST#7 | OTHERS | BUS | 3 | 5 | 5 | 10 | 5 | 14 | 6 | 10 | 12 | 12 | 12 | 12 |  | 50 Ohms | TOP=L2:L3=L2/L4:L6=L5/L7:BOTTOM=L7 |
| BMC_SSD_RST#7 | OTHERS | BUS | 4 | 5 | 5 | 10 | 5 | 14 | 6 | 10 | 12 | 12 | 12 | 12 |  | 50 Ohms | TOP=L2:L3=L2/L4:L6=L5/L7:BOTTOM=L7 |
| BMC_SSD_RST#7 | OTHERS | BUS | 5 | 5 | 5 | 10 | 5 | 14 | 6 | 10 | 12 | 12 | 12 | 12 |  | 50 Ohms | TOP=L2:L3=L2/L4:L6=L5/L7:BOTTOM=L7 |
| BMC_SSD_RST#7 | OTHERS | BUS | 6 | 5 | 5 | 10 | 5 | 14 | 6 | 10 | 12 | 12 | 12 | 12 |  | 50 Ohms | TOP=L2:L3=L2/L4:L6=L5/L7:BOTTOM=L7 |
| BMC_SSD_RST#7 | OTHERS | BUS | 7 | 5 | 5 | 10 | 5 | 14 | 6 | 10 | 12 | 12 | 12 | 12 |  | 50 Ohms | TOP=L2:L3=L2/L4:L6=L5/L7:BOTTOM=L7 |
| BMC_SSD_RST#7 | OTHERS | BUS | 8 | 4.75 | 5 | 10 | 5 | 14 | 6 | 9.5 | 12 | 12 | 12 | 12 |  | 50 Ohms | TOP=L2:L3=L2/L4:L6=L5/L7:BOTTOM=L7 |
| BMC_SSD_RST#8 | OTHERS | BUS | 1 | 4.75 | 5 | 10 | 5 | 14 | 6 | 9.5 | 12 | 12 | 12 | 12 |  | 50 Ohms | TOP=L2:L3=L2/L4:L6=L5/L7:BOTTOM=L7 |
| BMC_SSD_RST#8 | OTHERS | BUS | 2 | 5 | 5 | 10 | 5 | 14 | 6 | 10 | 12 | 12 | 12 | 12 |  | 50 Ohms | TOP=L2:L3=L2/L4:L6=L5/L7:BOTTOM=L7 |
| BMC_SSD_RST#8 | OTHERS | BUS | 3 | 5 | 5 | 10 | 5 | 14 | 6 | 10 | 12 | 12 | 12 | 12 |  | 50 Ohms | TOP=L2:L3=L2/L4:L6=L5/L7:BOTTOM=L7 |
| BMC_SSD_RST#8 | OTHERS | BUS | 4 | 5 | 5 | 10 | 5 | 14 | 6 | 10 | 12 | 12 | 12 | 12 |  | 50 Ohms | TOP=L2:L3=L2/L4:L6=L5/L7:BOTTOM=L7 |
| BMC_SSD_RST#8 | OTHERS | BUS | 5 | 5 | 5 | 10 | 5 | 14 | 6 | 10 | 12 | 12 | 12 | 12 |  | 50 Ohms | TOP=L2:L3=L2/L4:L6=L5/L7:BOTTOM=L7 |
| BMC_SSD_RST#8 | OTHERS | BUS | 6 | 5 | 5 | 10 | 5 | 14 | 6 | 10 | 12 | 12 | 12 | 12 |  | 50 Ohms | TOP=L2:L3=L2/L4:L6=L5/L7:BOTTOM=L7 |
| BMC_SSD_RST#8 | OTHERS | BUS | 7 | 5 | 5 | 10 | 5 | 14 | 6 | 10 | 12 | 12 | 12 | 12 |  | 50 Ohms | TOP=L2:L3=L2/L4:L6=L5/L7:BOTTOM=L7 |
| BMC_SSD_RST#8 | OTHERS | BUS | 8 | 4.75 | 5 | 10 | 5 | 14 | 6 | 9.5 | 12 | 12 | 12 | 12 |  | 50 Ohms | TOP=L2:L3=L2/L4:L6=L5/L7:BOTTOM=L7 |
| BMC_SSD_RST#9 | OTHERS | BUS | 1 | 4.75 | 5 | 10 | 5 | 14 | 6 | 9.5 | 12 | 12 | 12 | 12 |  | 50 Ohms | TOP=L2:L3=L2/L4:L6=L5/L7:BOTTOM=L7 |
| BMC_SSD_RST#9 | OTHERS | BUS | 2 | 5 | 5 | 10 | 5 | 14 | 6 | 10 | 12 | 12 | 12 | 12 |  | 50 Ohms | TOP=L2:L3=L2/L4:L6=L5/L7:BOTTOM=L7 |
| BMC_SSD_RST#9 | OTHERS | BUS | 3 | 5 | 5 | 10 | 5 | 14 | 6 | 10 | 12 | 12 | 12 | 12 |  | 50 Ohms | TOP=L2:L3=L2/L4:L6=L5/L7:BOTTOM=L7 |
| BMC_SSD_RST#9 | OTHERS | BUS | 4 | 5 | 5 | 10 | 5 | 14 | 6 | 10 | 12 | 12 | 12 | 12 |  | 50 Ohms | TOP=L2:L3=L2/L4:L6=L5/L7:BOTTOM=L7 |
| BMC_SSD_RST#9 | OTHERS | BUS | 5 | 5 | 5 | 10 | 5 | 14 | 6 | 10 | 12 | 12 | 12 | 12 |  | 50 Ohms | TOP=L2:L3=L2/L4:L6=L5/L7:BOTTOM=L7 |
| BMC_SSD_RST#9 | OTHERS | BUS | 6 | 5 | 5 | 10 | 5 | 14 | 6 | 10 | 12 | 12 | 12 | 12 |  | 50 Ohms | TOP=L2:L3=L2/L4:L6=L5/L7:BOTTOM=L7 |
| BMC_SSD_RST#9 | OTHERS | BUS | 7 | 5 | 5 | 10 | 5 | 14 | 6 | 10 | 12 | 12 | 12 | 12 |  | 50 Ohms | TOP=L2:L3=L2/L4:L6=L5/L7:BOTTOM=L7 |
| BMC_SSD_RST#9 | OTHERS | BUS | 8 | 4.75 | 5 | 10 | 5 | 14 | 6 | 9.5 | 12 | 12 | 12 | 12 |  | 50 Ohms | TOP=L2:L3=L2/L4:L6=L5/L7:BOTTOM=L7 |
| BMC_TPM_RST | OTHERS | BUS | 1 | 4.75 | 5 | 10 | 5 | 14 | 6 | 9.5 | 12 | 12 | 12 | 12 |  | 50 Ohms | TOP=L2:L3=L2/L4:L6=L5/L7:BOTTOM=L7 |
| BMC_TPM_RST | OTHERS | BUS | 2 | 5 | 5 | 10 | 5 | 14 | 6 | 10 | 12 | 12 | 12 | 12 |  | 50 Ohms | TOP=L2:L3=L2/L4:L6=L5/L7:BOTTOM=L7 |
| BMC_TPM_RST | OTHERS | BUS | 3 | 5 | 5 | 10 | 5 | 14 | 6 | 10 | 12 | 12 | 12 | 12 |  | 50 Ohms | TOP=L2:L3=L2/L4:L6=L5/L7:BOTTOM=L7 |
| BMC_TPM_RST | OTHERS | BUS | 4 | 5 | 5 | 10 | 5 | 14 | 6 | 10 | 12 | 12 | 12 | 12 |  | 50 Ohms | TOP=L2:L3=L2/L4:L6=L5/L7:BOTTOM=L7 |
| BMC_TPM_RST | OTHERS | BUS | 5 | 5 | 5 | 10 | 5 | 14 | 6 | 10 | 12 | 12 | 12 | 12 |  | 50 Ohms | TOP=L2:L3=L2/L4:L6=L5/L7:BOTTOM=L7 |
| BMC_TPM_RST | OTHERS | BUS | 6 | 5 | 5 | 10 | 5 | 14 | 6 | 10 | 12 | 12 | 12 | 12 |  | 50 Ohms | TOP=L2:L3=L2/L4:L6=L5/L7:BOTTOM=L7 |
| BMC_TPM_RST | OTHERS | BUS | 7 | 5 | 5 | 10 | 5 | 14 | 6 | 10 | 12 | 12 | 12 | 12 |  | 50 Ohms | TOP=L2:L3=L2/L4:L6=L5/L7:BOTTOM=L7 |
| BMC_TPM_RST | OTHERS | BUS | 8 | 4.75 | 5 | 10 | 5 | 14 | 6 | 9.5 | 12 | 12 | 12 | 12 |  | 50 Ohms | TOP=L2:L3=L2/L4:L6=L5/L7:BOTTOM=L7 |
| BMC_UART_SWITCH_1 | OTHERS | BUS | 1 | 4.75 | 5 | 10 | 5 | 14 | 6 | 9.5 | 12 | 12 | 12 | 12 |  | 50 Ohms | TOP=L2:L3=L2/L4:L6=L5/L7:BOTTOM=L7 |
| BMC_UART_SWITCH_1 | OTHERS | BUS | 2 | 5 | 5 | 10 | 5 | 14 | 6 | 10 | 12 | 12 | 12 | 12 |  | 50 Ohms | TOP=L2:L3=L2/L4:L6=L5/L7:BOTTOM=L7 |
| BMC_UART_SWITCH_1 | OTHERS | BUS | 3 | 5 | 5 | 10 | 5 | 14 | 6 | 10 | 12 | 12 | 12 | 12 |  | 50 Ohms | TOP=L2:L3=L2/L4:L6=L5/L7:BOTTOM=L7 |
| BMC_UART_SWITCH_1 | OTHERS | BUS | 4 | 5 | 5 | 10 | 5 | 14 | 6 | 10 | 12 | 12 | 12 | 12 |  | 50 Ohms | TOP=L2:L3=L2/L4:L6=L5/L7:BOTTOM=L7 |
| BMC_UART_SWITCH_1 | OTHERS | BUS | 5 | 5 | 5 | 10 | 5 | 14 | 6 | 10 | 12 | 12 | 12 | 12 |  | 50 Ohms | TOP=L2:L3=L2/L4:L6=L5/L7:BOTTOM=L7 |
| BMC_UART_SWITCH_1 | OTHERS | BUS | 6 | 5 | 5 | 10 | 5 | 14 | 6 | 10 | 12 | 12 | 12 | 12 |  | 50 Ohms | TOP=L2:L3=L2/L4:L6=L5/L7:BOTTOM=L7 |
| BMC_UART_SWITCH_1 | OTHERS | BUS | 7 | 5 | 5 | 10 | 5 | 14 | 6 | 10 | 12 | 12 | 12 | 12 |  | 50 Ohms | TOP=L2:L3=L2/L4:L6=L5/L7:BOTTOM=L7 |
| BMC_UART_SWITCH_1 | OTHERS | BUS | 8 | 4.75 | 5 | 10 | 5 | 14 | 6 | 9.5 | 12 | 12 | 12 | 12 |  | 50 Ohms | TOP=L2:L3=L2/L4:L6=L5/L7:BOTTOM=L7 |
| BMC_USB_EN_1 | OTHERS | BUS | 1 | 4.75 | 5 | 10 | 5 | 14 | 6 | 9.5 | 12 | 12 | 12 | 12 |  | 50 Ohms | TOP=L2:L3=L2/L4:L6=L5/L7:BOTTOM=L7 |
| BMC_USB_EN_1 | OTHERS | BUS | 2 | 5 | 5 | 10 | 5 | 14 | 6 | 10 | 12 | 12 | 12 | 12 |  | 50 Ohms | TOP=L2:L3=L2/L4:L6=L5/L7:BOTTOM=L7 |
| BMC_USB_EN_1 | OTHERS | BUS | 3 | 5 | 5 | 10 | 5 | 14 | 6 | 10 | 12 | 12 | 12 | 12 |  | 50 Ohms | TOP=L2:L3=L2/L4:L6=L5/L7:BOTTOM=L7 |
| BMC_USB_EN_1 | OTHERS | BUS | 4 | 5 | 5 | 10 | 5 | 14 | 6 | 10 | 12 | 12 | 12 | 12 |  | 50 Ohms | TOP=L2:L3=L2/L4:L6=L5/L7:BOTTOM=L7 |
| BMC_USB_EN_1 | OTHERS | BUS | 5 | 5 | 5 | 10 | 5 | 14 | 6 | 10 | 12 | 12 | 12 | 12 |  | 50 Ohms | TOP=L2:L3=L2/L4:L6=L5/L7:BOTTOM=L7 |
| BMC_USB_EN_1 | OTHERS | BUS | 6 | 5 | 5 | 10 | 5 | 14 | 6 | 10 | 12 | 12 | 12 | 12 |  | 50 Ohms | TOP=L2:L3=L2/L4:L6=L5/L7:BOTTOM=L7 |
| BMC_USB_EN_1 | OTHERS | BUS | 7 | 5 | 5 | 10 | 5 | 14 | 6 | 10 | 12 | 12 | 12 | 12 |  | 50 Ohms | TOP=L2:L3=L2/L4:L6=L5/L7:BOTTOM=L7 |
| BMC_USB_EN_1 | OTHERS | BUS | 8 | 4.75 | 5 | 10 | 5 | 14 | 6 | 9.5 | 12 | 12 | 12 | 12 |  | 50 Ohms | TOP=L2:L3=L2/L4:L6=L5/L7:BOTTOM=L7 |
| BMC0_ENTEST1 | OTHERS | BUS | 1 | 4.75 | 5 | 10 | 5 | 14 | 6 | 9.5 | 12 | 12 | 12 | 12 |  | 50 Ohms | TOP=L2:L3=L2/L4:L6=L5/L7:BOTTOM=L7 |
| BMC0_ENTEST1 | OTHERS | BUS | 2 | 5 | 5 | 10 | 5 | 14 | 6 | 10 | 12 | 12 | 12 | 12 |  | 50 Ohms | TOP=L2:L3=L2/L4:L6=L5/L7:BOTTOM=L7 |
| BMC0_ENTEST1 | OTHERS | BUS | 3 | 5 | 5 | 10 | 5 | 14 | 6 | 10 | 12 | 12 | 12 | 12 |  | 50 Ohms | TOP=L2:L3=L2/L4:L6=L5/L7:BOTTOM=L7 |
| BMC0_ENTEST1 | OTHERS | BUS | 4 | 5 | 5 | 10 | 5 | 14 | 6 | 10 | 12 | 12 | 12 | 12 |  | 50 Ohms | TOP=L2:L3=L2/L4:L6=L5/L7:BOTTOM=L7 |
| BMC0_ENTEST1 | OTHERS | BUS | 5 | 5 | 5 | 10 | 5 | 14 | 6 | 10 | 12 | 12 | 12 | 12 |  | 50 Ohms | TOP=L2:L3=L2/L4:L6=L5/L7:BOTTOM=L7 |
| BMC0_ENTEST1 | OTHERS | BUS | 6 | 5 | 5 | 10 | 5 | 14 | 6 | 10 | 12 | 12 | 12 | 12 |  | 50 Ohms | TOP=L2:L3=L2/L4:L6=L5/L7:BOTTOM=L7 |
| BMC0_ENTEST1 | OTHERS | BUS | 7 | 5 | 5 | 10 | 5 | 14 | 6 | 10 | 12 | 12 | 12 | 12 |  | 50 Ohms | TOP=L2:L3=L2/L4:L6=L5/L7:BOTTOM=L7 |
| BMC0_ENTEST1 | OTHERS | BUS | 8 | 4.75 | 5 | 10 | 5 | 14 | 6 | 9.5 | 12 | 12 | 12 | 12 |  | 50 Ohms | TOP=L2:L3=L2/L4:L6=L5/L7:BOTTOM=L7 |
| BMC0_JTAG_RTCK | OTHERS | BUS | 1 | 4.75 | 5 | 10 | 5 | 14 | 6 | 9.5 | 12 | 12 | 12 | 12 |  | 50 Ohms | TOP=L2:L3=L2/L4:L6=L5/L7:BOTTOM=L7 |
| BMC0_JTAG_RTCK | OTHERS | BUS | 2 | 5 | 5 | 10 | 5 | 14 | 6 | 10 | 12 | 12 | 12 | 12 |  | 50 Ohms | TOP=L2:L3=L2/L4:L6=L5/L7:BOTTOM=L7 |
| BMC0_JTAG_RTCK | OTHERS | BUS | 3 | 5 | 5 | 10 | 5 | 14 | 6 | 10 | 12 | 12 | 12 | 12 |  | 50 Ohms | TOP=L2:L3=L2/L4:L6=L5/L7:BOTTOM=L7 |
| BMC0_JTAG_RTCK | OTHERS | BUS | 4 | 5 | 5 | 10 | 5 | 14 | 6 | 10 | 12 | 12 | 12 | 12 |  | 50 Ohms | TOP=L2:L3=L2/L4:L6=L5/L7:BOTTOM=L7 |
| BMC0_JTAG_RTCK | OTHERS | BUS | 5 | 5 | 5 | 10 | 5 | 14 | 6 | 10 | 12 | 12 | 12 | 12 |  | 50 Ohms | TOP=L2:L3=L2/L4:L6=L5/L7:BOTTOM=L7 |
| BMC0_JTAG_RTCK | OTHERS | BUS | 6 | 5 | 5 | 10 | 5 | 14 | 6 | 10 | 12 | 12 | 12 | 12 |  | 50 Ohms | TOP=L2:L3=L2/L4:L6=L5/L7:BOTTOM=L7 |
| BMC0_JTAG_RTCK | OTHERS | BUS | 7 | 5 | 5 | 10 | 5 | 14 | 6 | 10 | 12 | 12 | 12 | 12 |  | 50 Ohms | TOP=L2:L3=L2/L4:L6=L5/L7:BOTTOM=L7 |
| BMC0_JTAG_RTCK | OTHERS | BUS | 8 | 4.75 | 5 | 10 | 5 | 14 | 6 | 9.5 | 12 | 12 | 12 | 12 |  | 50 Ohms | TOP=L2:L3=L2/L4:L6=L5/L7:BOTTOM=L7 |
| BMC0_LED_DR_R_LED0 | OTHERS | BUS | 1 | 4.75 | 5 | 10 | 5 | 14 | 6 | 9.5 | 12 | 12 | 12 | 12 |  | 50 Ohms | TOP=L2:L3=L2/L4:L6=L5/L7:BOTTOM=L7 |
| BMC0_LED_DR_R_LED0 | OTHERS | BUS | 2 | 5 | 5 | 10 | 5 | 14 | 6 | 10 | 12 | 12 | 12 | 12 |  | 50 Ohms | TOP=L2:L3=L2/L4:L6=L5/L7:BOTTOM=L7 |
| BMC0_LED_DR_R_LED0 | OTHERS | BUS | 3 | 5 | 5 | 10 | 5 | 14 | 6 | 10 | 12 | 12 | 12 | 12 |  | 50 Ohms | TOP=L2:L3=L2/L4:L6=L5/L7:BOTTOM=L7 |
| BMC0_LED_DR_R_LED0 | OTHERS | BUS | 4 | 5 | 5 | 10 | 5 | 14 | 6 | 10 | 12 | 12 | 12 | 12 |  | 50 Ohms | TOP=L2:L3=L2/L4:L6=L5/L7:BOTTOM=L7 |
| BMC0_LED_DR_R_LED0 | OTHERS | BUS | 5 | 5 | 5 | 10 | 5 | 14 | 6 | 10 | 12 | 12 | 12 | 12 |  | 50 Ohms | TOP=L2:L3=L2/L4:L6=L5/L7:BOTTOM=L7 |
| BMC0_LED_DR_R_LED0 | OTHERS | BUS | 6 | 5 | 5 | 10 | 5 | 14 | 6 | 10 | 12 | 12 | 12 | 12 |  | 50 Ohms | TOP=L2:L3=L2/L4:L6=L5/L7:BOTTOM=L7 |
| BMC0_LED_DR_R_LED0 | OTHERS | BUS | 7 | 5 | 5 | 10 | 5 | 14 | 6 | 10 | 12 | 12 | 12 | 12 |  | 50 Ohms | TOP=L2:L3=L2/L4:L6=L5/L7:BOTTOM=L7 |
| BMC0_LED_DR_R_LED0 | OTHERS | BUS | 8 | 4.75 | 5 | 10 | 5 | 14 | 6 | 9.5 | 12 | 12 | 12 | 12 |  | 50 Ohms | TOP=L2:L3=L2/L4:L6=L5/L7:BOTTOM=L7 |
| BMC0_SRST_N | OTHERS | BUS | 1 | 4.75 | 5 | 10 | 5 | 14 | 6 | 9.5 | 12 | 12 | 12 | 12 |  | 50 Ohms | TOP=L2:L3=L2/L4:L6=L5/L7:BOTTOM=L7 |
| BMC0_SRST_N | OTHERS | BUS | 2 | 5 | 5 | 10 | 5 | 14 | 6 | 10 | 12 | 12 | 12 | 12 |  | 50 Ohms | TOP=L2:L3=L2/L4:L6=L5/L7:BOTTOM=L7 |
| BMC0_SRST_N | OTHERS | BUS | 3 | 5 | 5 | 10 | 5 | 14 | 6 | 10 | 12 | 12 | 12 | 12 |  | 50 Ohms | TOP=L2:L3=L2/L4:L6=L5/L7:BOTTOM=L7 |
| BMC0_SRST_N | OTHERS | BUS | 4 | 5 | 5 | 10 | 5 | 14 | 6 | 10 | 12 | 12 | 12 | 12 |  | 50 Ohms | TOP=L2:L3=L2/L4:L6=L5/L7:BOTTOM=L7 |
| BMC0_SRST_N | OTHERS | BUS | 5 | 5 | 5 | 10 | 5 | 14 | 6 | 10 | 12 | 12 | 12 | 12 |  | 50 Ohms | TOP=L2:L3=L2/L4:L6=L5/L7:BOTTOM=L7 |
| BMC0_SRST_N | OTHERS | BUS | 6 | 5 | 5 | 10 | 5 | 14 | 6 | 10 | 12 | 12 | 12 | 12 |  | 50 Ohms | TOP=L2:L3=L2/L4:L6=L5/L7:BOTTOM=L7 |
| BMC0_SRST_N | OTHERS | BUS | 7 | 5 | 5 | 10 | 5 | 14 | 6 | 10 | 12 | 12 | 12 | 12 |  | 50 Ohms | TOP=L2:L3=L2/L4:L6=L5/L7:BOTTOM=L7 |
| BMC0_SRST_N | OTHERS | BUS | 8 | 4.75 | 5 | 10 | 5 | 14 | 6 | 9.5 | 12 | 12 | 12 | 12 |  | 50 Ohms | TOP=L2:L3=L2/L4:L6=L5/L7:BOTTOM=L7 |
| BMC0_TACH13 | OTHERS | BUS | 1 | 4.75 | 5 | 10 | 5 | 14 | 6 | 9.5 | 12 | 12 | 12 | 12 |  | 50 Ohms | TOP=L2:L3=L2/L4:L6=L5/L7:BOTTOM=L7 |
| BMC0_TACH13 | OTHERS | BUS | 2 | 5 | 5 | 10 | 5 | 14 | 6 | 10 | 12 | 12 | 12 | 12 |  | 50 Ohms | TOP=L2:L3=L2/L4:L6=L5/L7:BOTTOM=L7 |
| BMC0_TACH13 | OTHERS | BUS | 3 | 5 | 5 | 10 | 5 | 14 | 6 | 10 | 12 | 12 | 12 | 12 |  | 50 Ohms | TOP=L2:L3=L2/L4:L6=L5/L7:BOTTOM=L7 |
| BMC0_TACH13 | OTHERS | BUS | 4 | 5 | 5 | 10 | 5 | 14 | 6 | 10 | 12 | 12 | 12 | 12 |  | 50 Ohms | TOP=L2:L3=L2/L4:L6=L5/L7:BOTTOM=L7 |
| BMC0_TACH13 | OTHERS | BUS | 5 | 5 | 5 | 10 | 5 | 14 | 6 | 10 | 12 | 12 | 12 | 12 |  | 50 Ohms | TOP=L2:L3=L2/L4:L6=L5/L7:BOTTOM=L7 |
| BMC0_TACH13 | OTHERS | BUS | 6 | 5 | 5 | 10 | 5 | 14 | 6 | 10 | 12 | 12 | 12 | 12 |  | 50 Ohms | TOP=L2:L3=L2/L4:L6=L5/L7:BOTTOM=L7 |
| BMC0_TACH13 | OTHERS | BUS | 7 | 5 | 5 | 10 | 5 | 14 | 6 | 10 | 12 | 12 | 12 | 12 |  | 50 Ohms | TOP=L2:L3=L2/L4:L6=L5/L7:BOTTOM=L7 |
| BMC0_TACH13 | OTHERS | BUS | 8 | 4.75 | 5 | 10 | 5 | 14 | 6 | 9.5 | 12 | 12 | 12 | 12 |  | 50 Ohms | TOP=L2:L3=L2/L4:L6=L5/L7:BOTTOM=L7 |
| BOOT_RECOVERY# | OTHERS | BUS | 1 | 4.75 | 5 | 10 | 5 | 14 | 6 | 9.5 | 12 | 12 | 12 | 12 |  | 50 Ohms | TOP=L2:L3=L2/L4:L6=L5/L7:BOTTOM=L7 |
| BOOT_RECOVERY# | OTHERS | BUS | 2 | 5 | 5 | 10 | 5 | 14 | 6 | 10 | 12 | 12 | 12 | 12 |  | 50 Ohms | TOP=L2:L3=L2/L4:L6=L5/L7:BOTTOM=L7 |
| BOOT_RECOVERY# | OTHERS | BUS | 3 | 5 | 5 | 10 | 5 | 14 | 6 | 10 | 12 | 12 | 12 | 12 |  | 50 Ohms | TOP=L2:L3=L2/L4:L6=L5/L7:BOTTOM=L7 |
| BOOT_RECOVERY# | OTHERS | BUS | 4 | 5 | 5 | 10 | 5 | 14 | 6 | 10 | 12 | 12 | 12 | 12 |  | 50 Ohms | TOP=L2:L3=L2/L4:L6=L5/L7:BOTTOM=L7 |
| BOOT_RECOVERY# | OTHERS | BUS | 5 | 5 | 5 | 10 | 5 | 14 | 6 | 10 | 12 | 12 | 12 | 12 |  | 50 Ohms | TOP=L2:L3=L2/L4:L6=L5/L7:BOTTOM=L7 |
| BOOT_RECOVERY# | OTHERS | BUS | 6 | 5 | 5 | 10 | 5 | 14 | 6 | 10 | 12 | 12 | 12 | 12 |  | 50 Ohms | TOP=L2:L3=L2/L4:L6=L5/L7:BOTTOM=L7 |
| BOOT_RECOVERY# | OTHERS | BUS | 7 | 5 | 5 | 10 | 5 | 14 | 6 | 10 | 12 | 12 | 12 | 12 |  | 50 Ohms | TOP=L2:L3=L2/L4:L6=L5/L7:BOTTOM=L7 |
| BOOT_RECOVERY# | OTHERS | BUS | 8 | 4.75 | 5 | 10 | 5 | 14 | 6 | 9.5 | 12 | 12 | 12 | 12 |  | 50 Ohms | TOP=L2:L3=L2/L4:L6=L5/L7:BOTTOM=L7 |
| BOOT_RECOVERY#_R | OTHERS | BUS | 1 | 4.75 | 5 | 10 | 5 | 14 | 6 | 9.5 | 12 | 12 | 12 | 12 |  | 50 Ohms | TOP=L2:L3=L2/L4:L6=L5/L7:BOTTOM=L7 |
| BOOT_RECOVERY#_R | OTHERS | BUS | 2 | 5 | 5 | 10 | 5 | 14 | 6 | 10 | 12 | 12 | 12 | 12 |  | 50 Ohms | TOP=L2:L3=L2/L4:L6=L5/L7:BOTTOM=L7 |
| BOOT_RECOVERY#_R | OTHERS | BUS | 3 | 5 | 5 | 10 | 5 | 14 | 6 | 10 | 12 | 12 | 12 | 12 |  | 50 Ohms | TOP=L2:L3=L2/L4:L6=L5/L7:BOTTOM=L7 |
| BOOT_RECOVERY#_R | OTHERS | BUS | 4 | 5 | 5 | 10 | 5 | 14 | 6 | 10 | 12 | 12 | 12 | 12 |  | 50 Ohms | TOP=L2:L3=L2/L4:L6=L5/L7:BOTTOM=L7 |
| BOOT_RECOVERY#_R | OTHERS | BUS | 5 | 5 | 5 | 10 | 5 | 14 | 6 | 10 | 12 | 12 | 12 | 12 |  | 50 Ohms | TOP=L2:L3=L2/L4:L6=L5/L7:BOTTOM=L7 |
| BOOT_RECOVERY#_R | OTHERS | BUS | 6 | 5 | 5 | 10 | 5 | 14 | 6 | 10 | 12 | 12 | 12 | 12 |  | 50 Ohms | TOP=L2:L3=L2/L4:L6=L5/L7:BOTTOM=L7 |
| BOOT_RECOVERY#_R | OTHERS | BUS | 7 | 5 | 5 | 10 | 5 | 14 | 6 | 10 | 12 | 12 | 12 | 12 |  | 50 Ohms | TOP=L2:L3=L2/L4:L6=L5/L7:BOTTOM=L7 |
| BOOT_RECOVERY#_R | OTHERS | BUS | 8 | 4.75 | 5 | 10 | 5 | 14 | 6 | 9.5 | 12 | 12 | 12 | 12 |  | 50 Ohms | TOP=L2:L3=L2/L4:L6=L5/L7:BOTTOM=L7 |
| BOOT_RECOVERY_0 | OTHERS | BUS | 1 | 4.75 | 5 | 10 | 5 | 14 | 6 | 9.5 | 12 | 12 | 12 | 12 |  | 50 Ohms | TOP=L2:L3=L2/L4:L6=L5/L7:BOTTOM=L7 |
| BOOT_RECOVERY_0 | OTHERS | BUS | 2 | 5 | 5 | 10 | 5 | 14 | 6 | 10 | 12 | 12 | 12 | 12 |  | 50 Ohms | TOP=L2:L3=L2/L4:L6=L5/L7:BOTTOM=L7 |
| BOOT_RECOVERY_0 | OTHERS | BUS | 3 | 5 | 5 | 10 | 5 | 14 | 6 | 10 | 12 | 12 | 12 | 12 |  | 50 Ohms | TOP=L2:L3=L2/L4:L6=L5/L7:BOTTOM=L7 |
| BOOT_RECOVERY_0 | OTHERS | BUS | 4 | 5 | 5 | 10 | 5 | 14 | 6 | 10 | 12 | 12 | 12 | 12 |  | 50 Ohms | TOP=L2:L3=L2/L4:L6=L5/L7:BOTTOM=L7 |
| BOOT_RECOVERY_0 | OTHERS | BUS | 5 | 5 | 5 | 10 | 5 | 14 | 6 | 10 | 12 | 12 | 12 | 12 |  | 50 Ohms | TOP=L2:L3=L2/L4:L6=L5/L7:BOTTOM=L7 |
| BOOT_RECOVERY_0 | OTHERS | BUS | 6 | 5 | 5 | 10 | 5 | 14 | 6 | 10 | 12 | 12 | 12 | 12 |  | 50 Ohms | TOP=L2:L3=L2/L4:L6=L5/L7:BOTTOM=L7 |
| BOOT_RECOVERY_0 | OTHERS | BUS | 7 | 5 | 5 | 10 | 5 | 14 | 6 | 10 | 12 | 12 | 12 | 12 |  | 50 Ohms | TOP=L2:L3=L2/L4:L6=L5/L7:BOTTOM=L7 |
| BOOT_RECOVERY_0 | OTHERS | BUS | 8 | 4.75 | 5 | 10 | 5 | 14 | 6 | 9.5 | 12 | 12 | 12 | 12 |  | 50 Ohms | TOP=L2:L3=L2/L4:L6=L5/L7:BOTTOM=L7 |
| BOOT_RECOVERY_1 | OTHERS | BUS | 1 | 4.75 | 5 | 10 | 5 | 14 | 6 | 9.5 | 12 | 12 | 12 | 12 |  | 50 Ohms | TOP=L2:L3=L2/L4:L6=L5/L7:BOTTOM=L7 |
| BOOT_RECOVERY_1 | OTHERS | BUS | 2 | 5 | 5 | 10 | 5 | 14 | 6 | 10 | 12 | 12 | 12 | 12 |  | 50 Ohms | TOP=L2:L3=L2/L4:L6=L5/L7:BOTTOM=L7 |
| BOOT_RECOVERY_1 | OTHERS | BUS | 3 | 5 | 5 | 10 | 5 | 14 | 6 | 10 | 12 | 12 | 12 | 12 |  | 50 Ohms | TOP=L2:L3=L2/L4:L6=L5/L7:BOTTOM=L7 |
| BOOT_RECOVERY_1 | OTHERS | BUS | 4 | 5 | 5 | 10 | 5 | 14 | 6 | 10 | 12 | 12 | 12 | 12 |  | 50 Ohms | TOP=L2:L3=L2/L4:L6=L5/L7:BOTTOM=L7 |
| BOOT_RECOVERY_1 | OTHERS | BUS | 5 | 5 | 5 | 10 | 5 | 14 | 6 | 10 | 12 | 12 | 12 | 12 |  | 50 Ohms | TOP=L2:L3=L2/L4:L6=L5/L7:BOTTOM=L7 |
| BOOT_RECOVERY_1 | OTHERS | BUS | 6 | 5 | 5 | 10 | 5 | 14 | 6 | 10 | 12 | 12 | 12 | 12 |  | 50 Ohms | TOP=L2:L3=L2/L4:L6=L5/L7:BOTTOM=L7 |
| BOOT_RECOVERY_1 | OTHERS | BUS | 7 | 5 | 5 | 10 | 5 | 14 | 6 | 10 | 12 | 12 | 12 | 12 |  | 50 Ohms | TOP=L2:L3=L2/L4:L6=L5/L7:BOTTOM=L7 |
| BOOT_RECOVERY_1 | OTHERS | BUS | 8 | 4.75 | 5 | 10 | 5 | 14 | 6 | 9.5 | 12 | 12 | 12 | 12 |  | 50 Ohms | TOP=L2:L3=L2/L4:L6=L5/L7:BOTTOM=L7 |
| BOOTSTRAP_R_0 | OTHERS | BUS | 1 | 4.75 | 5 | 10 | 5 | 14 | 6 | 9.5 | 12 | 12 | 12 | 12 |  | 50 Ohms | TOP=L2:L3=L2/L4:L6=L5/L7:BOTTOM=L7 |
| BOOTSTRAP_R_0 | OTHERS | BUS | 2 | 5 | 5 | 10 | 5 | 14 | 6 | 10 | 12 | 12 | 12 | 12 |  | 50 Ohms | TOP=L2:L3=L2/L4:L6=L5/L7:BOTTOM=L7 |
| BOOTSTRAP_R_0 | OTHERS | BUS | 3 | 5 | 5 | 10 | 5 | 14 | 6 | 10 | 12 | 12 | 12 | 12 |  | 50 Ohms | TOP=L2:L3=L2/L4:L6=L5/L7:BOTTOM=L7 |
| BOOTSTRAP_R_0 | OTHERS | BUS | 4 | 5 | 5 | 10 | 5 | 14 | 6 | 10 | 12 | 12 | 12 | 12 |  | 50 Ohms | TOP=L2:L3=L2/L4:L6=L5/L7:BOTTOM=L7 |
| BOOTSTRAP_R_0 | OTHERS | BUS | 5 | 5 | 5 | 10 | 5 | 14 | 6 | 10 | 12 | 12 | 12 | 12 |  | 50 Ohms | TOP=L2:L3=L2/L4:L6=L5/L7:BOTTOM=L7 |
| BOOTSTRAP_R_0 | OTHERS | BUS | 6 | 5 | 5 | 10 | 5 | 14 | 6 | 10 | 12 | 12 | 12 | 12 |  | 50 Ohms | TOP=L2:L3=L2/L4:L6=L5/L7:BOTTOM=L7 |
| BOOTSTRAP_R_0 | OTHERS | BUS | 7 | 5 | 5 | 10 | 5 | 14 | 6 | 10 | 12 | 12 | 12 | 12 |  | 50 Ohms | TOP=L2:L3=L2/L4:L6=L5/L7:BOTTOM=L7 |
| BOOTSTRAP_R_0 | OTHERS | BUS | 8 | 4.75 | 5 | 10 | 5 | 14 | 6 | 9.5 | 12 | 12 | 12 | 12 |  | 50 Ohms | TOP=L2:L3=L2/L4:L6=L5/L7:BOTTOM=L7 |
| BOOTSTRAP_R_1 | OTHERS | BUS | 1 | 4.75 | 5 | 10 | 5 | 14 | 6 | 9.5 | 12 | 12 | 12 | 12 |  | 50 Ohms | TOP=L2:L3=L2/L4:L6=L5/L7:BOTTOM=L7 |
| BOOTSTRAP_R_1 | OTHERS | BUS | 2 | 5 | 5 | 10 | 5 | 14 | 6 | 10 | 12 | 12 | 12 | 12 |  | 50 Ohms | TOP=L2:L3=L2/L4:L6=L5/L7:BOTTOM=L7 |
| BOOTSTRAP_R_1 | OTHERS | BUS | 3 | 5 | 5 | 10 | 5 | 14 | 6 | 10 | 12 | 12 | 12 | 12 |  | 50 Ohms | TOP=L2:L3=L2/L4:L6=L5/L7:BOTTOM=L7 |
| BOOTSTRAP_R_1 | OTHERS | BUS | 4 | 5 | 5 | 10 | 5 | 14 | 6 | 10 | 12 | 12 | 12 | 12 |  | 50 Ohms | TOP=L2:L3=L2/L4:L6=L5/L7:BOTTOM=L7 |
| BOOTSTRAP_R_1 | OTHERS | BUS | 5 | 5 | 5 | 10 | 5 | 14 | 6 | 10 | 12 | 12 | 12 | 12 |  | 50 Ohms | TOP=L2:L3=L2/L4:L6=L5/L7:BOTTOM=L7 |
| BOOTSTRAP_R_1 | OTHERS | BUS | 6 | 5 | 5 | 10 | 5 | 14 | 6 | 10 | 12 | 12 | 12 | 12 |  | 50 Ohms | TOP=L2:L3=L2/L4:L6=L5/L7:BOTTOM=L7 |
| BOOTSTRAP_R_1 | OTHERS | BUS | 7 | 5 | 5 | 10 | 5 | 14 | 6 | 10 | 12 | 12 | 12 | 12 |  | 50 Ohms | TOP=L2:L3=L2/L4:L6=L5/L7:BOTTOM=L7 |
| BOOTSTRAP_R_1 | OTHERS | BUS | 8 | 4.75 | 5 | 10 | 5 | 14 | 6 | 9.5 | 12 | 12 | 12 | 12 |  | 50 Ohms | TOP=L2:L3=L2/L4:L6=L5/L7:BOTTOM=L7 |
| BOOTSTRAP_R_10 | OTHERS | BUS | 1 | 4.75 | 5 | 10 | 5 | 14 | 6 | 9.5 | 12 | 12 | 12 | 12 |  | 50 Ohms | TOP=L2:L3=L2/L4:L6=L5/L7:BOTTOM=L7 |
| BOOTSTRAP_R_10 | OTHERS | BUS | 2 | 5 | 5 | 10 | 5 | 14 | 6 | 10 | 12 | 12 | 12 | 12 |  | 50 Ohms | TOP=L2:L3=L2/L4:L6=L5/L7:BOTTOM=L7 |
| BOOTSTRAP_R_10 | OTHERS | BUS | 3 | 5 | 5 | 10 | 5 | 14 | 6 | 10 | 12 | 12 | 12 | 12 |  | 50 Ohms | TOP=L2:L3=L2/L4:L6=L5/L7:BOTTOM=L7 |
| BOOTSTRAP_R_10 | OTHERS | BUS | 4 | 5 | 5 | 10 | 5 | 14 | 6 | 10 | 12 | 12 | 12 | 12 |  | 50 Ohms | TOP=L2:L3=L2/L4:L6=L5/L7:BOTTOM=L7 |
| BOOTSTRAP_R_10 | OTHERS | BUS | 5 | 5 | 5 | 10 | 5 | 14 | 6 | 10 | 12 | 12 | 12 | 12 |  | 50 Ohms | TOP=L2:L3=L2/L4:L6=L5/L7:BOTTOM=L7 |
| BOOTSTRAP_R_10 | OTHERS | BUS | 6 | 5 | 5 | 10 | 5 | 14 | 6 | 10 | 12 | 12 | 12 | 12 |  | 50 Ohms | TOP=L2:L3=L2/L4:L6=L5/L7:BOTTOM=L7 |
| BOOTSTRAP_R_10 | OTHERS | BUS | 7 | 5 | 5 | 10 | 5 | 14 | 6 | 10 | 12 | 12 | 12 | 12 |  | 50 Ohms | TOP=L2:L3=L2/L4:L6=L5/L7:BOTTOM=L7 |
| BOOTSTRAP_R_10 | OTHERS | BUS | 8 | 4.75 | 5 | 10 | 5 | 14 | 6 | 9.5 | 12 | 12 | 12 | 12 |  | 50 Ohms | TOP=L2:L3=L2/L4:L6=L5/L7:BOTTOM=L7 |
| BOOTSTRAP_R_2 | OTHERS | BUS | 1 | 4.75 | 5 | 10 | 5 | 14 | 6 | 9.5 | 12 | 12 | 12 | 12 |  | 50 Ohms | TOP=L2:L3=L2/L4:L6=L5/L7:BOTTOM=L7 |
| BOOTSTRAP_R_2 | OTHERS | BUS | 2 | 5 | 5 | 10 | 5 | 14 | 6 | 10 | 12 | 12 | 12 | 12 |  | 50 Ohms | TOP=L2:L3=L2/L4:L6=L5/L7:BOTTOM=L7 |
| BOOTSTRAP_R_2 | OTHERS | BUS | 3 | 5 | 5 | 10 | 5 | 14 | 6 | 10 | 12 | 12 | 12 | 12 |  | 50 Ohms | TOP=L2:L3=L2/L4:L6=L5/L7:BOTTOM=L7 |
| BOOTSTRAP_R_2 | OTHERS | BUS | 4 | 5 | 5 | 10 | 5 | 14 | 6 | 10 | 12 | 12 | 12 | 12 |  | 50 Ohms | TOP=L2:L3=L2/L4:L6=L5/L7:BOTTOM=L7 |
| BOOTSTRAP_R_2 | OTHERS | BUS | 5 | 5 | 5 | 10 | 5 | 14 | 6 | 10 | 12 | 12 | 12 | 12 |  | 50 Ohms | TOP=L2:L3=L2/L4:L6=L5/L7:BOTTOM=L7 |
| BOOTSTRAP_R_2 | OTHERS | BUS | 6 | 5 | 5 | 10 | 5 | 14 | 6 | 10 | 12 | 12 | 12 | 12 |  | 50 Ohms | TOP=L2:L3=L2/L4:L6=L5/L7:BOTTOM=L7 |
| BOOTSTRAP_R_2 | OTHERS | BUS | 7 | 5 | 5 | 10 | 5 | 14 | 6 | 10 | 12 | 12 | 12 | 12 |  | 50 Ohms | TOP=L2:L3=L2/L4:L6=L5/L7:BOTTOM=L7 |
| BOOTSTRAP_R_2 | OTHERS | BUS | 8 | 4.75 | 5 | 10 | 5 | 14 | 6 | 9.5 | 12 | 12 | 12 | 12 |  | 50 Ohms | TOP=L2:L3=L2/L4:L6=L5/L7:BOTTOM=L7 |
| BOOTSTRAP_R_3 | OTHERS | BUS | 1 | 4.75 | 5 | 10 | 5 | 14 | 6 | 9.5 | 12 | 12 | 12 | 12 |  | 50 Ohms | TOP=L2:L3=L2/L4:L6=L5/L7:BOTTOM=L7 |
| BOOTSTRAP_R_3 | OTHERS | BUS | 2 | 5 | 5 | 10 | 5 | 14 | 6 | 10 | 12 | 12 | 12 | 12 |  | 50 Ohms | TOP=L2:L3=L2/L4:L6=L5/L7:BOTTOM=L7 |
| BOOTSTRAP_R_3 | OTHERS | BUS | 3 | 5 | 5 | 10 | 5 | 14 | 6 | 10 | 12 | 12 | 12 | 12 |  | 50 Ohms | TOP=L2:L3=L2/L4:L6=L5/L7:BOTTOM=L7 |
| BOOTSTRAP_R_3 | OTHERS | BUS | 4 | 5 | 5 | 10 | 5 | 14 | 6 | 10 | 12 | 12 | 12 | 12 |  | 50 Ohms | TOP=L2:L3=L2/L4:L6=L5/L7:BOTTOM=L7 |
| BOOTSTRAP_R_3 | OTHERS | BUS | 5 | 5 | 5 | 10 | 5 | 14 | 6 | 10 | 12 | 12 | 12 | 12 |  | 50 Ohms | TOP=L2:L3=L2/L4:L6=L5/L7:BOTTOM=L7 |
| BOOTSTRAP_R_3 | OTHERS | BUS | 6 | 5 | 5 | 10 | 5 | 14 | 6 | 10 | 12 | 12 | 12 | 12 |  | 50 Ohms | TOP=L2:L3=L2/L4:L6=L5/L7:BOTTOM=L7 |
| BOOTSTRAP_R_3 | OTHERS | BUS | 7 | 5 | 5 | 10 | 5 | 14 | 6 | 10 | 12 | 12 | 12 | 12 |  | 50 Ohms | TOP=L2:L3=L2/L4:L6=L5/L7:BOTTOM=L7 |
| BOOTSTRAP_R_3 | OTHERS | BUS | 8 | 4.75 | 5 | 10 | 5 | 14 | 6 | 9.5 | 12 | 12 | 12 | 12 |  | 50 Ohms | TOP=L2:L3=L2/L4:L6=L5/L7:BOTTOM=L7 |
| BOOTSTRAP_R_4 | OTHERS | BUS | 1 | 4.75 | 5 | 10 | 5 | 14 | 6 | 9.5 | 12 | 12 | 12 | 12 |  | 50 Ohms | TOP=L2:L3=L2/L4:L6=L5/L7:BOTTOM=L7 |
| BOOTSTRAP_R_4 | OTHERS | BUS | 2 | 5 | 5 | 10 | 5 | 14 | 6 | 10 | 12 | 12 | 12 | 12 |  | 50 Ohms | TOP=L2:L3=L2/L4:L6=L5/L7:BOTTOM=L7 |
| BOOTSTRAP_R_4 | OTHERS | BUS | 3 | 5 | 5 | 10 | 5 | 14 | 6 | 10 | 12 | 12 | 12 | 12 |  | 50 Ohms | TOP=L2:L3=L2/L4:L6=L5/L7:BOTTOM=L7 |
| BOOTSTRAP_R_4 | OTHERS | BUS | 4 | 5 | 5 | 10 | 5 | 14 | 6 | 10 | 12 | 12 | 12 | 12 |  | 50 Ohms | TOP=L2:L3=L2/L4:L6=L5/L7:BOTTOM=L7 |
| BOOTSTRAP_R_4 | OTHERS | BUS | 5 | 5 | 5 | 10 | 5 | 14 | 6 | 10 | 12 | 12 | 12 | 12 |  | 50 Ohms | TOP=L2:L3=L2/L4:L6=L5/L7:BOTTOM=L7 |
| BOOTSTRAP_R_4 | OTHERS | BUS | 6 | 5 | 5 | 10 | 5 | 14 | 6 | 10 | 12 | 12 | 12 | 12 |  | 50 Ohms | TOP=L2:L3=L2/L4:L6=L5/L7:BOTTOM=L7 |
| BOOTSTRAP_R_4 | OTHERS | BUS | 7 | 5 | 5 | 10 | 5 | 14 | 6 | 10 | 12 | 12 | 12 | 12 |  | 50 Ohms | TOP=L2:L3=L2/L4:L6=L5/L7:BOTTOM=L7 |
| BOOTSTRAP_R_4 | OTHERS | BUS | 8 | 4.75 | 5 | 10 | 5 | 14 | 6 | 9.5 | 12 | 12 | 12 | 12 |  | 50 Ohms | TOP=L2:L3=L2/L4:L6=L5/L7:BOTTOM=L7 |
| BOOTSTRAP_R_5 | OTHERS | BUS | 1 | 4.75 | 5 | 10 | 5 | 14 | 6 | 9.5 | 12 | 12 | 12 | 12 |  | 50 Ohms | TOP=L2:L3=L2/L4:L6=L5/L7:BOTTOM=L7 |
| BOOTSTRAP_R_5 | OTHERS | BUS | 2 | 5 | 5 | 10 | 5 | 14 | 6 | 10 | 12 | 12 | 12 | 12 |  | 50 Ohms | TOP=L2:L3=L2/L4:L6=L5/L7:BOTTOM=L7 |
| BOOTSTRAP_R_5 | OTHERS | BUS | 3 | 5 | 5 | 10 | 5 | 14 | 6 | 10 | 12 | 12 | 12 | 12 |  | 50 Ohms | TOP=L2:L3=L2/L4:L6=L5/L7:BOTTOM=L7 |
| BOOTSTRAP_R_5 | OTHERS | BUS | 4 | 5 | 5 | 10 | 5 | 14 | 6 | 10 | 12 | 12 | 12 | 12 |  | 50 Ohms | TOP=L2:L3=L2/L4:L6=L5/L7:BOTTOM=L7 |
| BOOTSTRAP_R_5 | OTHERS | BUS | 5 | 5 | 5 | 10 | 5 | 14 | 6 | 10 | 12 | 12 | 12 | 12 |  | 50 Ohms | TOP=L2:L3=L2/L4:L6=L5/L7:BOTTOM=L7 |
| BOOTSTRAP_R_5 | OTHERS | BUS | 6 | 5 | 5 | 10 | 5 | 14 | 6 | 10 | 12 | 12 | 12 | 12 |  | 50 Ohms | TOP=L2:L3=L2/L4:L6=L5/L7:BOTTOM=L7 |
| BOOTSTRAP_R_5 | OTHERS | BUS | 7 | 5 | 5 | 10 | 5 | 14 | 6 | 10 | 12 | 12 | 12 | 12 |  | 50 Ohms | TOP=L2:L3=L2/L4:L6=L5/L7:BOTTOM=L7 |
| BOOTSTRAP_R_5 | OTHERS | BUS | 8 | 4.75 | 5 | 10 | 5 | 14 | 6 | 9.5 | 12 | 12 | 12 | 12 |  | 50 Ohms | TOP=L2:L3=L2/L4:L6=L5/L7:BOTTOM=L7 |
| BOOTSTRAP_R_6 | OTHERS | BUS | 1 | 4.75 | 5 | 10 | 5 | 14 | 6 | 9.5 | 12 | 12 | 12 | 12 |  | 50 Ohms | TOP=L2:L3=L2/L4:L6=L5/L7:BOTTOM=L7 |
| BOOTSTRAP_R_6 | OTHERS | BUS | 2 | 5 | 5 | 10 | 5 | 14 | 6 | 10 | 12 | 12 | 12 | 12 |  | 50 Ohms | TOP=L2:L3=L2/L4:L6=L5/L7:BOTTOM=L7 |
| BOOTSTRAP_R_6 | OTHERS | BUS | 3 | 5 | 5 | 10 | 5 | 14 | 6 | 10 | 12 | 12 | 12 | 12 |  | 50 Ohms | TOP=L2:L3=L2/L4:L6=L5/L7:BOTTOM=L7 |
| BOOTSTRAP_R_6 | OTHERS | BUS | 4 | 5 | 5 | 10 | 5 | 14 | 6 | 10 | 12 | 12 | 12 | 12 |  | 50 Ohms | TOP=L2:L3=L2/L4:L6=L5/L7:BOTTOM=L7 |
| BOOTSTRAP_R_6 | OTHERS | BUS | 5 | 5 | 5 | 10 | 5 | 14 | 6 | 10 | 12 | 12 | 12 | 12 |  | 50 Ohms | TOP=L2:L3=L2/L4:L6=L5/L7:BOTTOM=L7 |
| BOOTSTRAP_R_6 | OTHERS | BUS | 6 | 5 | 5 | 10 | 5 | 14 | 6 | 10 | 12 | 12 | 12 | 12 |  | 50 Ohms | TOP=L2:L3=L2/L4:L6=L5/L7:BOTTOM=L7 |
| BOOTSTRAP_R_6 | OTHERS | BUS | 7 | 5 | 5 | 10 | 5 | 14 | 6 | 10 | 12 | 12 | 12 | 12 |  | 50 Ohms | TOP=L2:L3=L2/L4:L6=L5/L7:BOTTOM=L7 |
| BOOTSTRAP_R_6 | OTHERS | BUS | 8 | 4.75 | 5 | 10 | 5 | 14 | 6 | 9.5 | 12 | 12 | 12 | 12 |  | 50 Ohms | TOP=L2:L3=L2/L4:L6=L5/L7:BOTTOM=L7 |
| BOOTSTRAP_R_7 | OTHERS | BUS | 1 | 4.75 | 5 | 10 | 5 | 14 | 6 | 9.5 | 12 | 12 | 12 | 12 |  | 50 Ohms | TOP=L2:L3=L2/L4:L6=L5/L7:BOTTOM=L7 |
| BOOTSTRAP_R_7 | OTHERS | BUS | 2 | 5 | 5 | 10 | 5 | 14 | 6 | 10 | 12 | 12 | 12 | 12 |  | 50 Ohms | TOP=L2:L3=L2/L4:L6=L5/L7:BOTTOM=L7 |
| BOOTSTRAP_R_7 | OTHERS | BUS | 3 | 5 | 5 | 10 | 5 | 14 | 6 | 10 | 12 | 12 | 12 | 12 |  | 50 Ohms | TOP=L2:L3=L2/L4:L6=L5/L7:BOTTOM=L7 |
| BOOTSTRAP_R_7 | OTHERS | BUS | 4 | 5 | 5 | 10 | 5 | 14 | 6 | 10 | 12 | 12 | 12 | 12 |  | 50 Ohms | TOP=L2:L3=L2/L4:L6=L5/L7:BOTTOM=L7 |
| BOOTSTRAP_R_7 | OTHERS | BUS | 5 | 5 | 5 | 10 | 5 | 14 | 6 | 10 | 12 | 12 | 12 | 12 |  | 50 Ohms | TOP=L2:L3=L2/L4:L6=L5/L7:BOTTOM=L7 |
| BOOTSTRAP_R_7 | OTHERS | BUS | 6 | 5 | 5 | 10 | 5 | 14 | 6 | 10 | 12 | 12 | 12 | 12 |  | 50 Ohms | TOP=L2:L3=L2/L4:L6=L5/L7:BOTTOM=L7 |
| BOOTSTRAP_R_7 | OTHERS | BUS | 7 | 5 | 5 | 10 | 5 | 14 | 6 | 10 | 12 | 12 | 12 | 12 |  | 50 Ohms | TOP=L2:L3=L2/L4:L6=L5/L7:BOTTOM=L7 |
| BOOTSTRAP_R_7 | OTHERS | BUS | 8 | 4.75 | 5 | 10 | 5 | 14 | 6 | 9.5 | 12 | 12 | 12 | 12 |  | 50 Ohms | TOP=L2:L3=L2/L4:L6=L5/L7:BOTTOM=L7 |
| BOOTSTRAP_R_8 | OTHERS | BUS | 1 | 4.75 | 5 | 10 | 5 | 14 | 6 | 9.5 | 12 | 12 | 12 | 12 |  | 50 Ohms | TOP=L2:L3=L2/L4:L6=L5/L7:BOTTOM=L7 |
| BOOTSTRAP_R_8 | OTHERS | BUS | 2 | 5 | 5 | 10 | 5 | 14 | 6 | 10 | 12 | 12 | 12 | 12 |  | 50 Ohms | TOP=L2:L3=L2/L4:L6=L5/L7:BOTTOM=L7 |
| BOOTSTRAP_R_8 | OTHERS | BUS | 3 | 5 | 5 | 10 | 5 | 14 | 6 | 10 | 12 | 12 | 12 | 12 |  | 50 Ohms | TOP=L2:L3=L2/L4:L6=L5/L7:BOTTOM=L7 |
| BOOTSTRAP_R_8 | OTHERS | BUS | 4 | 5 | 5 | 10 | 5 | 14 | 6 | 10 | 12 | 12 | 12 | 12 |  | 50 Ohms | TOP=L2:L3=L2/L4:L6=L5/L7:BOTTOM=L7 |
| BOOTSTRAP_R_8 | OTHERS | BUS | 5 | 5 | 5 | 10 | 5 | 14 | 6 | 10 | 12 | 12 | 12 | 12 |  | 50 Ohms | TOP=L2:L3=L2/L4:L6=L5/L7:BOTTOM=L7 |
| BOOTSTRAP_R_8 | OTHERS | BUS | 6 | 5 | 5 | 10 | 5 | 14 | 6 | 10 | 12 | 12 | 12 | 12 |  | 50 Ohms | TOP=L2:L3=L2/L4:L6=L5/L7:BOTTOM=L7 |
| BOOTSTRAP_R_8 | OTHERS | BUS | 7 | 5 | 5 | 10 | 5 | 14 | 6 | 10 | 12 | 12 | 12 | 12 |  | 50 Ohms | TOP=L2:L3=L2/L4:L6=L5/L7:BOTTOM=L7 |
| BOOTSTRAP_R_8 | OTHERS | BUS | 8 | 4.75 | 5 | 10 | 5 | 14 | 6 | 9.5 | 12 | 12 | 12 | 12 |  | 50 Ohms | TOP=L2:L3=L2/L4:L6=L5/L7:BOTTOM=L7 |
| BOOTSTRAP_R_9 | OTHERS | BUS | 1 | 4.75 | 5 | 10 | 5 | 14 | 6 | 9.5 | 12 | 12 | 12 | 12 |  | 50 Ohms | TOP=L2:L3=L2/L4:L6=L5/L7:BOTTOM=L7 |
| BOOTSTRAP_R_9 | OTHERS | BUS | 2 | 5 | 5 | 10 | 5 | 14 | 6 | 10 | 12 | 12 | 12 | 12 |  | 50 Ohms | TOP=L2:L3=L2/L4:L6=L5/L7:BOTTOM=L7 |
| BOOTSTRAP_R_9 | OTHERS | BUS | 3 | 5 | 5 | 10 | 5 | 14 | 6 | 10 | 12 | 12 | 12 | 12 |  | 50 Ohms | TOP=L2:L3=L2/L4:L6=L5/L7:BOTTOM=L7 |
| BOOTSTRAP_R_9 | OTHERS | BUS | 4 | 5 | 5 | 10 | 5 | 14 | 6 | 10 | 12 | 12 | 12 | 12 |  | 50 Ohms | TOP=L2:L3=L2/L4:L6=L5/L7:BOTTOM=L7 |
| BOOTSTRAP_R_9 | OTHERS | BUS | 5 | 5 | 5 | 10 | 5 | 14 | 6 | 10 | 12 | 12 | 12 | 12 |  | 50 Ohms | TOP=L2:L3=L2/L4:L6=L5/L7:BOTTOM=L7 |
| BOOTSTRAP_R_9 | OTHERS | BUS | 6 | 5 | 5 | 10 | 5 | 14 | 6 | 10 | 12 | 12 | 12 | 12 |  | 50 Ohms | TOP=L2:L3=L2/L4:L6=L5/L7:BOTTOM=L7 |
| BOOTSTRAP_R_9 | OTHERS | BUS | 7 | 5 | 5 | 10 | 5 | 14 | 6 | 10 | 12 | 12 | 12 | 12 |  | 50 Ohms | TOP=L2:L3=L2/L4:L6=L5/L7:BOTTOM=L7 |
| BOOTSTRAP_R_9 | OTHERS | BUS | 8 | 4.75 | 5 | 10 | 5 | 14 | 6 | 9.5 | 12 | 12 | 12 | 12 |  | 50 Ohms | TOP=L2:L3=L2/L4:L6=L5/L7:BOTTOM=L7 |
| BOOTSTRAP0 | OTHERS | BUS | 1 | 4.75 | 5 | 10 | 5 | 14 | 6 | 9.5 | 12 | 12 | 12 | 12 |  | 50 Ohms | TOP=L2:L3=L2/L4:L6=L5/L7:BOTTOM=L7 |
| BOOTSTRAP0 | OTHERS | BUS | 2 | 5 | 5 | 10 | 5 | 14 | 6 | 10 | 12 | 12 | 12 | 12 |  | 50 Ohms | TOP=L2:L3=L2/L4:L6=L5/L7:BOTTOM=L7 |
| BOOTSTRAP0 | OTHERS | BUS | 3 | 5 | 5 | 10 | 5 | 14 | 6 | 10 | 12 | 12 | 12 | 12 |  | 50 Ohms | TOP=L2:L3=L2/L4:L6=L5/L7:BOTTOM=L7 |
| BOOTSTRAP0 | OTHERS | BUS | 4 | 5 | 5 | 10 | 5 | 14 | 6 | 10 | 12 | 12 | 12 | 12 |  | 50 Ohms | TOP=L2:L3=L2/L4:L6=L5/L7:BOTTOM=L7 |
| BOOTSTRAP0 | OTHERS | BUS | 5 | 5 | 5 | 10 | 5 | 14 | 6 | 10 | 12 | 12 | 12 | 12 |  | 50 Ohms | TOP=L2:L3=L2/L4:L6=L5/L7:BOTTOM=L7 |
| BOOTSTRAP0 | OTHERS | BUS | 6 | 5 | 5 | 10 | 5 | 14 | 6 | 10 | 12 | 12 | 12 | 12 |  | 50 Ohms | TOP=L2:L3=L2/L4:L6=L5/L7:BOTTOM=L7 |
| BOOTSTRAP0 | OTHERS | BUS | 7 | 5 | 5 | 10 | 5 | 14 | 6 | 10 | 12 | 12 | 12 | 12 |  | 50 Ohms | TOP=L2:L3=L2/L4:L6=L5/L7:BOTTOM=L7 |
| BOOTSTRAP0 | OTHERS | BUS | 8 | 4.75 | 5 | 10 | 5 | 14 | 6 | 9.5 | 12 | 12 | 12 | 12 |  | 50 Ohms | TOP=L2:L3=L2/L4:L6=L5/L7:BOTTOM=L7 |
| BOOTSTRAP1 | OTHERS | BUS | 1 | 4.75 | 5 | 10 | 5 | 14 | 6 | 9.5 | 12 | 12 | 12 | 12 |  | 50 Ohms | TOP=L2:L3=L2/L4:L6=L5/L7:BOTTOM=L7 |
| BOOTSTRAP1 | OTHERS | BUS | 2 | 5 | 5 | 10 | 5 | 14 | 6 | 10 | 12 | 12 | 12 | 12 |  | 50 Ohms | TOP=L2:L3=L2/L4:L6=L5/L7:BOTTOM=L7 |
| BOOTSTRAP1 | OTHERS | BUS | 3 | 5 | 5 | 10 | 5 | 14 | 6 | 10 | 12 | 12 | 12 | 12 |  | 50 Ohms | TOP=L2:L3=L2/L4:L6=L5/L7:BOTTOM=L7 |
| BOOTSTRAP1 | OTHERS | BUS | 4 | 5 | 5 | 10 | 5 | 14 | 6 | 10 | 12 | 12 | 12 | 12 |  | 50 Ohms | TOP=L2:L3=L2/L4:L6=L5/L7:BOTTOM=L7 |
| BOOTSTRAP1 | OTHERS | BUS | 5 | 5 | 5 | 10 | 5 | 14 | 6 | 10 | 12 | 12 | 12 | 12 |  | 50 Ohms | TOP=L2:L3=L2/L4:L6=L5/L7:BOTTOM=L7 |
| BOOTSTRAP1 | OTHERS | BUS | 6 | 5 | 5 | 10 | 5 | 14 | 6 | 10 | 12 | 12 | 12 | 12 |  | 50 Ohms | TOP=L2:L3=L2/L4:L6=L5/L7:BOTTOM=L7 |
| BOOTSTRAP1 | OTHERS | BUS | 7 | 5 | 5 | 10 | 5 | 14 | 6 | 10 | 12 | 12 | 12 | 12 |  | 50 Ohms | TOP=L2:L3=L2/L4:L6=L5/L7:BOTTOM=L7 |
| BOOTSTRAP1 | OTHERS | BUS | 8 | 4.75 | 5 | 10 | 5 | 14 | 6 | 9.5 | 12 | 12 | 12 | 12 |  | 50 Ohms | TOP=L2:L3=L2/L4:L6=L5/L7:BOTTOM=L7 |
| BOOTSTRAP10 | OTHERS | BUS | 1 | 4.75 | 5 | 10 | 5 | 14 | 6 | 9.5 | 12 | 12 | 12 | 12 |  | 50 Ohms | TOP=L2:L3=L2/L4:L6=L5/L7:BOTTOM=L7 |
| BOOTSTRAP10 | OTHERS | BUS | 2 | 5 | 5 | 10 | 5 | 14 | 6 | 10 | 12 | 12 | 12 | 12 |  | 50 Ohms | TOP=L2:L3=L2/L4:L6=L5/L7:BOTTOM=L7 |
| BOOTSTRAP10 | OTHERS | BUS | 3 | 5 | 5 | 10 | 5 | 14 | 6 | 10 | 12 | 12 | 12 | 12 |  | 50 Ohms | TOP=L2:L3=L2/L4:L6=L5/L7:BOTTOM=L7 |
| BOOTSTRAP10 | OTHERS | BUS | 4 | 5 | 5 | 10 | 5 | 14 | 6 | 10 | 12 | 12 | 12 | 12 |  | 50 Ohms | TOP=L2:L3=L2/L4:L6=L5/L7:BOTTOM=L7 |
| BOOTSTRAP10 | OTHERS | BUS | 5 | 5 | 5 | 10 | 5 | 14 | 6 | 10 | 12 | 12 | 12 | 12 |  | 50 Ohms | TOP=L2:L3=L2/L4:L6=L5/L7:BOTTOM=L7 |
| BOOTSTRAP10 | OTHERS | BUS | 6 | 5 | 5 | 10 | 5 | 14 | 6 | 10 | 12 | 12 | 12 | 12 |  | 50 Ohms | TOP=L2:L3=L2/L4:L6=L5/L7:BOTTOM=L7 |
| BOOTSTRAP10 | OTHERS | BUS | 7 | 5 | 5 | 10 | 5 | 14 | 6 | 10 | 12 | 12 | 12 | 12 |  | 50 Ohms | TOP=L2:L3=L2/L4:L6=L5/L7:BOTTOM=L7 |
| BOOTSTRAP10 | OTHERS | BUS | 8 | 4.75 | 5 | 10 | 5 | 14 | 6 | 9.5 | 12 | 12 | 12 | 12 |  | 50 Ohms | TOP=L2:L3=L2/L4:L6=L5/L7:BOTTOM=L7 |
| BOOTSTRAP2 | OTHERS | BUS | 1 | 4.75 | 5 | 10 | 5 | 14 | 6 | 9.5 | 12 | 12 | 12 | 12 |  | 50 Ohms | TOP=L2:L3=L2/L4:L6=L5/L7:BOTTOM=L7 |
| BOOTSTRAP2 | OTHERS | BUS | 2 | 5 | 5 | 10 | 5 | 14 | 6 | 10 | 12 | 12 | 12 | 12 |  | 50 Ohms | TOP=L2:L3=L2/L4:L6=L5/L7:BOTTOM=L7 |
| BOOTSTRAP2 | OTHERS | BUS | 3 | 5 | 5 | 10 | 5 | 14 | 6 | 10 | 12 | 12 | 12 | 12 |  | 50 Ohms | TOP=L2:L3=L2/L4:L6=L5/L7:BOTTOM=L7 |
| BOOTSTRAP2 | OTHERS | BUS | 4 | 5 | 5 | 10 | 5 | 14 | 6 | 10 | 12 | 12 | 12 | 12 |  | 50 Ohms | TOP=L2:L3=L2/L4:L6=L5/L7:BOTTOM=L7 |
| BOOTSTRAP2 | OTHERS | BUS | 5 | 5 | 5 | 10 | 5 | 14 | 6 | 10 | 12 | 12 | 12 | 12 |  | 50 Ohms | TOP=L2:L3=L2/L4:L6=L5/L7:BOTTOM=L7 |
| BOOTSTRAP2 | OTHERS | BUS | 6 | 5 | 5 | 10 | 5 | 14 | 6 | 10 | 12 | 12 | 12 | 12 |  | 50 Ohms | TOP=L2:L3=L2/L4:L6=L5/L7:BOTTOM=L7 |
| BOOTSTRAP2 | OTHERS | BUS | 7 | 5 | 5 | 10 | 5 | 14 | 6 | 10 | 12 | 12 | 12 | 12 |  | 50 Ohms | TOP=L2:L3=L2/L4:L6=L5/L7:BOTTOM=L7 |
| BOOTSTRAP2 | OTHERS | BUS | 8 | 4.75 | 5 | 10 | 5 | 14 | 6 | 9.5 | 12 | 12 | 12 | 12 |  | 50 Ohms | TOP=L2:L3=L2/L4:L6=L5/L7:BOTTOM=L7 |
| BOOTSTRAP3 | OTHERS | BUS | 1 | 4.75 | 5 | 10 | 5 | 14 | 6 | 9.5 | 12 | 12 | 12 | 12 |  | 50 Ohms | TOP=L2:L3=L2/L4:L6=L5/L7:BOTTOM=L7 |
| BOOTSTRAP3 | OTHERS | BUS | 2 | 5 | 5 | 10 | 5 | 14 | 6 | 10 | 12 | 12 | 12 | 12 |  | 50 Ohms | TOP=L2:L3=L2/L4:L6=L5/L7:BOTTOM=L7 |
| BOOTSTRAP3 | OTHERS | BUS | 3 | 5 | 5 | 10 | 5 | 14 | 6 | 10 | 12 | 12 | 12 | 12 |  | 50 Ohms | TOP=L2:L3=L2/L4:L6=L5/L7:BOTTOM=L7 |
| BOOTSTRAP3 | OTHERS | BUS | 4 | 5 | 5 | 10 | 5 | 14 | 6 | 10 | 12 | 12 | 12 | 12 |  | 50 Ohms | TOP=L2:L3=L2/L4:L6=L5/L7:BOTTOM=L7 |
| BOOTSTRAP3 | OTHERS | BUS | 5 | 5 | 5 | 10 | 5 | 14 | 6 | 10 | 12 | 12 | 12 | 12 |  | 50 Ohms | TOP=L2:L3=L2/L4:L6=L5/L7:BOTTOM=L7 |
| BOOTSTRAP3 | OTHERS | BUS | 6 | 5 | 5 | 10 | 5 | 14 | 6 | 10 | 12 | 12 | 12 | 12 |  | 50 Ohms | TOP=L2:L3=L2/L4:L6=L5/L7:BOTTOM=L7 |
| BOOTSTRAP3 | OTHERS | BUS | 7 | 5 | 5 | 10 | 5 | 14 | 6 | 10 | 12 | 12 | 12 | 12 |  | 50 Ohms | TOP=L2:L3=L2/L4:L6=L5/L7:BOTTOM=L7 |
| BOOTSTRAP3 | OTHERS | BUS | 8 | 4.75 | 5 | 10 | 5 | 14 | 6 | 9.5 | 12 | 12 | 12 | 12 |  | 50 Ohms | TOP=L2:L3=L2/L4:L6=L5/L7:BOTTOM=L7 |
| BOOTSTRAP4 | OTHERS | BUS | 1 | 4.75 | 5 | 10 | 5 | 14 | 6 | 9.5 | 12 | 12 | 12 | 12 |  | 50 Ohms | TOP=L2:L3=L2/L4:L6=L5/L7:BOTTOM=L7 |
| BOOTSTRAP4 | OTHERS | BUS | 2 | 5 | 5 | 10 | 5 | 14 | 6 | 10 | 12 | 12 | 12 | 12 |  | 50 Ohms | TOP=L2:L3=L2/L4:L6=L5/L7:BOTTOM=L7 |
| BOOTSTRAP4 | OTHERS | BUS | 3 | 5 | 5 | 10 | 5 | 14 | 6 | 10 | 12 | 12 | 12 | 12 |  | 50 Ohms | TOP=L2:L3=L2/L4:L6=L5/L7:BOTTOM=L7 |
| BOOTSTRAP4 | OTHERS | BUS | 4 | 5 | 5 | 10 | 5 | 14 | 6 | 10 | 12 | 12 | 12 | 12 |  | 50 Ohms | TOP=L2:L3=L2/L4:L6=L5/L7:BOTTOM=L7 |
| BOOTSTRAP4 | OTHERS | BUS | 5 | 5 | 5 | 10 | 5 | 14 | 6 | 10 | 12 | 12 | 12 | 12 |  | 50 Ohms | TOP=L2:L3=L2/L4:L6=L5/L7:BOTTOM=L7 |
| BOOTSTRAP4 | OTHERS | BUS | 6 | 5 | 5 | 10 | 5 | 14 | 6 | 10 | 12 | 12 | 12 | 12 |  | 50 Ohms | TOP=L2:L3=L2/L4:L6=L5/L7:BOTTOM=L7 |
| BOOTSTRAP4 | OTHERS | BUS | 7 | 5 | 5 | 10 | 5 | 14 | 6 | 10 | 12 | 12 | 12 | 12 |  | 50 Ohms | TOP=L2:L3=L2/L4:L6=L5/L7:BOTTOM=L7 |
| BOOTSTRAP4 | OTHERS | BUS | 8 | 4.75 | 5 | 10 | 5 | 14 | 6 | 9.5 | 12 | 12 | 12 | 12 |  | 50 Ohms | TOP=L2:L3=L2/L4:L6=L5/L7:BOTTOM=L7 |
| BOOTSTRAP5 | OTHERS | BUS | 1 | 4.75 | 5 | 10 | 5 | 14 | 6 | 9.5 | 12 | 12 | 12 | 12 |  | 50 Ohms | TOP=L2:L3=L2/L4:L6=L5/L7:BOTTOM=L7 |
| BOOTSTRAP5 | OTHERS | BUS | 2 | 5 | 5 | 10 | 5 | 14 | 6 | 10 | 12 | 12 | 12 | 12 |  | 50 Ohms | TOP=L2:L3=L2/L4:L6=L5/L7:BOTTOM=L7 |
| BOOTSTRAP5 | OTHERS | BUS | 3 | 5 | 5 | 10 | 5 | 14 | 6 | 10 | 12 | 12 | 12 | 12 |  | 50 Ohms | TOP=L2:L3=L2/L4:L6=L5/L7:BOTTOM=L7 |
| BOOTSTRAP5 | OTHERS | BUS | 4 | 5 | 5 | 10 | 5 | 14 | 6 | 10 | 12 | 12 | 12 | 12 |  | 50 Ohms | TOP=L2:L3=L2/L4:L6=L5/L7:BOTTOM=L7 |
| BOOTSTRAP5 | OTHERS | BUS | 5 | 5 | 5 | 10 | 5 | 14 | 6 | 10 | 12 | 12 | 12 | 12 |  | 50 Ohms | TOP=L2:L3=L2/L4:L6=L5/L7:BOTTOM=L7 |
| BOOTSTRAP5 | OTHERS | BUS | 6 | 5 | 5 | 10 | 5 | 14 | 6 | 10 | 12 | 12 | 12 | 12 |  | 50 Ohms | TOP=L2:L3=L2/L4:L6=L5/L7:BOTTOM=L7 |
| BOOTSTRAP5 | OTHERS | BUS | 7 | 5 | 5 | 10 | 5 | 14 | 6 | 10 | 12 | 12 | 12 | 12 |  | 50 Ohms | TOP=L2:L3=L2/L4:L6=L5/L7:BOTTOM=L7 |
| BOOTSTRAP5 | OTHERS | BUS | 8 | 4.75 | 5 | 10 | 5 | 14 | 6 | 9.5 | 12 | 12 | 12 | 12 |  | 50 Ohms | TOP=L2:L3=L2/L4:L6=L5/L7:BOTTOM=L7 |
| BOOTSTRAP6 | OTHERS | BUS | 1 | 4.75 | 5 | 10 | 5 | 14 | 6 | 9.5 | 12 | 12 | 12 | 12 |  | 50 Ohms | TOP=L2:L3=L2/L4:L6=L5/L7:BOTTOM=L7 |
| BOOTSTRAP6 | OTHERS | BUS | 2 | 5 | 5 | 10 | 5 | 14 | 6 | 10 | 12 | 12 | 12 | 12 |  | 50 Ohms | TOP=L2:L3=L2/L4:L6=L5/L7:BOTTOM=L7 |
| BOOTSTRAP6 | OTHERS | BUS | 3 | 5 | 5 | 10 | 5 | 14 | 6 | 10 | 12 | 12 | 12 | 12 |  | 50 Ohms | TOP=L2:L3=L2/L4:L6=L5/L7:BOTTOM=L7 |
| BOOTSTRAP6 | OTHERS | BUS | 4 | 5 | 5 | 10 | 5 | 14 | 6 | 10 | 12 | 12 | 12 | 12 |  | 50 Ohms | TOP=L2:L3=L2/L4:L6=L5/L7:BOTTOM=L7 |
| BOOTSTRAP6 | OTHERS | BUS | 5 | 5 | 5 | 10 | 5 | 14 | 6 | 10 | 12 | 12 | 12 | 12 |  | 50 Ohms | TOP=L2:L3=L2/L4:L6=L5/L7:BOTTOM=L7 |
| BOOTSTRAP6 | OTHERS | BUS | 6 | 5 | 5 | 10 | 5 | 14 | 6 | 10 | 12 | 12 | 12 | 12 |  | 50 Ohms | TOP=L2:L3=L2/L4:L6=L5/L7:BOTTOM=L7 |
| BOOTSTRAP6 | OTHERS | BUS | 7 | 5 | 5 | 10 | 5 | 14 | 6 | 10 | 12 | 12 | 12 | 12 |  | 50 Ohms | TOP=L2:L3=L2/L4:L6=L5/L7:BOTTOM=L7 |
| BOOTSTRAP6 | OTHERS | BUS | 8 | 4.75 | 5 | 10 | 5 | 14 | 6 | 9.5 | 12 | 12 | 12 | 12 |  | 50 Ohms | TOP=L2:L3=L2/L4:L6=L5/L7:BOTTOM=L7 |
| BOOTSTRAP7 | OTHERS | BUS | 1 | 4.75 | 5 | 10 | 5 | 14 | 6 | 9.5 | 12 | 12 | 12 | 12 |  | 50 Ohms | TOP=L2:L3=L2/L4:L6=L5/L7:BOTTOM=L7 |
| BOOTSTRAP7 | OTHERS | BUS | 2 | 5 | 5 | 10 | 5 | 14 | 6 | 10 | 12 | 12 | 12 | 12 |  | 50 Ohms | TOP=L2:L3=L2/L4:L6=L5/L7:BOTTOM=L7 |
| BOOTSTRAP7 | OTHERS | BUS | 3 | 5 | 5 | 10 | 5 | 14 | 6 | 10 | 12 | 12 | 12 | 12 |  | 50 Ohms | TOP=L2:L3=L2/L4:L6=L5/L7:BOTTOM=L7 |
| BOOTSTRAP7 | OTHERS | BUS | 4 | 5 | 5 | 10 | 5 | 14 | 6 | 10 | 12 | 12 | 12 | 12 |  | 50 Ohms | TOP=L2:L3=L2/L4:L6=L5/L7:BOTTOM=L7 |
| BOOTSTRAP7 | OTHERS | BUS | 5 | 5 | 5 | 10 | 5 | 14 | 6 | 10 | 12 | 12 | 12 | 12 |  | 50 Ohms | TOP=L2:L3=L2/L4:L6=L5/L7:BOTTOM=L7 |
| BOOTSTRAP7 | OTHERS | BUS | 6 | 5 | 5 | 10 | 5 | 14 | 6 | 10 | 12 | 12 | 12 | 12 |  | 50 Ohms | TOP=L2:L3=L2/L4:L6=L5/L7:BOTTOM=L7 |
| BOOTSTRAP7 | OTHERS | BUS | 7 | 5 | 5 | 10 | 5 | 14 | 6 | 10 | 12 | 12 | 12 | 12 |  | 50 Ohms | TOP=L2:L3=L2/L4:L6=L5/L7:BOTTOM=L7 |
| BOOTSTRAP7 | OTHERS | BUS | 8 | 4.75 | 5 | 10 | 5 | 14 | 6 | 9.5 | 12 | 12 | 12 | 12 |  | 50 Ohms | TOP=L2:L3=L2/L4:L6=L5/L7:BOTTOM=L7 |
| BOOTSTRAP8 | OTHERS | BUS | 1 | 4.75 | 5 | 10 | 5 | 14 | 6 | 9.5 | 12 | 12 | 12 | 12 |  | 50 Ohms | TOP=L2:L3=L2/L4:L6=L5/L7:BOTTOM=L7 |
| BOOTSTRAP8 | OTHERS | BUS | 2 | 5 | 5 | 10 | 5 | 14 | 6 | 10 | 12 | 12 | 12 | 12 |  | 50 Ohms | TOP=L2:L3=L2/L4:L6=L5/L7:BOTTOM=L7 |
| BOOTSTRAP8 | OTHERS | BUS | 3 | 5 | 5 | 10 | 5 | 14 | 6 | 10 | 12 | 12 | 12 | 12 |  | 50 Ohms | TOP=L2:L3=L2/L4:L6=L5/L7:BOTTOM=L7 |
| BOOTSTRAP8 | OTHERS | BUS | 4 | 5 | 5 | 10 | 5 | 14 | 6 | 10 | 12 | 12 | 12 | 12 |  | 50 Ohms | TOP=L2:L3=L2/L4:L6=L5/L7:BOTTOM=L7 |
| BOOTSTRAP8 | OTHERS | BUS | 5 | 5 | 5 | 10 | 5 | 14 | 6 | 10 | 12 | 12 | 12 | 12 |  | 50 Ohms | TOP=L2:L3=L2/L4:L6=L5/L7:BOTTOM=L7 |
| BOOTSTRAP8 | OTHERS | BUS | 6 | 5 | 5 | 10 | 5 | 14 | 6 | 10 | 12 | 12 | 12 | 12 |  | 50 Ohms | TOP=L2:L3=L2/L4:L6=L5/L7:BOTTOM=L7 |
| BOOTSTRAP8 | OTHERS | BUS | 7 | 5 | 5 | 10 | 5 | 14 | 6 | 10 | 12 | 12 | 12 | 12 |  | 50 Ohms | TOP=L2:L3=L2/L4:L6=L5/L7:BOTTOM=L7 |
| BOOTSTRAP8 | OTHERS | BUS | 8 | 4.75 | 5 | 10 | 5 | 14 | 6 | 9.5 | 12 | 12 | 12 | 12 |  | 50 Ohms | TOP=L2:L3=L2/L4:L6=L5/L7:BOTTOM=L7 |
| BOOTSTRAP9 | OTHERS | BUS | 1 | 4.75 | 5 | 10 | 5 | 14 | 6 | 9.5 | 12 | 12 | 12 | 12 |  | 50 Ohms | TOP=L2:L3=L2/L4:L6=L5/L7:BOTTOM=L7 |
| BOOTSTRAP9 | OTHERS | BUS | 2 | 5 | 5 | 10 | 5 | 14 | 6 | 10 | 12 | 12 | 12 | 12 |  | 50 Ohms | TOP=L2:L3=L2/L4:L6=L5/L7:BOTTOM=L7 |
| BOOTSTRAP9 | OTHERS | BUS | 3 | 5 | 5 | 10 | 5 | 14 | 6 | 10 | 12 | 12 | 12 | 12 |  | 50 Ohms | TOP=L2:L3=L2/L4:L6=L5/L7:BOTTOM=L7 |
| BOOTSTRAP9 | OTHERS | BUS | 4 | 5 | 5 | 10 | 5 | 14 | 6 | 10 | 12 | 12 | 12 | 12 |  | 50 Ohms | TOP=L2:L3=L2/L4:L6=L5/L7:BOTTOM=L7 |
| BOOTSTRAP9 | OTHERS | BUS | 5 | 5 | 5 | 10 | 5 | 14 | 6 | 10 | 12 | 12 | 12 | 12 |  | 50 Ohms | TOP=L2:L3=L2/L4:L6=L5/L7:BOTTOM=L7 |
| BOOTSTRAP9 | OTHERS | BUS | 6 | 5 | 5 | 10 | 5 | 14 | 6 | 10 | 12 | 12 | 12 | 12 |  | 50 Ohms | TOP=L2:L3=L2/L4:L6=L5/L7:BOTTOM=L7 |
| BOOTSTRAP9 | OTHERS | BUS | 7 | 5 | 5 | 10 | 5 | 14 | 6 | 10 | 12 | 12 | 12 | 12 |  | 50 Ohms | TOP=L2:L3=L2/L4:L6=L5/L7:BOTTOM=L7 |
| BOOTSTRAP9 | OTHERS | BUS | 8 | 4.75 | 5 | 10 | 5 | 14 | 6 | 9.5 | 12 | 12 | 12 | 12 |  | 50 Ohms | TOP=L2:L3=L2/L4:L6=L5/L7:BOTTOM=L7 |
| BP_PRSNT_N | OTHERS | BUS | 1 | 4.75 | 5 | 10 | 5 | 14 | 6 | 9.5 | 12 | 12 | 12 | 12 |  | 50 Ohms | TOP=L2:L3=L2/L4:L6=L5/L7:BOTTOM=L7 |
| BP_PRSNT_N | OTHERS | BUS | 2 | 5 | 5 | 10 | 5 | 14 | 6 | 10 | 12 | 12 | 12 | 12 |  | 50 Ohms | TOP=L2:L3=L2/L4:L6=L5/L7:BOTTOM=L7 |
| BP_PRSNT_N | OTHERS | BUS | 3 | 5 | 5 | 10 | 5 | 14 | 6 | 10 | 12 | 12 | 12 | 12 |  | 50 Ohms | TOP=L2:L3=L2/L4:L6=L5/L7:BOTTOM=L7 |
| BP_PRSNT_N | OTHERS | BUS | 4 | 5 | 5 | 10 | 5 | 14 | 6 | 10 | 12 | 12 | 12 | 12 |  | 50 Ohms | TOP=L2:L3=L2/L4:L6=L5/L7:BOTTOM=L7 |
| BP_PRSNT_N | OTHERS | BUS | 5 | 5 | 5 | 10 | 5 | 14 | 6 | 10 | 12 | 12 | 12 | 12 |  | 50 Ohms | TOP=L2:L3=L2/L4:L6=L5/L7:BOTTOM=L7 |
| BP_PRSNT_N | OTHERS | BUS | 6 | 5 | 5 | 10 | 5 | 14 | 6 | 10 | 12 | 12 | 12 | 12 |  | 50 Ohms | TOP=L2:L3=L2/L4:L6=L5/L7:BOTTOM=L7 |
| BP_PRSNT_N | OTHERS | BUS | 7 | 5 | 5 | 10 | 5 | 14 | 6 | 10 | 12 | 12 | 12 | 12 |  | 50 Ohms | TOP=L2:L3=L2/L4:L6=L5/L7:BOTTOM=L7 |
| BP_PRSNT_N | OTHERS | BUS | 8 | 4.75 | 5 | 10 | 5 | 14 | 6 | 9.5 | 12 | 12 | 12 | 12 |  | 50 Ohms | TOP=L2:L3=L2/L4:L6=L5/L7:BOTTOM=L7 |
| BUS_SW_OE# | OTHERS | BUS | 1 | 4.75 | 5 | 10 | 5 | 14 | 6 | 9.5 | 12 | 12 | 12 | 12 |  | 50 Ohms | TOP=L2:L3=L2/L4:L6=L5/L7:BOTTOM=L7 |
| BUS_SW_OE# | OTHERS | BUS | 2 | 5 | 5 | 10 | 5 | 14 | 6 | 10 | 12 | 12 | 12 | 12 |  | 50 Ohms | TOP=L2:L3=L2/L4:L6=L5/L7:BOTTOM=L7 |
| BUS_SW_OE# | OTHERS | BUS | 3 | 5 | 5 | 10 | 5 | 14 | 6 | 10 | 12 | 12 | 12 | 12 |  | 50 Ohms | TOP=L2:L3=L2/L4:L6=L5/L7:BOTTOM=L7 |
| BUS_SW_OE# | OTHERS | BUS | 4 | 5 | 5 | 10 | 5 | 14 | 6 | 10 | 12 | 12 | 12 | 12 |  | 50 Ohms | TOP=L2:L3=L2/L4:L6=L5/L7:BOTTOM=L7 |
| BUS_SW_OE# | OTHERS | BUS | 5 | 5 | 5 | 10 | 5 | 14 | 6 | 10 | 12 | 12 | 12 | 12 |  | 50 Ohms | TOP=L2:L3=L2/L4:L6=L5/L7:BOTTOM=L7 |
| BUS_SW_OE# | OTHERS | BUS | 6 | 5 | 5 | 10 | 5 | 14 | 6 | 10 | 12 | 12 | 12 | 12 |  | 50 Ohms | TOP=L2:L3=L2/L4:L6=L5/L7:BOTTOM=L7 |
| BUS_SW_OE# | OTHERS | BUS | 7 | 5 | 5 | 10 | 5 | 14 | 6 | 10 | 12 | 12 | 12 | 12 |  | 50 Ohms | TOP=L2:L3=L2/L4:L6=L5/L7:BOTTOM=L7 |
| BUS_SW_OE# | OTHERS | BUS | 8 | 4.75 | 5 | 10 | 5 | 14 | 6 | 9.5 | 12 | 12 | 12 | 12 |  | 50 Ohms | TOP=L2:L3=L2/L4:L6=L5/L7:BOTTOM=L7 |
| CBL_PRSNT_N_1 | OTHERS | BUS | 1 | 4.75 | 5 | 10 | 5 | 14 | 6 | 9.5 | 12 | 12 | 12 | 12 |  | 50 Ohms | TOP=L2:L3=L2/L4:L6=L5/L7:BOTTOM=L7 |
| CBL_PRSNT_N_1 | OTHERS | BUS | 2 | 5 | 5 | 10 | 5 | 14 | 6 | 10 | 12 | 12 | 12 | 12 |  | 50 Ohms | TOP=L2:L3=L2/L4:L6=L5/L7:BOTTOM=L7 |
| CBL_PRSNT_N_1 | OTHERS | BUS | 3 | 5 | 5 | 10 | 5 | 14 | 6 | 10 | 12 | 12 | 12 | 12 |  | 50 Ohms | TOP=L2:L3=L2/L4:L6=L5/L7:BOTTOM=L7 |
| CBL_PRSNT_N_1 | OTHERS | BUS | 4 | 5 | 5 | 10 | 5 | 14 | 6 | 10 | 12 | 12 | 12 | 12 |  | 50 Ohms | TOP=L2:L3=L2/L4:L6=L5/L7:BOTTOM=L7 |
| CBL_PRSNT_N_1 | OTHERS | BUS | 5 | 5 | 5 | 10 | 5 | 14 | 6 | 10 | 12 | 12 | 12 | 12 |  | 50 Ohms | TOP=L2:L3=L2/L4:L6=L5/L7:BOTTOM=L7 |
| CBL_PRSNT_N_1 | OTHERS | BUS | 6 | 5 | 5 | 10 | 5 | 14 | 6 | 10 | 12 | 12 | 12 | 12 |  | 50 Ohms | TOP=L2:L3=L2/L4:L6=L5/L7:BOTTOM=L7 |
| CBL_PRSNT_N_1 | OTHERS | BUS | 7 | 5 | 5 | 10 | 5 | 14 | 6 | 10 | 12 | 12 | 12 | 12 |  | 50 Ohms | TOP=L2:L3=L2/L4:L6=L5/L7:BOTTOM=L7 |
| CBL_PRSNT_N_1 | OTHERS | BUS | 8 | 4.75 | 5 | 10 | 5 | 14 | 6 | 9.5 | 12 | 12 | 12 | 12 |  | 50 Ohms | TOP=L2:L3=L2/L4:L6=L5/L7:BOTTOM=L7 |
| CBL_PRSNT_N_2 | OTHERS | BUS | 1 | 4.75 | 5 | 10 | 5 | 14 | 6 | 9.5 | 12 | 12 | 12 | 12 |  | 50 Ohms | TOP=L2:L3=L2/L4:L6=L5/L7:BOTTOM=L7 |
| CBL_PRSNT_N_2 | OTHERS | BUS | 2 | 5 | 5 | 10 | 5 | 14 | 6 | 10 | 12 | 12 | 12 | 12 |  | 50 Ohms | TOP=L2:L3=L2/L4:L6=L5/L7:BOTTOM=L7 |
| CBL_PRSNT_N_2 | OTHERS | BUS | 3 | 5 | 5 | 10 | 5 | 14 | 6 | 10 | 12 | 12 | 12 | 12 |  | 50 Ohms | TOP=L2:L3=L2/L4:L6=L5/L7:BOTTOM=L7 |
| CBL_PRSNT_N_2 | OTHERS | BUS | 4 | 5 | 5 | 10 | 5 | 14 | 6 | 10 | 12 | 12 | 12 | 12 |  | 50 Ohms | TOP=L2:L3=L2/L4:L6=L5/L7:BOTTOM=L7 |
| CBL_PRSNT_N_2 | OTHERS | BUS | 5 | 5 | 5 | 10 | 5 | 14 | 6 | 10 | 12 | 12 | 12 | 12 |  | 50 Ohms | TOP=L2:L3=L2/L4:L6=L5/L7:BOTTOM=L7 |
| CBL_PRSNT_N_2 | OTHERS | BUS | 6 | 5 | 5 | 10 | 5 | 14 | 6 | 10 | 12 | 12 | 12 | 12 |  | 50 Ohms | TOP=L2:L3=L2/L4:L6=L5/L7:BOTTOM=L7 |
| CBL_PRSNT_N_2 | OTHERS | BUS | 7 | 5 | 5 | 10 | 5 | 14 | 6 | 10 | 12 | 12 | 12 | 12 |  | 50 Ohms | TOP=L2:L3=L2/L4:L6=L5/L7:BOTTOM=L7 |
| CBL_PRSNT_N_2 | OTHERS | BUS | 8 | 4.75 | 5 | 10 | 5 | 14 | 6 | 9.5 | 12 | 12 | 12 | 12 |  | 50 Ohms | TOP=L2:L3=L2/L4:L6=L5/L7:BOTTOM=L7 |
| CBL_PRSNT_N_3 | OTHERS | BUS | 1 | 4.75 | 5 | 10 | 5 | 14 | 6 | 9.5 | 12 | 12 | 12 | 12 |  | 50 Ohms | TOP=L2:L3=L2/L4:L6=L5/L7:BOTTOM=L7 |
| CBL_PRSNT_N_3 | OTHERS | BUS | 2 | 5 | 5 | 10 | 5 | 14 | 6 | 10 | 12 | 12 | 12 | 12 |  | 50 Ohms | TOP=L2:L3=L2/L4:L6=L5/L7:BOTTOM=L7 |
| CBL_PRSNT_N_3 | OTHERS | BUS | 3 | 5 | 5 | 10 | 5 | 14 | 6 | 10 | 12 | 12 | 12 | 12 |  | 50 Ohms | TOP=L2:L3=L2/L4:L6=L5/L7:BOTTOM=L7 |
| CBL_PRSNT_N_3 | OTHERS | BUS | 4 | 5 | 5 | 10 | 5 | 14 | 6 | 10 | 12 | 12 | 12 | 12 |  | 50 Ohms | TOP=L2:L3=L2/L4:L6=L5/L7:BOTTOM=L7 |
| CBL_PRSNT_N_3 | OTHERS | BUS | 5 | 5 | 5 | 10 | 5 | 14 | 6 | 10 | 12 | 12 | 12 | 12 |  | 50 Ohms | TOP=L2:L3=L2/L4:L6=L5/L7:BOTTOM=L7 |
| CBL_PRSNT_N_3 | OTHERS | BUS | 6 | 5 | 5 | 10 | 5 | 14 | 6 | 10 | 12 | 12 | 12 | 12 |  | 50 Ohms | TOP=L2:L3=L2/L4:L6=L5/L7:BOTTOM=L7 |
| CBL_PRSNT_N_3 | OTHERS | BUS | 7 | 5 | 5 | 10 | 5 | 14 | 6 | 10 | 12 | 12 | 12 | 12 |  | 50 Ohms | TOP=L2:L3=L2/L4:L6=L5/L7:BOTTOM=L7 |
| CBL_PRSNT_N_3 | OTHERS | BUS | 8 | 4.75 | 5 | 10 | 5 | 14 | 6 | 9.5 | 12 | 12 | 12 | 12 |  | 50 Ohms | TOP=L2:L3=L2/L4:L6=L5/L7:BOTTOM=L7 |
| CBL_PRSNT_N_4 | OTHERS | BUS | 1 | 4.75 | 5 | 10 | 5 | 14 | 6 | 9.5 | 12 | 12 | 12 | 12 |  | 50 Ohms | TOP=L2:L3=L2/L4:L6=L5/L7:BOTTOM=L7 |
| CBL_PRSNT_N_4 | OTHERS | BUS | 2 | 5 | 5 | 10 | 5 | 14 | 6 | 10 | 12 | 12 | 12 | 12 |  | 50 Ohms | TOP=L2:L3=L2/L4:L6=L5/L7:BOTTOM=L7 |
| CBL_PRSNT_N_4 | OTHERS | BUS | 3 | 5 | 5 | 10 | 5 | 14 | 6 | 10 | 12 | 12 | 12 | 12 |  | 50 Ohms | TOP=L2:L3=L2/L4:L6=L5/L7:BOTTOM=L7 |
| CBL_PRSNT_N_4 | OTHERS | BUS | 4 | 5 | 5 | 10 | 5 | 14 | 6 | 10 | 12 | 12 | 12 | 12 |  | 50 Ohms | TOP=L2:L3=L2/L4:L6=L5/L7:BOTTOM=L7 |
| CBL_PRSNT_N_4 | OTHERS | BUS | 5 | 5 | 5 | 10 | 5 | 14 | 6 | 10 | 12 | 12 | 12 | 12 |  | 50 Ohms | TOP=L2:L3=L2/L4:L6=L5/L7:BOTTOM=L7 |
| CBL_PRSNT_N_4 | OTHERS | BUS | 6 | 5 | 5 | 10 | 5 | 14 | 6 | 10 | 12 | 12 | 12 | 12 |  | 50 Ohms | TOP=L2:L3=L2/L4:L6=L5/L7:BOTTOM=L7 |
| CBL_PRSNT_N_4 | OTHERS | BUS | 7 | 5 | 5 | 10 | 5 | 14 | 6 | 10 | 12 | 12 | 12 | 12 |  | 50 Ohms | TOP=L2:L3=L2/L4:L6=L5/L7:BOTTOM=L7 |
| CBL_PRSNT_N_4 | OTHERS | BUS | 8 | 4.75 | 5 | 10 | 5 | 14 | 6 | 9.5 | 12 | 12 | 12 | 12 |  | 50 Ohms | TOP=L2:L3=L2/L4:L6=L5/L7:BOTTOM=L7 |
| CBL_PRSNT_N_5 | OTHERS | BUS | 1 | 4.75 | 5 | 10 | 5 | 14 | 6 | 9.5 | 12 | 12 | 12 | 12 |  | 50 Ohms | TOP=L2:L3=L2/L4:L6=L5/L7:BOTTOM=L7 |
| CBL_PRSNT_N_5 | OTHERS | BUS | 2 | 5 | 5 | 10 | 5 | 14 | 6 | 10 | 12 | 12 | 12 | 12 |  | 50 Ohms | TOP=L2:L3=L2/L4:L6=L5/L7:BOTTOM=L7 |
| CBL_PRSNT_N_5 | OTHERS | BUS | 3 | 5 | 5 | 10 | 5 | 14 | 6 | 10 | 12 | 12 | 12 | 12 |  | 50 Ohms | TOP=L2:L3=L2/L4:L6=L5/L7:BOTTOM=L7 |
| CBL_PRSNT_N_5 | OTHERS | BUS | 4 | 5 | 5 | 10 | 5 | 14 | 6 | 10 | 12 | 12 | 12 | 12 |  | 50 Ohms | TOP=L2:L3=L2/L4:L6=L5/L7:BOTTOM=L7 |
| CBL_PRSNT_N_5 | OTHERS | BUS | 5 | 5 | 5 | 10 | 5 | 14 | 6 | 10 | 12 | 12 | 12 | 12 |  | 50 Ohms | TOP=L2:L3=L2/L4:L6=L5/L7:BOTTOM=L7 |
| CBL_PRSNT_N_5 | OTHERS | BUS | 6 | 5 | 5 | 10 | 5 | 14 | 6 | 10 | 12 | 12 | 12 | 12 |  | 50 Ohms | TOP=L2:L3=L2/L4:L6=L5/L7:BOTTOM=L7 |
| CBL_PRSNT_N_5 | OTHERS | BUS | 7 | 5 | 5 | 10 | 5 | 14 | 6 | 10 | 12 | 12 | 12 | 12 |  | 50 Ohms | TOP=L2:L3=L2/L4:L6=L5/L7:BOTTOM=L7 |
| CBL_PRSNT_N_5 | OTHERS | BUS | 8 | 4.75 | 5 | 10 | 5 | 14 | 6 | 9.5 | 12 | 12 | 12 | 12 |  | 50 Ohms | TOP=L2:L3=L2/L4:L6=L5/L7:BOTTOM=L7 |
| CBL_PRSNT_N_6 | OTHERS | BUS | 1 | 4.75 | 5 | 10 | 5 | 14 | 6 | 9.5 | 12 | 12 | 12 | 12 |  | 50 Ohms | TOP=L2:L3=L2/L4:L6=L5/L7:BOTTOM=L7 |
| CBL_PRSNT_N_6 | OTHERS | BUS | 2 | 5 | 5 | 10 | 5 | 14 | 6 | 10 | 12 | 12 | 12 | 12 |  | 50 Ohms | TOP=L2:L3=L2/L4:L6=L5/L7:BOTTOM=L7 |
| CBL_PRSNT_N_6 | OTHERS | BUS | 3 | 5 | 5 | 10 | 5 | 14 | 6 | 10 | 12 | 12 | 12 | 12 |  | 50 Ohms | TOP=L2:L3=L2/L4:L6=L5/L7:BOTTOM=L7 |
| CBL_PRSNT_N_6 | OTHERS | BUS | 4 | 5 | 5 | 10 | 5 | 14 | 6 | 10 | 12 | 12 | 12 | 12 |  | 50 Ohms | TOP=L2:L3=L2/L4:L6=L5/L7:BOTTOM=L7 |
| CBL_PRSNT_N_6 | OTHERS | BUS | 5 | 5 | 5 | 10 | 5 | 14 | 6 | 10 | 12 | 12 | 12 | 12 |  | 50 Ohms | TOP=L2:L3=L2/L4:L6=L5/L7:BOTTOM=L7 |
| CBL_PRSNT_N_6 | OTHERS | BUS | 6 | 5 | 5 | 10 | 5 | 14 | 6 | 10 | 12 | 12 | 12 | 12 |  | 50 Ohms | TOP=L2:L3=L2/L4:L6=L5/L7:BOTTOM=L7 |
| CBL_PRSNT_N_6 | OTHERS | BUS | 7 | 5 | 5 | 10 | 5 | 14 | 6 | 10 | 12 | 12 | 12 | 12 |  | 50 Ohms | TOP=L2:L3=L2/L4:L6=L5/L7:BOTTOM=L7 |
| CBL_PRSNT_N_6 | OTHERS | BUS | 8 | 4.75 | 5 | 10 | 5 | 14 | 6 | 9.5 | 12 | 12 | 12 | 12 |  | 50 Ohms | TOP=L2:L3=L2/L4:L6=L5/L7:BOTTOM=L7 |
| CBL_PRSNT_N_7 | OTHERS | BUS | 1 | 4.75 | 5 | 10 | 5 | 14 | 6 | 9.5 | 12 | 12 | 12 | 12 |  | 50 Ohms | TOP=L2:L3=L2/L4:L6=L5/L7:BOTTOM=L7 |
| CBL_PRSNT_N_7 | OTHERS | BUS | 2 | 5 | 5 | 10 | 5 | 14 | 6 | 10 | 12 | 12 | 12 | 12 |  | 50 Ohms | TOP=L2:L3=L2/L4:L6=L5/L7:BOTTOM=L7 |
| CBL_PRSNT_N_7 | OTHERS | BUS | 3 | 5 | 5 | 10 | 5 | 14 | 6 | 10 | 12 | 12 | 12 | 12 |  | 50 Ohms | TOP=L2:L3=L2/L4:L6=L5/L7:BOTTOM=L7 |
| CBL_PRSNT_N_7 | OTHERS | BUS | 4 | 5 | 5 | 10 | 5 | 14 | 6 | 10 | 12 | 12 | 12 | 12 |  | 50 Ohms | TOP=L2:L3=L2/L4:L6=L5/L7:BOTTOM=L7 |
| CBL_PRSNT_N_7 | OTHERS | BUS | 5 | 5 | 5 | 10 | 5 | 14 | 6 | 10 | 12 | 12 | 12 | 12 |  | 50 Ohms | TOP=L2:L3=L2/L4:L6=L5/L7:BOTTOM=L7 |
| CBL_PRSNT_N_7 | OTHERS | BUS | 6 | 5 | 5 | 10 | 5 | 14 | 6 | 10 | 12 | 12 | 12 | 12 |  | 50 Ohms | TOP=L2:L3=L2/L4:L6=L5/L7:BOTTOM=L7 |
| CBL_PRSNT_N_7 | OTHERS | BUS | 7 | 5 | 5 | 10 | 5 | 14 | 6 | 10 | 12 | 12 | 12 | 12 |  | 50 Ohms | TOP=L2:L3=L2/L4:L6=L5/L7:BOTTOM=L7 |
| CBL_PRSNT_N_7 | OTHERS | BUS | 8 | 4.75 | 5 | 10 | 5 | 14 | 6 | 9.5 | 12 | 12 | 12 | 12 |  | 50 Ohms | TOP=L2:L3=L2/L4:L6=L5/L7:BOTTOM=L7 |
| CBL_PRSNT_N_8 | OTHERS | BUS | 1 | 4.75 | 5 | 10 | 5 | 14 | 6 | 9.5 | 12 | 12 | 12 | 12 |  | 50 Ohms | TOP=L2:L3=L2/L4:L6=L5/L7:BOTTOM=L7 |
| CBL_PRSNT_N_8 | OTHERS | BUS | 2 | 5 | 5 | 10 | 5 | 14 | 6 | 10 | 12 | 12 | 12 | 12 |  | 50 Ohms | TOP=L2:L3=L2/L4:L6=L5/L7:BOTTOM=L7 |
| CBL_PRSNT_N_8 | OTHERS | BUS | 3 | 5 | 5 | 10 | 5 | 14 | 6 | 10 | 12 | 12 | 12 | 12 |  | 50 Ohms | TOP=L2:L3=L2/L4:L6=L5/L7:BOTTOM=L7 |
| CBL_PRSNT_N_8 | OTHERS | BUS | 4 | 5 | 5 | 10 | 5 | 14 | 6 | 10 | 12 | 12 | 12 | 12 |  | 50 Ohms | TOP=L2:L3=L2/L4:L6=L5/L7:BOTTOM=L7 |
| CBL_PRSNT_N_8 | OTHERS | BUS | 5 | 5 | 5 | 10 | 5 | 14 | 6 | 10 | 12 | 12 | 12 | 12 |  | 50 Ohms | TOP=L2:L3=L2/L4:L6=L5/L7:BOTTOM=L7 |
| CBL_PRSNT_N_8 | OTHERS | BUS | 6 | 5 | 5 | 10 | 5 | 14 | 6 | 10 | 12 | 12 | 12 | 12 |  | 50 Ohms | TOP=L2:L3=L2/L4:L6=L5/L7:BOTTOM=L7 |
| CBL_PRSNT_N_8 | OTHERS | BUS | 7 | 5 | 5 | 10 | 5 | 14 | 6 | 10 | 12 | 12 | 12 | 12 |  | 50 Ohms | TOP=L2:L3=L2/L4:L6=L5/L7:BOTTOM=L7 |
| CBL_PRSNT_N_8 | OTHERS | BUS | 8 | 4.75 | 5 | 10 | 5 | 14 | 6 | 9.5 | 12 | 12 | 12 | 12 |  | 50 Ohms | TOP=L2:L3=L2/L4:L6=L5/L7:BOTTOM=L7 |
| CLK_50M_BMC_NCSI | OTHERS | BUS | 1 | 4.75 | 5 | 10 | 5 | 14 | 6 | 9.5 | 12 | 12 | 12 | 12 |  | 50 Ohms | TOP=L2:L3=L2/L4:L6=L5/L7:BOTTOM=L7 |
| CLK_50M_BMC_NCSI | OTHERS | BUS | 2 | 5 | 5 | 10 | 5 | 14 | 6 | 10 | 12 | 12 | 12 | 12 |  | 50 Ohms | TOP=L2:L3=L2/L4:L6=L5/L7:BOTTOM=L7 |
| CLK_50M_BMC_NCSI | OTHERS | BUS | 3 | 5 | 5 | 10 | 5 | 14 | 6 | 10 | 12 | 12 | 12 | 12 |  | 50 Ohms | TOP=L2:L3=L2/L4:L6=L5/L7:BOTTOM=L7 |
| CLK_50M_BMC_NCSI | OTHERS | BUS | 4 | 5 | 5 | 10 | 5 | 14 | 6 | 10 | 12 | 12 | 12 | 12 |  | 50 Ohms | TOP=L2:L3=L2/L4:L6=L5/L7:BOTTOM=L7 |
| CLK_50M_BMC_NCSI | OTHERS | BUS | 5 | 5 | 5 | 10 | 5 | 14 | 6 | 10 | 12 | 12 | 12 | 12 |  | 50 Ohms | TOP=L2:L3=L2/L4:L6=L5/L7:BOTTOM=L7 |
| CLK_50M_BMC_NCSI | OTHERS | BUS | 6 | 5 | 5 | 10 | 5 | 14 | 6 | 10 | 12 | 12 | 12 | 12 |  | 50 Ohms | TOP=L2:L3=L2/L4:L6=L5/L7:BOTTOM=L7 |
| CLK_50M_BMC_NCSI | OTHERS | BUS | 7 | 5 | 5 | 10 | 5 | 14 | 6 | 10 | 12 | 12 | 12 | 12 |  | 50 Ohms | TOP=L2:L3=L2/L4:L6=L5/L7:BOTTOM=L7 |
| CLK_50M_BMC_NCSI | OTHERS | BUS | 8 | 4.75 | 5 | 10 | 5 | 14 | 6 | 9.5 | 12 | 12 | 12 | 12 |  | 50 Ohms | TOP=L2:L3=L2/L4:L6=L5/L7:BOTTOM=L7 |
| CLK_50M_BMC_NCSI_R | OTHERS | BUS | 1 | 4.75 | 5 | 10 | 5 | 14 | 6 | 9.5 | 12 | 12 | 12 | 12 |  | 50 Ohms | TOP=L2:L3=L2/L4:L6=L5/L7:BOTTOM=L7 |
| CLK_50M_BMC_NCSI_R | OTHERS | BUS | 2 | 5 | 5 | 10 | 5 | 14 | 6 | 10 | 12 | 12 | 12 | 12 |  | 50 Ohms | TOP=L2:L3=L2/L4:L6=L5/L7:BOTTOM=L7 |
| CLK_50M_BMC_NCSI_R | OTHERS | BUS | 3 | 5 | 5 | 10 | 5 | 14 | 6 | 10 | 12 | 12 | 12 | 12 |  | 50 Ohms | TOP=L2:L3=L2/L4:L6=L5/L7:BOTTOM=L7 |
| CLK_50M_BMC_NCSI_R | OTHERS | BUS | 4 | 5 | 5 | 10 | 5 | 14 | 6 | 10 | 12 | 12 | 12 | 12 |  | 50 Ohms | TOP=L2:L3=L2/L4:L6=L5/L7:BOTTOM=L7 |
| CLK_50M_BMC_NCSI_R | OTHERS | BUS | 5 | 5 | 5 | 10 | 5 | 14 | 6 | 10 | 12 | 12 | 12 | 12 |  | 50 Ohms | TOP=L2:L3=L2/L4:L6=L5/L7:BOTTOM=L7 |
| CLK_50M_BMC_NCSI_R | OTHERS | BUS | 6 | 5 | 5 | 10 | 5 | 14 | 6 | 10 | 12 | 12 | 12 | 12 |  | 50 Ohms | TOP=L2:L3=L2/L4:L6=L5/L7:BOTTOM=L7 |
| CLK_50M_BMC_NCSI_R | OTHERS | BUS | 7 | 5 | 5 | 10 | 5 | 14 | 6 | 10 | 12 | 12 | 12 | 12 |  | 50 Ohms | TOP=L2:L3=L2/L4:L6=L5/L7:BOTTOM=L7 |
| CLK_50M_BMC_NCSI_R | OTHERS | BUS | 8 | 4.75 | 5 | 10 | 5 | 14 | 6 | 9.5 | 12 | 12 | 12 | 12 |  | 50 Ohms | TOP=L2:L3=L2/L4:L6=L5/L7:BOTTOM=L7 |
| CLK_50M_BMC0 | OTHERS | BUS | 1 | 4.75 | 5 | 10 | 5 | 14 | 6 | 9.5 | 12 | 12 | 12 | 12 |  | 50 Ohms | TOP=L2:L3=L2/L4:L6=L5/L7:BOTTOM=L7 |
| CLK_50M_BMC0 | OTHERS | BUS | 2 | 5 | 5 | 10 | 5 | 14 | 6 | 10 | 12 | 12 | 12 | 12 |  | 50 Ohms | TOP=L2:L3=L2/L4:L6=L5/L7:BOTTOM=L7 |
| CLK_50M_BMC0 | OTHERS | BUS | 3 | 5 | 5 | 10 | 5 | 14 | 6 | 10 | 12 | 12 | 12 | 12 |  | 50 Ohms | TOP=L2:L3=L2/L4:L6=L5/L7:BOTTOM=L7 |
| CLK_50M_BMC0 | OTHERS | BUS | 4 | 5 | 5 | 10 | 5 | 14 | 6 | 10 | 12 | 12 | 12 | 12 |  | 50 Ohms | TOP=L2:L3=L2/L4:L6=L5/L7:BOTTOM=L7 |
| CLK_50M_BMC0 | OTHERS | BUS | 5 | 5 | 5 | 10 | 5 | 14 | 6 | 10 | 12 | 12 | 12 | 12 |  | 50 Ohms | TOP=L2:L3=L2/L4:L6=L5/L7:BOTTOM=L7 |
| CLK_50M_BMC0 | OTHERS | BUS | 6 | 5 | 5 | 10 | 5 | 14 | 6 | 10 | 12 | 12 | 12 | 12 |  | 50 Ohms | TOP=L2:L3=L2/L4:L6=L5/L7:BOTTOM=L7 |
| CLK_50M_BMC0 | OTHERS | BUS | 7 | 5 | 5 | 10 | 5 | 14 | 6 | 10 | 12 | 12 | 12 | 12 |  | 50 Ohms | TOP=L2:L3=L2/L4:L6=L5/L7:BOTTOM=L7 |
| CLK_50M_BMC0 | OTHERS | BUS | 8 | 4.75 | 5 | 10 | 5 | 14 | 6 | 9.5 | 12 | 12 | 12 | 12 |  | 50 Ohms | TOP=L2:L3=L2/L4:L6=L5/L7:BOTTOM=L7 |
| CLK_50M_RMII_PHY | OTHERS | BUS | 1 | 4.75 | 5 | 10 | 5 | 14 | 6 | 9.5 | 12 | 12 | 12 | 12 |  | 50 Ohms | TOP=L2:L3=L2/L4:L6=L5/L7:BOTTOM=L7 |
| CLK_50M_RMII_PHY | OTHERS | BUS | 2 | 5 | 5 | 10 | 5 | 14 | 6 | 10 | 12 | 12 | 12 | 12 |  | 50 Ohms | TOP=L2:L3=L2/L4:L6=L5/L7:BOTTOM=L7 |
| CLK_50M_RMII_PHY | OTHERS | BUS | 3 | 5 | 5 | 10 | 5 | 14 | 6 | 10 | 12 | 12 | 12 | 12 |  | 50 Ohms | TOP=L2:L3=L2/L4:L6=L5/L7:BOTTOM=L7 |
| CLK_50M_RMII_PHY | OTHERS | BUS | 4 | 5 | 5 | 10 | 5 | 14 | 6 | 10 | 12 | 12 | 12 | 12 |  | 50 Ohms | TOP=L2:L3=L2/L4:L6=L5/L7:BOTTOM=L7 |
| CLK_50M_RMII_PHY | OTHERS | BUS | 5 | 5 | 5 | 10 | 5 | 14 | 6 | 10 | 12 | 12 | 12 | 12 |  | 50 Ohms | TOP=L2:L3=L2/L4:L6=L5/L7:BOTTOM=L7 |
| CLK_50M_RMII_PHY | OTHERS | BUS | 6 | 5 | 5 | 10 | 5 | 14 | 6 | 10 | 12 | 12 | 12 | 12 |  | 50 Ohms | TOP=L2:L3=L2/L4:L6=L5/L7:BOTTOM=L7 |
| CLK_50M_RMII_PHY | OTHERS | BUS | 7 | 5 | 5 | 10 | 5 | 14 | 6 | 10 | 12 | 12 | 12 | 12 |  | 50 Ohms | TOP=L2:L3=L2/L4:L6=L5/L7:BOTTOM=L7 |
| CLK_50M_RMII_PHY | OTHERS | BUS | 8 | 4.75 | 5 | 10 | 5 | 14 | 6 | 9.5 | 12 | 12 | 12 | 12 |  | 50 Ohms | TOP=L2:L3=L2/L4:L6=L5/L7:BOTTOM=L7 |
| CLK_50M_RMII_PHY_IN | OTHERS | BUS | 1 | 4.75 | 5 | 10 | 5 | 14 | 6 | 9.5 | 12 | 12 | 12 | 12 |  | 50 Ohms | TOP=L2:L3=L2/L4:L6=L5/L7:BOTTOM=L7 |
| CLK_50M_RMII_PHY_IN | OTHERS | BUS | 2 | 5 | 5 | 10 | 5 | 14 | 6 | 10 | 12 | 12 | 12 | 12 |  | 50 Ohms | TOP=L2:L3=L2/L4:L6=L5/L7:BOTTOM=L7 |
| CLK_50M_RMII_PHY_IN | OTHERS | BUS | 3 | 5 | 5 | 10 | 5 | 14 | 6 | 10 | 12 | 12 | 12 | 12 |  | 50 Ohms | TOP=L2:L3=L2/L4:L6=L5/L7:BOTTOM=L7 |
| CLK_50M_RMII_PHY_IN | OTHERS | BUS | 4 | 5 | 5 | 10 | 5 | 14 | 6 | 10 | 12 | 12 | 12 | 12 |  | 50 Ohms | TOP=L2:L3=L2/L4:L6=L5/L7:BOTTOM=L7 |
| CLK_50M_RMII_PHY_IN | OTHERS | BUS | 5 | 5 | 5 | 10 | 5 | 14 | 6 | 10 | 12 | 12 | 12 | 12 |  | 50 Ohms | TOP=L2:L3=L2/L4:L6=L5/L7:BOTTOM=L7 |
| CLK_50M_RMII_PHY_IN | OTHERS | BUS | 6 | 5 | 5 | 10 | 5 | 14 | 6 | 10 | 12 | 12 | 12 | 12 |  | 50 Ohms | TOP=L2:L3=L2/L4:L6=L5/L7:BOTTOM=L7 |
| CLK_50M_RMII_PHY_IN | OTHERS | BUS | 7 | 5 | 5 | 10 | 5 | 14 | 6 | 10 | 12 | 12 | 12 | 12 |  | 50 Ohms | TOP=L2:L3=L2/L4:L6=L5/L7:BOTTOM=L7 |
| CLK_50M_RMII_PHY_IN | OTHERS | BUS | 8 | 4.75 | 5 | 10 | 5 | 14 | 6 | 9.5 | 12 | 12 | 12 | 12 |  | 50 Ohms | TOP=L2:L3=L2/L4:L6=L5/L7:BOTTOM=L7 |
| CLK_P_1_R | OTHERS | BUS | 1 | 4.75 | 5 | 10 | 5 | 14 | 6 | 9.5 | 12 | 12 | 12 | 12 |  | 50 Ohms | TOP=L2:L3=L2/L4:L6=L5/L7:BOTTOM=L7 |
| CLK_P_1_R | OTHERS | BUS | 2 | 5 | 5 | 10 | 5 | 14 | 6 | 10 | 12 | 12 | 12 | 12 |  | 50 Ohms | TOP=L2:L3=L2/L4:L6=L5/L7:BOTTOM=L7 |
| CLK_P_1_R | OTHERS | BUS | 3 | 5 | 5 | 10 | 5 | 14 | 6 | 10 | 12 | 12 | 12 | 12 |  | 50 Ohms | TOP=L2:L3=L2/L4:L6=L5/L7:BOTTOM=L7 |
| CLK_P_1_R | OTHERS | BUS | 4 | 5 | 5 | 10 | 5 | 14 | 6 | 10 | 12 | 12 | 12 | 12 |  | 50 Ohms | TOP=L2:L3=L2/L4:L6=L5/L7:BOTTOM=L7 |
| CLK_P_1_R | OTHERS | BUS | 5 | 5 | 5 | 10 | 5 | 14 | 6 | 10 | 12 | 12 | 12 | 12 |  | 50 Ohms | TOP=L2:L3=L2/L4:L6=L5/L7:BOTTOM=L7 |
| CLK_P_1_R | OTHERS | BUS | 6 | 5 | 5 | 10 | 5 | 14 | 6 | 10 | 12 | 12 | 12 | 12 |  | 50 Ohms | TOP=L2:L3=L2/L4:L6=L5/L7:BOTTOM=L7 |
| CLK_P_1_R | OTHERS | BUS | 7 | 5 | 5 | 10 | 5 | 14 | 6 | 10 | 12 | 12 | 12 | 12 |  | 50 Ohms | TOP=L2:L3=L2/L4:L6=L5/L7:BOTTOM=L7 |
| CLK_P_1_R | OTHERS | BUS | 8 | 4.75 | 5 | 10 | 5 | 14 | 6 | 9.5 | 12 | 12 | 12 | 12 |  | 50 Ohms | TOP=L2:L3=L2/L4:L6=L5/L7:BOTTOM=L7 |
| CLK_P_2_R | OTHERS | BUS | 1 | 4.75 | 5 | 10 | 5 | 14 | 6 | 9.5 | 12 | 12 | 12 | 12 |  | 50 Ohms | TOP=L2:L3=L2/L4:L6=L5/L7:BOTTOM=L7 |
| CLK_P_2_R | OTHERS | BUS | 2 | 5 | 5 | 10 | 5 | 14 | 6 | 10 | 12 | 12 | 12 | 12 |  | 50 Ohms | TOP=L2:L3=L2/L4:L6=L5/L7:BOTTOM=L7 |
| CLK_P_2_R | OTHERS | BUS | 3 | 5 | 5 | 10 | 5 | 14 | 6 | 10 | 12 | 12 | 12 | 12 |  | 50 Ohms | TOP=L2:L3=L2/L4:L6=L5/L7:BOTTOM=L7 |
| CLK_P_2_R | OTHERS | BUS | 4 | 5 | 5 | 10 | 5 | 14 | 6 | 10 | 12 | 12 | 12 | 12 |  | 50 Ohms | TOP=L2:L3=L2/L4:L6=L5/L7:BOTTOM=L7 |
| CLK_P_2_R | OTHERS | BUS | 5 | 5 | 5 | 10 | 5 | 14 | 6 | 10 | 12 | 12 | 12 | 12 |  | 50 Ohms | TOP=L2:L3=L2/L4:L6=L5/L7:BOTTOM=L7 |
| CLK_P_2_R | OTHERS | BUS | 6 | 5 | 5 | 10 | 5 | 14 | 6 | 10 | 12 | 12 | 12 | 12 |  | 50 Ohms | TOP=L2:L3=L2/L4:L6=L5/L7:BOTTOM=L7 |
| CLK_P_2_R | OTHERS | BUS | 7 | 5 | 5 | 10 | 5 | 14 | 6 | 10 | 12 | 12 | 12 | 12 |  | 50 Ohms | TOP=L2:L3=L2/L4:L6=L5/L7:BOTTOM=L7 |
| CLK_P_2_R | OTHERS | BUS | 8 | 4.75 | 5 | 10 | 5 | 14 | 6 | 9.5 | 12 | 12 | 12 | 12 |  | 50 Ohms | TOP=L2:L3=L2/L4:L6=L5/L7:BOTTOM=L7 |
| CLK_P_3_R | OTHERS | BUS | 1 | 4.75 | 5 | 10 | 5 | 14 | 6 | 9.5 | 12 | 12 | 12 | 12 |  | 50 Ohms | TOP=L2:L3=L2/L4:L6=L5/L7:BOTTOM=L7 |
| CLK_P_3_R | OTHERS | BUS | 2 | 5 | 5 | 10 | 5 | 14 | 6 | 10 | 12 | 12 | 12 | 12 |  | 50 Ohms | TOP=L2:L3=L2/L4:L6=L5/L7:BOTTOM=L7 |
| CLK_P_3_R | OTHERS | BUS | 3 | 5 | 5 | 10 | 5 | 14 | 6 | 10 | 12 | 12 | 12 | 12 |  | 50 Ohms | TOP=L2:L3=L2/L4:L6=L5/L7:BOTTOM=L7 |
| CLK_P_3_R | OTHERS | BUS | 4 | 5 | 5 | 10 | 5 | 14 | 6 | 10 | 12 | 12 | 12 | 12 |  | 50 Ohms | TOP=L2:L3=L2/L4:L6=L5/L7:BOTTOM=L7 |
| CLK_P_3_R | OTHERS | BUS | 5 | 5 | 5 | 10 | 5 | 14 | 6 | 10 | 12 | 12 | 12 | 12 |  | 50 Ohms | TOP=L2:L3=L2/L4:L6=L5/L7:BOTTOM=L7 |
| CLK_P_3_R | OTHERS | BUS | 6 | 5 | 5 | 10 | 5 | 14 | 6 | 10 | 12 | 12 | 12 | 12 |  | 50 Ohms | TOP=L2:L3=L2/L4:L6=L5/L7:BOTTOM=L7 |
| CLK_P_3_R | OTHERS | BUS | 7 | 5 | 5 | 10 | 5 | 14 | 6 | 10 | 12 | 12 | 12 | 12 |  | 50 Ohms | TOP=L2:L3=L2/L4:L6=L5/L7:BOTTOM=L7 |
| CLK_P_3_R | OTHERS | BUS | 8 | 4.75 | 5 | 10 | 5 | 14 | 6 | 9.5 | 12 | 12 | 12 | 12 |  | 50 Ohms | TOP=L2:L3=L2/L4:L6=L5/L7:BOTTOM=L7 |
| CLK_P_4_R | OTHERS | BUS | 1 | 4.75 | 5 | 10 | 5 | 14 | 6 | 9.5 | 12 | 12 | 12 | 12 |  | 50 Ohms | TOP=L2:L3=L2/L4:L6=L5/L7:BOTTOM=L7 |
| CLK_P_4_R | OTHERS | BUS | 2 | 5 | 5 | 10 | 5 | 14 | 6 | 10 | 12 | 12 | 12 | 12 |  | 50 Ohms | TOP=L2:L3=L2/L4:L6=L5/L7:BOTTOM=L7 |
| CLK_P_4_R | OTHERS | BUS | 3 | 5 | 5 | 10 | 5 | 14 | 6 | 10 | 12 | 12 | 12 | 12 |  | 50 Ohms | TOP=L2:L3=L2/L4:L6=L5/L7:BOTTOM=L7 |
| CLK_P_4_R | OTHERS | BUS | 4 | 5 | 5 | 10 | 5 | 14 | 6 | 10 | 12 | 12 | 12 | 12 |  | 50 Ohms | TOP=L2:L3=L2/L4:L6=L5/L7:BOTTOM=L7 |
| CLK_P_4_R | OTHERS | BUS | 5 | 5 | 5 | 10 | 5 | 14 | 6 | 10 | 12 | 12 | 12 | 12 |  | 50 Ohms | TOP=L2:L3=L2/L4:L6=L5/L7:BOTTOM=L7 |
| CLK_P_4_R | OTHERS | BUS | 6 | 5 | 5 | 10 | 5 | 14 | 6 | 10 | 12 | 12 | 12 | 12 |  | 50 Ohms | TOP=L2:L3=L2/L4:L6=L5/L7:BOTTOM=L7 |
| CLK_P_4_R | OTHERS | BUS | 7 | 5 | 5 | 10 | 5 | 14 | 6 | 10 | 12 | 12 | 12 | 12 |  | 50 Ohms | TOP=L2:L3=L2/L4:L6=L5/L7:BOTTOM=L7 |
| CLK_P_4_R | OTHERS | BUS | 8 | 4.75 | 5 | 10 | 5 | 14 | 6 | 9.5 | 12 | 12 | 12 | 12 |  | 50 Ohms | TOP=L2:L3=L2/L4:L6=L5/L7:BOTTOM=L7 |
| CLK_P_5_R | OTHERS | BUS | 1 | 4.75 | 5 | 10 | 5 | 14 | 6 | 9.5 | 12 | 12 | 12 | 12 |  | 50 Ohms | TOP=L2:L3=L2/L4:L6=L5/L7:BOTTOM=L7 |
| CLK_P_5_R | OTHERS | BUS | 2 | 5 | 5 | 10 | 5 | 14 | 6 | 10 | 12 | 12 | 12 | 12 |  | 50 Ohms | TOP=L2:L3=L2/L4:L6=L5/L7:BOTTOM=L7 |
| CLK_P_5_R | OTHERS | BUS | 3 | 5 | 5 | 10 | 5 | 14 | 6 | 10 | 12 | 12 | 12 | 12 |  | 50 Ohms | TOP=L2:L3=L2/L4:L6=L5/L7:BOTTOM=L7 |
| CLK_P_5_R | OTHERS | BUS | 4 | 5 | 5 | 10 | 5 | 14 | 6 | 10 | 12 | 12 | 12 | 12 |  | 50 Ohms | TOP=L2:L3=L2/L4:L6=L5/L7:BOTTOM=L7 |
| CLK_P_5_R | OTHERS | BUS | 5 | 5 | 5 | 10 | 5 | 14 | 6 | 10 | 12 | 12 | 12 | 12 |  | 50 Ohms | TOP=L2:L3=L2/L4:L6=L5/L7:BOTTOM=L7 |
| CLK_P_5_R | OTHERS | BUS | 6 | 5 | 5 | 10 | 5 | 14 | 6 | 10 | 12 | 12 | 12 | 12 |  | 50 Ohms | TOP=L2:L3=L2/L4:L6=L5/L7:BOTTOM=L7 |
| CLK_P_5_R | OTHERS | BUS | 7 | 5 | 5 | 10 | 5 | 14 | 6 | 10 | 12 | 12 | 12 | 12 |  | 50 Ohms | TOP=L2:L3=L2/L4:L6=L5/L7:BOTTOM=L7 |
| CLK_P_5_R | OTHERS | BUS | 8 | 4.75 | 5 | 10 | 5 | 14 | 6 | 9.5 | 12 | 12 | 12 | 12 |  | 50 Ohms | TOP=L2:L3=L2/L4:L6=L5/L7:BOTTOM=L7 |
| CLK_P_6_R | OTHERS | BUS | 1 | 4.75 | 5 | 10 | 5 | 14 | 6 | 9.5 | 12 | 12 | 12 | 12 |  | 50 Ohms | TOP=L2:L3=L2/L4:L6=L5/L7:BOTTOM=L7 |
| CLK_P_6_R | OTHERS | BUS | 2 | 5 | 5 | 10 | 5 | 14 | 6 | 10 | 12 | 12 | 12 | 12 |  | 50 Ohms | TOP=L2:L3=L2/L4:L6=L5/L7:BOTTOM=L7 |
| CLK_P_6_R | OTHERS | BUS | 3 | 5 | 5 | 10 | 5 | 14 | 6 | 10 | 12 | 12 | 12 | 12 |  | 50 Ohms | TOP=L2:L3=L2/L4:L6=L5/L7:BOTTOM=L7 |
| CLK_P_6_R | OTHERS | BUS | 4 | 5 | 5 | 10 | 5 | 14 | 6 | 10 | 12 | 12 | 12 | 12 |  | 50 Ohms | TOP=L2:L3=L2/L4:L6=L5/L7:BOTTOM=L7 |
| CLK_P_6_R | OTHERS | BUS | 5 | 5 | 5 | 10 | 5 | 14 | 6 | 10 | 12 | 12 | 12 | 12 |  | 50 Ohms | TOP=L2:L3=L2/L4:L6=L5/L7:BOTTOM=L7 |
| CLK_P_6_R | OTHERS | BUS | 6 | 5 | 5 | 10 | 5 | 14 | 6 | 10 | 12 | 12 | 12 | 12 |  | 50 Ohms | TOP=L2:L3=L2/L4:L6=L5/L7:BOTTOM=L7 |
| CLK_P_6_R | OTHERS | BUS | 7 | 5 | 5 | 10 | 5 | 14 | 6 | 10 | 12 | 12 | 12 | 12 |  | 50 Ohms | TOP=L2:L3=L2/L4:L6=L5/L7:BOTTOM=L7 |
| CLK_P_6_R | OTHERS | BUS | 8 | 4.75 | 5 | 10 | 5 | 14 | 6 | 9.5 | 12 | 12 | 12 | 12 |  | 50 Ohms | TOP=L2:L3=L2/L4:L6=L5/L7:BOTTOM=L7 |
| CLK_P_7_R | OTHERS | BUS | 1 | 4.75 | 5 | 10 | 5 | 14 | 6 | 9.5 | 12 | 12 | 12 | 12 |  | 50 Ohms | TOP=L2:L3=L2/L4:L6=L5/L7:BOTTOM=L7 |
| CLK_P_7_R | OTHERS | BUS | 2 | 5 | 5 | 10 | 5 | 14 | 6 | 10 | 12 | 12 | 12 | 12 |  | 50 Ohms | TOP=L2:L3=L2/L4:L6=L5/L7:BOTTOM=L7 |
| CLK_P_7_R | OTHERS | BUS | 3 | 5 | 5 | 10 | 5 | 14 | 6 | 10 | 12 | 12 | 12 | 12 |  | 50 Ohms | TOP=L2:L3=L2/L4:L6=L5/L7:BOTTOM=L7 |
| CLK_P_7_R | OTHERS | BUS | 4 | 5 | 5 | 10 | 5 | 14 | 6 | 10 | 12 | 12 | 12 | 12 |  | 50 Ohms | TOP=L2:L3=L2/L4:L6=L5/L7:BOTTOM=L7 |
| CLK_P_7_R | OTHERS | BUS | 5 | 5 | 5 | 10 | 5 | 14 | 6 | 10 | 12 | 12 | 12 | 12 |  | 50 Ohms | TOP=L2:L3=L2/L4:L6=L5/L7:BOTTOM=L7 |
| CLK_P_7_R | OTHERS | BUS | 6 | 5 | 5 | 10 | 5 | 14 | 6 | 10 | 12 | 12 | 12 | 12 |  | 50 Ohms | TOP=L2:L3=L2/L4:L6=L5/L7:BOTTOM=L7 |
| CLK_P_7_R | OTHERS | BUS | 7 | 5 | 5 | 10 | 5 | 14 | 6 | 10 | 12 | 12 | 12 | 12 |  | 50 Ohms | TOP=L2:L3=L2/L4:L6=L5/L7:BOTTOM=L7 |
| CLK_P_7_R | OTHERS | BUS | 8 | 4.75 | 5 | 10 | 5 | 14 | 6 | 9.5 | 12 | 12 | 12 | 12 |  | 50 Ohms | TOP=L2:L3=L2/L4:L6=L5/L7:BOTTOM=L7 |
| CLK_P_8_R | OTHERS | BUS | 1 | 4.75 | 5 | 10 | 5 | 14 | 6 | 9.5 | 12 | 12 | 12 | 12 |  | 50 Ohms | TOP=L2:L3=L2/L4:L6=L5/L7:BOTTOM=L7 |
| CLK_P_8_R | OTHERS | BUS | 2 | 5 | 5 | 10 | 5 | 14 | 6 | 10 | 12 | 12 | 12 | 12 |  | 50 Ohms | TOP=L2:L3=L2/L4:L6=L5/L7:BOTTOM=L7 |
| CLK_P_8_R | OTHERS | BUS | 3 | 5 | 5 | 10 | 5 | 14 | 6 | 10 | 12 | 12 | 12 | 12 |  | 50 Ohms | TOP=L2:L3=L2/L4:L6=L5/L7:BOTTOM=L7 |
| CLK_P_8_R | OTHERS | BUS | 4 | 5 | 5 | 10 | 5 | 14 | 6 | 10 | 12 | 12 | 12 | 12 |  | 50 Ohms | TOP=L2:L3=L2/L4:L6=L5/L7:BOTTOM=L7 |
| CLK_P_8_R | OTHERS | BUS | 5 | 5 | 5 | 10 | 5 | 14 | 6 | 10 | 12 | 12 | 12 | 12 |  | 50 Ohms | TOP=L2:L3=L2/L4:L6=L5/L7:BOTTOM=L7 |
| CLK_P_8_R | OTHERS | BUS | 6 | 5 | 5 | 10 | 5 | 14 | 6 | 10 | 12 | 12 | 12 | 12 |  | 50 Ohms | TOP=L2:L3=L2/L4:L6=L5/L7:BOTTOM=L7 |
| CLK_P_8_R | OTHERS | BUS | 7 | 5 | 5 | 10 | 5 | 14 | 6 | 10 | 12 | 12 | 12 | 12 |  | 50 Ohms | TOP=L2:L3=L2/L4:L6=L5/L7:BOTTOM=L7 |
| CLK_P_8_R | OTHERS | BUS | 8 | 4.75 | 5 | 10 | 5 | 14 | 6 | 9.5 | 12 | 12 | 12 | 12 |  | 50 Ohms | TOP=L2:L3=L2/L4:L6=L5/L7:BOTTOM=L7 |
| CLKGEN_OE1 | OTHERS | BUS | 1 | 4.75 | 5 | 10 | 5 | 14 | 6 | 9.5 | 12 | 12 | 12 | 12 |  | 50 Ohms | TOP=L2:L3=L2/L4:L6=L5/L7:BOTTOM=L7 |
| CLKGEN_OE1 | OTHERS | BUS | 2 | 5 | 5 | 10 | 5 | 14 | 6 | 10 | 12 | 12 | 12 | 12 |  | 50 Ohms | TOP=L2:L3=L2/L4:L6=L5/L7:BOTTOM=L7 |
| CLKGEN_OE1 | OTHERS | BUS | 3 | 5 | 5 | 10 | 5 | 14 | 6 | 10 | 12 | 12 | 12 | 12 |  | 50 Ohms | TOP=L2:L3=L2/L4:L6=L5/L7:BOTTOM=L7 |
| CLKGEN_OE1 | OTHERS | BUS | 4 | 5 | 5 | 10 | 5 | 14 | 6 | 10 | 12 | 12 | 12 | 12 |  | 50 Ohms | TOP=L2:L3=L2/L4:L6=L5/L7:BOTTOM=L7 |
| CLKGEN_OE1 | OTHERS | BUS | 5 | 5 | 5 | 10 | 5 | 14 | 6 | 10 | 12 | 12 | 12 | 12 |  | 50 Ohms | TOP=L2:L3=L2/L4:L6=L5/L7:BOTTOM=L7 |
| CLKGEN_OE1 | OTHERS | BUS | 6 | 5 | 5 | 10 | 5 | 14 | 6 | 10 | 12 | 12 | 12 | 12 |  | 50 Ohms | TOP=L2:L3=L2/L4:L6=L5/L7:BOTTOM=L7 |
| CLKGEN_OE1 | OTHERS | BUS | 7 | 5 | 5 | 10 | 5 | 14 | 6 | 10 | 12 | 12 | 12 | 12 |  | 50 Ohms | TOP=L2:L3=L2/L4:L6=L5/L7:BOTTOM=L7 |
| CLKGEN_OE1 | OTHERS | BUS | 8 | 4.75 | 5 | 10 | 5 | 14 | 6 | 9.5 | 12 | 12 | 12 | 12 |  | 50 Ohms | TOP=L2:L3=L2/L4:L6=L5/L7:BOTTOM=L7 |
| CLKGEN_OE1_R | OTHERS | BUS | 1 | 4.75 | 5 | 10 | 5 | 14 | 6 | 9.5 | 12 | 12 | 12 | 12 |  | 50 Ohms | TOP=L2:L3=L2/L4:L6=L5/L7:BOTTOM=L7 |
| CLKGEN_OE1_R | OTHERS | BUS | 2 | 5 | 5 | 10 | 5 | 14 | 6 | 10 | 12 | 12 | 12 | 12 |  | 50 Ohms | TOP=L2:L3=L2/L4:L6=L5/L7:BOTTOM=L7 |
| CLKGEN_OE1_R | OTHERS | BUS | 3 | 5 | 5 | 10 | 5 | 14 | 6 | 10 | 12 | 12 | 12 | 12 |  | 50 Ohms | TOP=L2:L3=L2/L4:L6=L5/L7:BOTTOM=L7 |
| CLKGEN_OE1_R | OTHERS | BUS | 4 | 5 | 5 | 10 | 5 | 14 | 6 | 10 | 12 | 12 | 12 | 12 |  | 50 Ohms | TOP=L2:L3=L2/L4:L6=L5/L7:BOTTOM=L7 |
| CLKGEN_OE1_R | OTHERS | BUS | 5 | 5 | 5 | 10 | 5 | 14 | 6 | 10 | 12 | 12 | 12 | 12 |  | 50 Ohms | TOP=L2:L3=L2/L4:L6=L5/L7:BOTTOM=L7 |
| CLKGEN_OE1_R | OTHERS | BUS | 6 | 5 | 5 | 10 | 5 | 14 | 6 | 10 | 12 | 12 | 12 | 12 |  | 50 Ohms | TOP=L2:L3=L2/L4:L6=L5/L7:BOTTOM=L7 |
| CLKGEN_OE1_R | OTHERS | BUS | 7 | 5 | 5 | 10 | 5 | 14 | 6 | 10 | 12 | 12 | 12 | 12 |  | 50 Ohms | TOP=L2:L3=L2/L4:L6=L5/L7:BOTTOM=L7 |
| CLKGEN_OE1_R | OTHERS | BUS | 8 | 4.75 | 5 | 10 | 5 | 14 | 6 | 9.5 | 12 | 12 | 12 | 12 |  | 50 Ohms | TOP=L2:L3=L2/L4:L6=L5/L7:BOTTOM=L7 |
| CLKGEN_OE2 | OTHERS | BUS | 1 | 4.75 | 5 | 10 | 5 | 14 | 6 | 9.5 | 12 | 12 | 12 | 12 |  | 50 Ohms | TOP=L2:L3=L2/L4:L6=L5/L7:BOTTOM=L7 |
| CLKGEN_OE2 | OTHERS | BUS | 2 | 5 | 5 | 10 | 5 | 14 | 6 | 10 | 12 | 12 | 12 | 12 |  | 50 Ohms | TOP=L2:L3=L2/L4:L6=L5/L7:BOTTOM=L7 |
| CLKGEN_OE2 | OTHERS | BUS | 3 | 5 | 5 | 10 | 5 | 14 | 6 | 10 | 12 | 12 | 12 | 12 |  | 50 Ohms | TOP=L2:L3=L2/L4:L6=L5/L7:BOTTOM=L7 |
| CLKGEN_OE2 | OTHERS | BUS | 4 | 5 | 5 | 10 | 5 | 14 | 6 | 10 | 12 | 12 | 12 | 12 |  | 50 Ohms | TOP=L2:L3=L2/L4:L6=L5/L7:BOTTOM=L7 |
| CLKGEN_OE2 | OTHERS | BUS | 5 | 5 | 5 | 10 | 5 | 14 | 6 | 10 | 12 | 12 | 12 | 12 |  | 50 Ohms | TOP=L2:L3=L2/L4:L6=L5/L7:BOTTOM=L7 |
| CLKGEN_OE2 | OTHERS | BUS | 6 | 5 | 5 | 10 | 5 | 14 | 6 | 10 | 12 | 12 | 12 | 12 |  | 50 Ohms | TOP=L2:L3=L2/L4:L6=L5/L7:BOTTOM=L7 |
| CLKGEN_OE2 | OTHERS | BUS | 7 | 5 | 5 | 10 | 5 | 14 | 6 | 10 | 12 | 12 | 12 | 12 |  | 50 Ohms | TOP=L2:L3=L2/L4:L6=L5/L7:BOTTOM=L7 |
| CLKGEN_OE2 | OTHERS | BUS | 8 | 4.75 | 5 | 10 | 5 | 14 | 6 | 9.5 | 12 | 12 | 12 | 12 |  | 50 Ohms | TOP=L2:L3=L2/L4:L6=L5/L7:BOTTOM=L7 |
| CLKGEN_OE2_R | OTHERS | BUS | 1 | 4.75 | 5 | 10 | 5 | 14 | 6 | 9.5 | 12 | 12 | 12 | 12 |  | 50 Ohms | TOP=L2:L3=L2/L4:L6=L5/L7:BOTTOM=L7 |
| CLKGEN_OE2_R | OTHERS | BUS | 2 | 5 | 5 | 10 | 5 | 14 | 6 | 10 | 12 | 12 | 12 | 12 |  | 50 Ohms | TOP=L2:L3=L2/L4:L6=L5/L7:BOTTOM=L7 |
| CLKGEN_OE2_R | OTHERS | BUS | 3 | 5 | 5 | 10 | 5 | 14 | 6 | 10 | 12 | 12 | 12 | 12 |  | 50 Ohms | TOP=L2:L3=L2/L4:L6=L5/L7:BOTTOM=L7 |
| CLKGEN_OE2_R | OTHERS | BUS | 4 | 5 | 5 | 10 | 5 | 14 | 6 | 10 | 12 | 12 | 12 | 12 |  | 50 Ohms | TOP=L2:L3=L2/L4:L6=L5/L7:BOTTOM=L7 |
| CLKGEN_OE2_R | OTHERS | BUS | 5 | 5 | 5 | 10 | 5 | 14 | 6 | 10 | 12 | 12 | 12 | 12 |  | 50 Ohms | TOP=L2:L3=L2/L4:L6=L5/L7:BOTTOM=L7 |
| CLKGEN_OE2_R | OTHERS | BUS | 6 | 5 | 5 | 10 | 5 | 14 | 6 | 10 | 12 | 12 | 12 | 12 |  | 50 Ohms | TOP=L2:L3=L2/L4:L6=L5/L7:BOTTOM=L7 |
| CLKGEN_OE2_R | OTHERS | BUS | 7 | 5 | 5 | 10 | 5 | 14 | 6 | 10 | 12 | 12 | 12 | 12 |  | 50 Ohms | TOP=L2:L3=L2/L4:L6=L5/L7:BOTTOM=L7 |
| CLKGEN_OE2_R | OTHERS | BUS | 8 | 4.75 | 5 | 10 | 5 | 14 | 6 | 9.5 | 12 | 12 | 12 | 12 |  | 50 Ohms | TOP=L2:L3=L2/L4:L6=L5/L7:BOTTOM=L7 |
| CLKGEN_OE3 | OTHERS | BUS | 1 | 4.75 | 5 | 10 | 5 | 14 | 6 | 9.5 | 12 | 12 | 12 | 12 |  | 50 Ohms | TOP=L2:L3=L2/L4:L6=L5/L7:BOTTOM=L7 |
| CLKGEN_OE3 | OTHERS | BUS | 2 | 5 | 5 | 10 | 5 | 14 | 6 | 10 | 12 | 12 | 12 | 12 |  | 50 Ohms | TOP=L2:L3=L2/L4:L6=L5/L7:BOTTOM=L7 |
| CLKGEN_OE3 | OTHERS | BUS | 3 | 5 | 5 | 10 | 5 | 14 | 6 | 10 | 12 | 12 | 12 | 12 |  | 50 Ohms | TOP=L2:L3=L2/L4:L6=L5/L7:BOTTOM=L7 |
| CLKGEN_OE3 | OTHERS | BUS | 4 | 5 | 5 | 10 | 5 | 14 | 6 | 10 | 12 | 12 | 12 | 12 |  | 50 Ohms | TOP=L2:L3=L2/L4:L6=L5/L7:BOTTOM=L7 |
| CLKGEN_OE3 | OTHERS | BUS | 5 | 5 | 5 | 10 | 5 | 14 | 6 | 10 | 12 | 12 | 12 | 12 |  | 50 Ohms | TOP=L2:L3=L2/L4:L6=L5/L7:BOTTOM=L7 |
| CLKGEN_OE3 | OTHERS | BUS | 6 | 5 | 5 | 10 | 5 | 14 | 6 | 10 | 12 | 12 | 12 | 12 |  | 50 Ohms | TOP=L2:L3=L2/L4:L6=L5/L7:BOTTOM=L7 |
| CLKGEN_OE3 | OTHERS | BUS | 7 | 5 | 5 | 10 | 5 | 14 | 6 | 10 | 12 | 12 | 12 | 12 |  | 50 Ohms | TOP=L2:L3=L2/L4:L6=L5/L7:BOTTOM=L7 |
| CLKGEN_OE3 | OTHERS | BUS | 8 | 4.75 | 5 | 10 | 5 | 14 | 6 | 9.5 | 12 | 12 | 12 | 12 |  | 50 Ohms | TOP=L2:L3=L2/L4:L6=L5/L7:BOTTOM=L7 |
| CLKGEN_OE3_R | OTHERS | BUS | 1 | 4.75 | 5 | 10 | 5 | 14 | 6 | 9.5 | 12 | 12 | 12 | 12 |  | 50 Ohms | TOP=L2:L3=L2/L4:L6=L5/L7:BOTTOM=L7 |
| CLKGEN_OE3_R | OTHERS | BUS | 2 | 5 | 5 | 10 | 5 | 14 | 6 | 10 | 12 | 12 | 12 | 12 |  | 50 Ohms | TOP=L2:L3=L2/L4:L6=L5/L7:BOTTOM=L7 |
| CLKGEN_OE3_R | OTHERS | BUS | 3 | 5 | 5 | 10 | 5 | 14 | 6 | 10 | 12 | 12 | 12 | 12 |  | 50 Ohms | TOP=L2:L3=L2/L4:L6=L5/L7:BOTTOM=L7 |
| CLKGEN_OE3_R | OTHERS | BUS | 4 | 5 | 5 | 10 | 5 | 14 | 6 | 10 | 12 | 12 | 12 | 12 |  | 50 Ohms | TOP=L2:L3=L2/L4:L6=L5/L7:BOTTOM=L7 |
| CLKGEN_OE3_R | OTHERS | BUS | 5 | 5 | 5 | 10 | 5 | 14 | 6 | 10 | 12 | 12 | 12 | 12 |  | 50 Ohms | TOP=L2:L3=L2/L4:L6=L5/L7:BOTTOM=L7 |
| CLKGEN_OE3_R | OTHERS | BUS | 6 | 5 | 5 | 10 | 5 | 14 | 6 | 10 | 12 | 12 | 12 | 12 |  | 50 Ohms | TOP=L2:L3=L2/L4:L6=L5/L7:BOTTOM=L7 |
| CLKGEN_OE3_R | OTHERS | BUS | 7 | 5 | 5 | 10 | 5 | 14 | 6 | 10 | 12 | 12 | 12 | 12 |  | 50 Ohms | TOP=L2:L3=L2/L4:L6=L5/L7:BOTTOM=L7 |
| CLKGEN_OE3_R | OTHERS | BUS | 8 | 4.75 | 5 | 10 | 5 | 14 | 6 | 9.5 | 12 | 12 | 12 | 12 |  | 50 Ohms | TOP=L2:L3=L2/L4:L6=L5/L7:BOTTOM=L7 |
| CLKGEN_PWGD | OTHERS | BUS | 1 | 4.75 | 5 | 10 | 5 | 14 | 6 | 9.5 | 12 | 12 | 12 | 12 |  | 50 Ohms | TOP=L2:L3=L2/L4:L6=L5/L7:BOTTOM=L7 |
| CLKGEN_PWGD | OTHERS | BUS | 2 | 5 | 5 | 10 | 5 | 14 | 6 | 10 | 12 | 12 | 12 | 12 |  | 50 Ohms | TOP=L2:L3=L2/L4:L6=L5/L7:BOTTOM=L7 |
| CLKGEN_PWGD | OTHERS | BUS | 3 | 5 | 5 | 10 | 5 | 14 | 6 | 10 | 12 | 12 | 12 | 12 |  | 50 Ohms | TOP=L2:L3=L2/L4:L6=L5/L7:BOTTOM=L7 |
| CLKGEN_PWGD | OTHERS | BUS | 4 | 5 | 5 | 10 | 5 | 14 | 6 | 10 | 12 | 12 | 12 | 12 |  | 50 Ohms | TOP=L2:L3=L2/L4:L6=L5/L7:BOTTOM=L7 |
| CLKGEN_PWGD | OTHERS | BUS | 5 | 5 | 5 | 10 | 5 | 14 | 6 | 10 | 12 | 12 | 12 | 12 |  | 50 Ohms | TOP=L2:L3=L2/L4:L6=L5/L7:BOTTOM=L7 |
| CLKGEN_PWGD | OTHERS | BUS | 6 | 5 | 5 | 10 | 5 | 14 | 6 | 10 | 12 | 12 | 12 | 12 |  | 50 Ohms | TOP=L2:L3=L2/L4:L6=L5/L7:BOTTOM=L7 |
| CLKGEN_PWGD | OTHERS | BUS | 7 | 5 | 5 | 10 | 5 | 14 | 6 | 10 | 12 | 12 | 12 | 12 |  | 50 Ohms | TOP=L2:L3=L2/L4:L6=L5/L7:BOTTOM=L7 |
| CLKGEN_PWGD | OTHERS | BUS | 8 | 4.75 | 5 | 10 | 5 | 14 | 6 | 9.5 | 12 | 12 | 12 | 12 |  | 50 Ohms | TOP=L2:L3=L2/L4:L6=L5/L7:BOTTOM=L7 |
| CLKGNE_SADR | OTHERS | BUS | 1 | 4.75 | 5 | 10 | 5 | 14 | 6 | 9.5 | 12 | 12 | 12 | 12 |  | 50 Ohms | TOP=L2:L3=L2/L4:L6=L5/L7:BOTTOM=L7 |
| CLKGNE_SADR | OTHERS | BUS | 2 | 5 | 5 | 10 | 5 | 14 | 6 | 10 | 12 | 12 | 12 | 12 |  | 50 Ohms | TOP=L2:L3=L2/L4:L6=L5/L7:BOTTOM=L7 |
| CLKGNE_SADR | OTHERS | BUS | 3 | 5 | 5 | 10 | 5 | 14 | 6 | 10 | 12 | 12 | 12 | 12 |  | 50 Ohms | TOP=L2:L3=L2/L4:L6=L5/L7:BOTTOM=L7 |
| CLKGNE_SADR | OTHERS | BUS | 4 | 5 | 5 | 10 | 5 | 14 | 6 | 10 | 12 | 12 | 12 | 12 |  | 50 Ohms | TOP=L2:L3=L2/L4:L6=L5/L7:BOTTOM=L7 |
| CLKGNE_SADR | OTHERS | BUS | 5 | 5 | 5 | 10 | 5 | 14 | 6 | 10 | 12 | 12 | 12 | 12 |  | 50 Ohms | TOP=L2:L3=L2/L4:L6=L5/L7:BOTTOM=L7 |
| CLKGNE_SADR | OTHERS | BUS | 6 | 5 | 5 | 10 | 5 | 14 | 6 | 10 | 12 | 12 | 12 | 12 |  | 50 Ohms | TOP=L2:L3=L2/L4:L6=L5/L7:BOTTOM=L7 |
| CLKGNE_SADR | OTHERS | BUS | 7 | 5 | 5 | 10 | 5 | 14 | 6 | 10 | 12 | 12 | 12 | 12 |  | 50 Ohms | TOP=L2:L3=L2/L4:L6=L5/L7:BOTTOM=L7 |
| CLKGNE_SADR | OTHERS | BUS | 8 | 4.75 | 5 | 10 | 5 | 14 | 6 | 9.5 | 12 | 12 | 12 | 12 |  | 50 Ohms | TOP=L2:L3=L2/L4:L6=L5/L7:BOTTOM=L7 |
| CLKGNE_SADR_R | OTHERS | BUS | 1 | 4.75 | 5 | 10 | 5 | 14 | 6 | 9.5 | 12 | 12 | 12 | 12 |  | 50 Ohms | TOP=L2:L3=L2/L4:L6=L5/L7:BOTTOM=L7 |
| CLKGNE_SADR_R | OTHERS | BUS | 2 | 5 | 5 | 10 | 5 | 14 | 6 | 10 | 12 | 12 | 12 | 12 |  | 50 Ohms | TOP=L2:L3=L2/L4:L6=L5/L7:BOTTOM=L7 |
| CLKGNE_SADR_R | OTHERS | BUS | 3 | 5 | 5 | 10 | 5 | 14 | 6 | 10 | 12 | 12 | 12 | 12 |  | 50 Ohms | TOP=L2:L3=L2/L4:L6=L5/L7:BOTTOM=L7 |
| CLKGNE_SADR_R | OTHERS | BUS | 4 | 5 | 5 | 10 | 5 | 14 | 6 | 10 | 12 | 12 | 12 | 12 |  | 50 Ohms | TOP=L2:L3=L2/L4:L6=L5/L7:BOTTOM=L7 |
| CLKGNE_SADR_R | OTHERS | BUS | 5 | 5 | 5 | 10 | 5 | 14 | 6 | 10 | 12 | 12 | 12 | 12 |  | 50 Ohms | TOP=L2:L3=L2/L4:L6=L5/L7:BOTTOM=L7 |
| CLKGNE_SADR_R | OTHERS | BUS | 6 | 5 | 5 | 10 | 5 | 14 | 6 | 10 | 12 | 12 | 12 | 12 |  | 50 Ohms | TOP=L2:L3=L2/L4:L6=L5/L7:BOTTOM=L7 |
| CLKGNE_SADR_R | OTHERS | BUS | 7 | 5 | 5 | 10 | 5 | 14 | 6 | 10 | 12 | 12 | 12 | 12 |  | 50 Ohms | TOP=L2:L3=L2/L4:L6=L5/L7:BOTTOM=L7 |
| CLKGNE_SADR_R | OTHERS | BUS | 8 | 4.75 | 5 | 10 | 5 | 14 | 6 | 9.5 | 12 | 12 | 12 | 12 |  | 50 Ohms | TOP=L2:L3=L2/L4:L6=L5/L7:BOTTOM=L7 |
| CLKGNE_SS_EN | OTHERS | BUS | 1 | 4.75 | 5 | 10 | 5 | 14 | 6 | 9.5 | 12 | 12 | 12 | 12 |  | 50 Ohms | TOP=L2:L3=L2/L4:L6=L5/L7:BOTTOM=L7 |
| CLKGNE_SS_EN | OTHERS | BUS | 2 | 5 | 5 | 10 | 5 | 14 | 6 | 10 | 12 | 12 | 12 | 12 |  | 50 Ohms | TOP=L2:L3=L2/L4:L6=L5/L7:BOTTOM=L7 |
| CLKGNE_SS_EN | OTHERS | BUS | 3 | 5 | 5 | 10 | 5 | 14 | 6 | 10 | 12 | 12 | 12 | 12 |  | 50 Ohms | TOP=L2:L3=L2/L4:L6=L5/L7:BOTTOM=L7 |
| CLKGNE_SS_EN | OTHERS | BUS | 4 | 5 | 5 | 10 | 5 | 14 | 6 | 10 | 12 | 12 | 12 | 12 |  | 50 Ohms | TOP=L2:L3=L2/L4:L6=L5/L7:BOTTOM=L7 |
| CLKGNE_SS_EN | OTHERS | BUS | 5 | 5 | 5 | 10 | 5 | 14 | 6 | 10 | 12 | 12 | 12 | 12 |  | 50 Ohms | TOP=L2:L3=L2/L4:L6=L5/L7:BOTTOM=L7 |
| CLKGNE_SS_EN | OTHERS | BUS | 6 | 5 | 5 | 10 | 5 | 14 | 6 | 10 | 12 | 12 | 12 | 12 |  | 50 Ohms | TOP=L2:L3=L2/L4:L6=L5/L7:BOTTOM=L7 |
| CLKGNE_SS_EN | OTHERS | BUS | 7 | 5 | 5 | 10 | 5 | 14 | 6 | 10 | 12 | 12 | 12 | 12 |  | 50 Ohms | TOP=L2:L3=L2/L4:L6=L5/L7:BOTTOM=L7 |
| CLKGNE_SS_EN | OTHERS | BUS | 8 | 4.75 | 5 | 10 | 5 | 14 | 6 | 9.5 | 12 | 12 | 12 | 12 |  | 50 Ohms | TOP=L2:L3=L2/L4:L6=L5/L7:BOTTOM=L7 |
| CN2_P23 | OTHERS | BUS | 1 | 4.75 | 5 | 10 | 5 | 14 | 6 | 9.5 | 12 | 12 | 12 | 12 |  | 50 Ohms | TOP=L2:L3=L2/L4:L6=L5/L7:BOTTOM=L7 |
| CN2_P23 | OTHERS | BUS | 2 | 5 | 5 | 10 | 5 | 14 | 6 | 10 | 12 | 12 | 12 | 12 |  | 50 Ohms | TOP=L2:L3=L2/L4:L6=L5/L7:BOTTOM=L7 |
| CN2_P23 | OTHERS | BUS | 3 | 5 | 5 | 10 | 5 | 14 | 6 | 10 | 12 | 12 | 12 | 12 |  | 50 Ohms | TOP=L2:L3=L2/L4:L6=L5/L7:BOTTOM=L7 |
| CN2_P23 | OTHERS | BUS | 4 | 5 | 5 | 10 | 5 | 14 | 6 | 10 | 12 | 12 | 12 | 12 |  | 50 Ohms | TOP=L2:L3=L2/L4:L6=L5/L7:BOTTOM=L7 |
| CN2_P23 | OTHERS | BUS | 5 | 5 | 5 | 10 | 5 | 14 | 6 | 10 | 12 | 12 | 12 | 12 |  | 50 Ohms | TOP=L2:L3=L2/L4:L6=L5/L7:BOTTOM=L7 |
| CN2_P23 | OTHERS | BUS | 6 | 5 | 5 | 10 | 5 | 14 | 6 | 10 | 12 | 12 | 12 | 12 |  | 50 Ohms | TOP=L2:L3=L2/L4:L6=L5/L7:BOTTOM=L7 |
| CN2_P23 | OTHERS | BUS | 7 | 5 | 5 | 10 | 5 | 14 | 6 | 10 | 12 | 12 | 12 | 12 |  | 50 Ohms | TOP=L2:L3=L2/L4:L6=L5/L7:BOTTOM=L7 |
| CN2_P23 | OTHERS | BUS | 8 | 4.75 | 5 | 10 | 5 | 14 | 6 | 9.5 | 12 | 12 | 12 | 12 |  | 50 Ohms | TOP=L2:L3=L2/L4:L6=L5/L7:BOTTOM=L7 |
| CONSOLE_LED_0 | OTHERS | BUS | 1 | 4.75 | 5 | 10 | 5 | 14 | 6 | 9.5 | 12 | 12 | 12 | 12 |  | 50 Ohms | TOP=L2:L3=L2/L4:L6=L5/L7:BOTTOM=L7 |
| CONSOLE_LED_0 | OTHERS | BUS | 2 | 5 | 5 | 10 | 5 | 14 | 6 | 10 | 12 | 12 | 12 | 12 |  | 50 Ohms | TOP=L2:L3=L2/L4:L6=L5/L7:BOTTOM=L7 |
| CONSOLE_LED_0 | OTHERS | BUS | 3 | 5 | 5 | 10 | 5 | 14 | 6 | 10 | 12 | 12 | 12 | 12 |  | 50 Ohms | TOP=L2:L3=L2/L4:L6=L5/L7:BOTTOM=L7 |
| CONSOLE_LED_0 | OTHERS | BUS | 4 | 5 | 5 | 10 | 5 | 14 | 6 | 10 | 12 | 12 | 12 | 12 |  | 50 Ohms | TOP=L2:L3=L2/L4:L6=L5/L7:BOTTOM=L7 |
| CONSOLE_LED_0 | OTHERS | BUS | 5 | 5 | 5 | 10 | 5 | 14 | 6 | 10 | 12 | 12 | 12 | 12 |  | 50 Ohms | TOP=L2:L3=L2/L4:L6=L5/L7:BOTTOM=L7 |
| CONSOLE_LED_0 | OTHERS | BUS | 6 | 5 | 5 | 10 | 5 | 14 | 6 | 10 | 12 | 12 | 12 | 12 |  | 50 Ohms | TOP=L2:L3=L2/L4:L6=L5/L7:BOTTOM=L7 |
| CONSOLE_LED_0 | OTHERS | BUS | 7 | 5 | 5 | 10 | 5 | 14 | 6 | 10 | 12 | 12 | 12 | 12 |  | 50 Ohms | TOP=L2:L3=L2/L4:L6=L5/L7:BOTTOM=L7 |
| CONSOLE_LED_0 | OTHERS | BUS | 8 | 4.75 | 5 | 10 | 5 | 14 | 6 | 9.5 | 12 | 12 | 12 | 12 |  | 50 Ohms | TOP=L2:L3=L2/L4:L6=L5/L7:BOTTOM=L7 |
| DACB | OTHERS | BUS | 1 | 4.75 | 5 | 10 | 5 | 14 | 6 | 9.5 | 12 | 12 | 12 | 12 |  | 50 Ohms | TOP=L2:L3=L2/L4:L6=L5/L7:BOTTOM=L7 |
| DACB | OTHERS | BUS | 2 | 5 | 5 | 10 | 5 | 14 | 6 | 10 | 12 | 12 | 12 | 12 |  | 50 Ohms | TOP=L2:L3=L2/L4:L6=L5/L7:BOTTOM=L7 |
| DACB | OTHERS | BUS | 3 | 5 | 5 | 10 | 5 | 14 | 6 | 10 | 12 | 12 | 12 | 12 |  | 50 Ohms | TOP=L2:L3=L2/L4:L6=L5/L7:BOTTOM=L7 |
| DACB | OTHERS | BUS | 4 | 5 | 5 | 10 | 5 | 14 | 6 | 10 | 12 | 12 | 12 | 12 |  | 50 Ohms | TOP=L2:L3=L2/L4:L6=L5/L7:BOTTOM=L7 |
| DACB | OTHERS | BUS | 5 | 5 | 5 | 10 | 5 | 14 | 6 | 10 | 12 | 12 | 12 | 12 |  | 50 Ohms | TOP=L2:L3=L2/L4:L6=L5/L7:BOTTOM=L7 |
| DACB | OTHERS | BUS | 6 | 5 | 5 | 10 | 5 | 14 | 6 | 10 | 12 | 12 | 12 | 12 |  | 50 Ohms | TOP=L2:L3=L2/L4:L6=L5/L7:BOTTOM=L7 |
| DACB | OTHERS | BUS | 7 | 5 | 5 | 10 | 5 | 14 | 6 | 10 | 12 | 12 | 12 | 12 |  | 50 Ohms | TOP=L2:L3=L2/L4:L6=L5/L7:BOTTOM=L7 |
| DACB | OTHERS | BUS | 8 | 4.75 | 5 | 10 | 5 | 14 | 6 | 9.5 | 12 | 12 | 12 | 12 |  | 50 Ohms | TOP=L2:L3=L2/L4:L6=L5/L7:BOTTOM=L7 |
| DACG | OTHERS | BUS | 1 | 4.75 | 5 | 10 | 5 | 14 | 6 | 9.5 | 12 | 12 | 12 | 12 |  | 50 Ohms | TOP=L2:L3=L2/L4:L6=L5/L7:BOTTOM=L7 |
| DACG | OTHERS | BUS | 2 | 5 | 5 | 10 | 5 | 14 | 6 | 10 | 12 | 12 | 12 | 12 |  | 50 Ohms | TOP=L2:L3=L2/L4:L6=L5/L7:BOTTOM=L7 |
| DACG | OTHERS | BUS | 3 | 5 | 5 | 10 | 5 | 14 | 6 | 10 | 12 | 12 | 12 | 12 |  | 50 Ohms | TOP=L2:L3=L2/L4:L6=L5/L7:BOTTOM=L7 |
| DACG | OTHERS | BUS | 4 | 5 | 5 | 10 | 5 | 14 | 6 | 10 | 12 | 12 | 12 | 12 |  | 50 Ohms | TOP=L2:L3=L2/L4:L6=L5/L7:BOTTOM=L7 |
| DACG | OTHERS | BUS | 5 | 5 | 5 | 10 | 5 | 14 | 6 | 10 | 12 | 12 | 12 | 12 |  | 50 Ohms | TOP=L2:L3=L2/L4:L6=L5/L7:BOTTOM=L7 |
| DACG | OTHERS | BUS | 6 | 5 | 5 | 10 | 5 | 14 | 6 | 10 | 12 | 12 | 12 | 12 |  | 50 Ohms | TOP=L2:L3=L2/L4:L6=L5/L7:BOTTOM=L7 |
| DACG | OTHERS | BUS | 7 | 5 | 5 | 10 | 5 | 14 | 6 | 10 | 12 | 12 | 12 | 12 |  | 50 Ohms | TOP=L2:L3=L2/L4:L6=L5/L7:BOTTOM=L7 |
| DACG | OTHERS | BUS | 8 | 4.75 | 5 | 10 | 5 | 14 | 6 | 9.5 | 12 | 12 | 12 | 12 |  | 50 Ohms | TOP=L2:L3=L2/L4:L6=L5/L7:BOTTOM=L7 |
| DACR | OTHERS | BUS | 1 | 4.75 | 5 | 10 | 5 | 14 | 6 | 9.5 | 12 | 12 | 12 | 12 |  | 50 Ohms | TOP=L2:L3=L2/L4:L6=L5/L7:BOTTOM=L7 |
| DACR | OTHERS | BUS | 2 | 5 | 5 | 10 | 5 | 14 | 6 | 10 | 12 | 12 | 12 | 12 |  | 50 Ohms | TOP=L2:L3=L2/L4:L6=L5/L7:BOTTOM=L7 |
| DACR | OTHERS | BUS | 3 | 5 | 5 | 10 | 5 | 14 | 6 | 10 | 12 | 12 | 12 | 12 |  | 50 Ohms | TOP=L2:L3=L2/L4:L6=L5/L7:BOTTOM=L7 |
| DACR | OTHERS | BUS | 4 | 5 | 5 | 10 | 5 | 14 | 6 | 10 | 12 | 12 | 12 | 12 |  | 50 Ohms | TOP=L2:L3=L2/L4:L6=L5/L7:BOTTOM=L7 |
| DACR | OTHERS | BUS | 5 | 5 | 5 | 10 | 5 | 14 | 6 | 10 | 12 | 12 | 12 | 12 |  | 50 Ohms | TOP=L2:L3=L2/L4:L6=L5/L7:BOTTOM=L7 |
| DACR | OTHERS | BUS | 6 | 5 | 5 | 10 | 5 | 14 | 6 | 10 | 12 | 12 | 12 | 12 |  | 50 Ohms | TOP=L2:L3=L2/L4:L6=L5/L7:BOTTOM=L7 |
| DACR | OTHERS | BUS | 7 | 5 | 5 | 10 | 5 | 14 | 6 | 10 | 12 | 12 | 12 | 12 |  | 50 Ohms | TOP=L2:L3=L2/L4:L6=L5/L7:BOTTOM=L7 |
| DACR | OTHERS | BUS | 8 | 4.75 | 5 | 10 | 5 | 14 | 6 | 9.5 | 12 | 12 | 12 | 12 |  | 50 Ohms | TOP=L2:L3=L2/L4:L6=L5/L7:BOTTOM=L7 |
| DACRSET | OTHERS | BUS | 1 | 4.75 | 5 | 10 | 5 | 14 | 6 | 9.5 | 12 | 12 | 12 | 12 |  | 50 Ohms | TOP=L2:L3=L2/L4:L6=L5/L7:BOTTOM=L7 |
| DACRSET | OTHERS | BUS | 2 | 5 | 5 | 10 | 5 | 14 | 6 | 10 | 12 | 12 | 12 | 12 |  | 50 Ohms | TOP=L2:L3=L2/L4:L6=L5/L7:BOTTOM=L7 |
| DACRSET | OTHERS | BUS | 3 | 5 | 5 | 10 | 5 | 14 | 6 | 10 | 12 | 12 | 12 | 12 |  | 50 Ohms | TOP=L2:L3=L2/L4:L6=L5/L7:BOTTOM=L7 |
| DACRSET | OTHERS | BUS | 4 | 5 | 5 | 10 | 5 | 14 | 6 | 10 | 12 | 12 | 12 | 12 |  | 50 Ohms | TOP=L2:L3=L2/L4:L6=L5/L7:BOTTOM=L7 |
| DACRSET | OTHERS | BUS | 5 | 5 | 5 | 10 | 5 | 14 | 6 | 10 | 12 | 12 | 12 | 12 |  | 50 Ohms | TOP=L2:L3=L2/L4:L6=L5/L7:BOTTOM=L7 |
| DACRSET | OTHERS | BUS | 6 | 5 | 5 | 10 | 5 | 14 | 6 | 10 | 12 | 12 | 12 | 12 |  | 50 Ohms | TOP=L2:L3=L2/L4:L6=L5/L7:BOTTOM=L7 |
| DACRSET | OTHERS | BUS | 7 | 5 | 5 | 10 | 5 | 14 | 6 | 10 | 12 | 12 | 12 | 12 |  | 50 Ohms | TOP=L2:L3=L2/L4:L6=L5/L7:BOTTOM=L7 |
| DACRSET | OTHERS | BUS | 8 | 4.75 | 5 | 10 | 5 | 14 | 6 | 9.5 | 12 | 12 | 12 | 12 |  | 50 Ohms | TOP=L2:L3=L2/L4:L6=L5/L7:BOTTOM=L7 |
| DEBUG_CONSOLE_LED_0 | OTHERS | BUS | 1 | 4.75 | 5 | 10 | 5 | 14 | 6 | 9.5 | 12 | 12 | 12 | 12 |  | 50 Ohms | TOP=L2:L3=L2/L4:L6=L5/L7:BOTTOM=L7 |
| DEBUG_CONSOLE_LED_0 | OTHERS | BUS | 2 | 5 | 5 | 10 | 5 | 14 | 6 | 10 | 12 | 12 | 12 | 12 |  | 50 Ohms | TOP=L2:L3=L2/L4:L6=L5/L7:BOTTOM=L7 |
| DEBUG_CONSOLE_LED_0 | OTHERS | BUS | 3 | 5 | 5 | 10 | 5 | 14 | 6 | 10 | 12 | 12 | 12 | 12 |  | 50 Ohms | TOP=L2:L3=L2/L4:L6=L5/L7:BOTTOM=L7 |
| DEBUG_CONSOLE_LED_0 | OTHERS | BUS | 4 | 5 | 5 | 10 | 5 | 14 | 6 | 10 | 12 | 12 | 12 | 12 |  | 50 Ohms | TOP=L2:L3=L2/L4:L6=L5/L7:BOTTOM=L7 |
| DEBUG_CONSOLE_LED_0 | OTHERS | BUS | 5 | 5 | 5 | 10 | 5 | 14 | 6 | 10 | 12 | 12 | 12 | 12 |  | 50 Ohms | TOP=L2:L3=L2/L4:L6=L5/L7:BOTTOM=L7 |
| DEBUG_CONSOLE_LED_0 | OTHERS | BUS | 6 | 5 | 5 | 10 | 5 | 14 | 6 | 10 | 12 | 12 | 12 | 12 |  | 50 Ohms | TOP=L2:L3=L2/L4:L6=L5/L7:BOTTOM=L7 |
| DEBUG_CONSOLE_LED_0 | OTHERS | BUS | 7 | 5 | 5 | 10 | 5 | 14 | 6 | 10 | 12 | 12 | 12 | 12 |  | 50 Ohms | TOP=L2:L3=L2/L4:L6=L5/L7:BOTTOM=L7 |
| DEBUG_CONSOLE_LED_0 | OTHERS | BUS | 8 | 4.75 | 5 | 10 | 5 | 14 | 6 | 9.5 | 12 | 12 | 12 | 12 |  | 50 Ohms | TOP=L2:L3=L2/L4:L6=L5/L7:BOTTOM=L7 |
| DIVIDER_1_IN | OTHERS | BUS | 1 | 4.75 | 5 | 10 | 5 | 14 | 6 | 9.5 | 12 | 12 | 12 | 12 |  | 50 Ohms | TOP=L2:L3=L2/L4:L6=L5/L7:BOTTOM=L7 |
| DIVIDER_1_IN | OTHERS | BUS | 2 | 5 | 5 | 10 | 5 | 14 | 6 | 10 | 12 | 12 | 12 | 12 |  | 50 Ohms | TOP=L2:L3=L2/L4:L6=L5/L7:BOTTOM=L7 |
| DIVIDER_1_IN | OTHERS | BUS | 3 | 5 | 5 | 10 | 5 | 14 | 6 | 10 | 12 | 12 | 12 | 12 |  | 50 Ohms | TOP=L2:L3=L2/L4:L6=L5/L7:BOTTOM=L7 |
| DIVIDER_1_IN | OTHERS | BUS | 4 | 5 | 5 | 10 | 5 | 14 | 6 | 10 | 12 | 12 | 12 | 12 |  | 50 Ohms | TOP=L2:L3=L2/L4:L6=L5/L7:BOTTOM=L7 |
| DIVIDER_1_IN | OTHERS | BUS | 5 | 5 | 5 | 10 | 5 | 14 | 6 | 10 | 12 | 12 | 12 | 12 |  | 50 Ohms | TOP=L2:L3=L2/L4:L6=L5/L7:BOTTOM=L7 |
| DIVIDER_1_IN | OTHERS | BUS | 6 | 5 | 5 | 10 | 5 | 14 | 6 | 10 | 12 | 12 | 12 | 12 |  | 50 Ohms | TOP=L2:L3=L2/L4:L6=L5/L7:BOTTOM=L7 |
| DIVIDER_1_IN | OTHERS | BUS | 7 | 5 | 5 | 10 | 5 | 14 | 6 | 10 | 12 | 12 | 12 | 12 |  | 50 Ohms | TOP=L2:L3=L2/L4:L6=L5/L7:BOTTOM=L7 |
| DIVIDER_1_IN | OTHERS | BUS | 8 | 4.75 | 5 | 10 | 5 | 14 | 6 | 9.5 | 12 | 12 | 12 | 12 |  | 50 Ohms | TOP=L2:L3=L2/L4:L6=L5/L7:BOTTOM=L7 |
| DIVIDER_2_IN | OTHERS | BUS | 1 | 4.75 | 5 | 10 | 5 | 14 | 6 | 9.5 | 12 | 12 | 12 | 12 |  | 50 Ohms | TOP=L2:L3=L2/L4:L6=L5/L7:BOTTOM=L7 |
| DIVIDER_2_IN | OTHERS | BUS | 2 | 5 | 5 | 10 | 5 | 14 | 6 | 10 | 12 | 12 | 12 | 12 |  | 50 Ohms | TOP=L2:L3=L2/L4:L6=L5/L7:BOTTOM=L7 |
| DIVIDER_2_IN | OTHERS | BUS | 3 | 5 | 5 | 10 | 5 | 14 | 6 | 10 | 12 | 12 | 12 | 12 |  | 50 Ohms | TOP=L2:L3=L2/L4:L6=L5/L7:BOTTOM=L7 |
| DIVIDER_2_IN | OTHERS | BUS | 4 | 5 | 5 | 10 | 5 | 14 | 6 | 10 | 12 | 12 | 12 | 12 |  | 50 Ohms | TOP=L2:L3=L2/L4:L6=L5/L7:BOTTOM=L7 |
| DIVIDER_2_IN | OTHERS | BUS | 5 | 5 | 5 | 10 | 5 | 14 | 6 | 10 | 12 | 12 | 12 | 12 |  | 50 Ohms | TOP=L2:L3=L2/L4:L6=L5/L7:BOTTOM=L7 |
| DIVIDER_2_IN | OTHERS | BUS | 6 | 5 | 5 | 10 | 5 | 14 | 6 | 10 | 12 | 12 | 12 | 12 |  | 50 Ohms | TOP=L2:L3=L2/L4:L6=L5/L7:BOTTOM=L7 |
| DIVIDER_2_IN | OTHERS | BUS | 7 | 5 | 5 | 10 | 5 | 14 | 6 | 10 | 12 | 12 | 12 | 12 |  | 50 Ohms | TOP=L2:L3=L2/L4:L6=L5/L7:BOTTOM=L7 |
| DIVIDER_2_IN | OTHERS | BUS | 8 | 4.75 | 5 | 10 | 5 | 14 | 6 | 9.5 | 12 | 12 | 12 | 12 |  | 50 Ohms | TOP=L2:L3=L2/L4:L6=L5/L7:BOTTOM=L7 |
| DP_BMC_CPU_RST_N_R | OTHERS | BUS | 1 | 4.75 | 5 | 10 | 5 | 14 | 6 | 9.5 | 12 | 12 | 12 | 12 |  | 50 Ohms | TOP=L2:L3=L2/L4:L6=L5/L7:BOTTOM=L7 |
| DP_BMC_CPU_RST_N_R | OTHERS | BUS | 2 | 5 | 5 | 10 | 5 | 14 | 6 | 10 | 12 | 12 | 12 | 12 |  | 50 Ohms | TOP=L2:L3=L2/L4:L6=L5/L7:BOTTOM=L7 |
| DP_BMC_CPU_RST_N_R | OTHERS | BUS | 3 | 5 | 5 | 10 | 5 | 14 | 6 | 10 | 12 | 12 | 12 | 12 |  | 50 Ohms | TOP=L2:L3=L2/L4:L6=L5/L7:BOTTOM=L7 |
| DP_BMC_CPU_RST_N_R | OTHERS | BUS | 4 | 5 | 5 | 10 | 5 | 14 | 6 | 10 | 12 | 12 | 12 | 12 |  | 50 Ohms | TOP=L2:L3=L2/L4:L6=L5/L7:BOTTOM=L7 |
| DP_BMC_CPU_RST_N_R | OTHERS | BUS | 5 | 5 | 5 | 10 | 5 | 14 | 6 | 10 | 12 | 12 | 12 | 12 |  | 50 Ohms | TOP=L2:L3=L2/L4:L6=L5/L7:BOTTOM=L7 |
| DP_BMC_CPU_RST_N_R | OTHERS | BUS | 6 | 5 | 5 | 10 | 5 | 14 | 6 | 10 | 12 | 12 | 12 | 12 |  | 50 Ohms | TOP=L2:L3=L2/L4:L6=L5/L7:BOTTOM=L7 |
| DP_BMC_CPU_RST_N_R | OTHERS | BUS | 7 | 5 | 5 | 10 | 5 | 14 | 6 | 10 | 12 | 12 | 12 | 12 |  | 50 Ohms | TOP=L2:L3=L2/L4:L6=L5/L7:BOTTOM=L7 |
| DP_BMC_CPU_RST_N_R | OTHERS | BUS | 8 | 4.75 | 5 | 10 | 5 | 14 | 6 | 9.5 | 12 | 12 | 12 | 12 |  | 50 Ohms | TOP=L2:L3=L2/L4:L6=L5/L7:BOTTOM=L7 |
| DP_RST_N | OTHERS | BUS | 1 | 4.75 | 5 | 10 | 5 | 14 | 6 | 9.5 | 12 | 12 | 12 | 12 |  | 50 Ohms | TOP=L2:L3=L2/L4:L6=L5/L7:BOTTOM=L7 |
| DP_RST_N | OTHERS | BUS | 2 | 5 | 5 | 10 | 5 | 14 | 6 | 10 | 12 | 12 | 12 | 12 |  | 50 Ohms | TOP=L2:L3=L2/L4:L6=L5/L7:BOTTOM=L7 |
| DP_RST_N | OTHERS | BUS | 3 | 5 | 5 | 10 | 5 | 14 | 6 | 10 | 12 | 12 | 12 | 12 |  | 50 Ohms | TOP=L2:L3=L2/L4:L6=L5/L7:BOTTOM=L7 |
| DP_RST_N | OTHERS | BUS | 4 | 5 | 5 | 10 | 5 | 14 | 6 | 10 | 12 | 12 | 12 | 12 |  | 50 Ohms | TOP=L2:L3=L2/L4:L6=L5/L7:BOTTOM=L7 |
| DP_RST_N | OTHERS | BUS | 5 | 5 | 5 | 10 | 5 | 14 | 6 | 10 | 12 | 12 | 12 | 12 |  | 50 Ohms | TOP=L2:L3=L2/L4:L6=L5/L7:BOTTOM=L7 |
| DP_RST_N | OTHERS | BUS | 6 | 5 | 5 | 10 | 5 | 14 | 6 | 10 | 12 | 12 | 12 | 12 |  | 50 Ohms | TOP=L2:L3=L2/L4:L6=L5/L7:BOTTOM=L7 |
| DP_RST_N | OTHERS | BUS | 7 | 5 | 5 | 10 | 5 | 14 | 6 | 10 | 12 | 12 | 12 | 12 |  | 50 Ohms | TOP=L2:L3=L2/L4:L6=L5/L7:BOTTOM=L7 |
| DP_RST_N | OTHERS | BUS | 8 | 4.75 | 5 | 10 | 5 | 14 | 6 | 9.5 | 12 | 12 | 12 | 12 |  | 50 Ohms | TOP=L2:L3=L2/L4:L6=L5/L7:BOTTOM=L7 |
| DP_RST_N_R | OTHERS | BUS | 1 | 4.75 | 5 | 10 | 5 | 14 | 6 | 9.5 | 12 | 12 | 12 | 12 |  | 50 Ohms | TOP=L2:L3=L2/L4:L6=L5/L7:BOTTOM=L7 |
| DP_RST_N_R | OTHERS | BUS | 2 | 5 | 5 | 10 | 5 | 14 | 6 | 10 | 12 | 12 | 12 | 12 |  | 50 Ohms | TOP=L2:L3=L2/L4:L6=L5/L7:BOTTOM=L7 |
| DP_RST_N_R | OTHERS | BUS | 3 | 5 | 5 | 10 | 5 | 14 | 6 | 10 | 12 | 12 | 12 | 12 |  | 50 Ohms | TOP=L2:L3=L2/L4:L6=L5/L7:BOTTOM=L7 |
| DP_RST_N_R | OTHERS | BUS | 4 | 5 | 5 | 10 | 5 | 14 | 6 | 10 | 12 | 12 | 12 | 12 |  | 50 Ohms | TOP=L2:L3=L2/L4:L6=L5/L7:BOTTOM=L7 |
| DP_RST_N_R | OTHERS | BUS | 5 | 5 | 5 | 10 | 5 | 14 | 6 | 10 | 12 | 12 | 12 | 12 |  | 50 Ohms | TOP=L2:L3=L2/L4:L6=L5/L7:BOTTOM=L7 |
| DP_RST_N_R | OTHERS | BUS | 6 | 5 | 5 | 10 | 5 | 14 | 6 | 10 | 12 | 12 | 12 | 12 |  | 50 Ohms | TOP=L2:L3=L2/L4:L6=L5/L7:BOTTOM=L7 |
| DP_RST_N_R | OTHERS | BUS | 7 | 5 | 5 | 10 | 5 | 14 | 6 | 10 | 12 | 12 | 12 | 12 |  | 50 Ohms | TOP=L2:L3=L2/L4:L6=L5/L7:BOTTOM=L7 |
| DP_RST_N_R | OTHERS | BUS | 8 | 4.75 | 5 | 10 | 5 | 14 | 6 | 9.5 | 12 | 12 | 12 | 12 |  | 50 Ohms | TOP=L2:L3=L2/L4:L6=L5/L7:BOTTOM=L7 |
| DPB_HW_REVISION | OTHERS | BUS | 1 | 4.75 | 5 | 10 | 5 | 14 | 6 | 9.5 | 12 | 12 | 12 | 12 |  | 50 Ohms | TOP=L2:L3=L2/L4:L6=L5/L7:BOTTOM=L7 |
| DPB_HW_REVISION | OTHERS | BUS | 2 | 5 | 5 | 10 | 5 | 14 | 6 | 10 | 12 | 12 | 12 | 12 |  | 50 Ohms | TOP=L2:L3=L2/L4:L6=L5/L7:BOTTOM=L7 |
| DPB_HW_REVISION | OTHERS | BUS | 3 | 5 | 5 | 10 | 5 | 14 | 6 | 10 | 12 | 12 | 12 | 12 |  | 50 Ohms | TOP=L2:L3=L2/L4:L6=L5/L7:BOTTOM=L7 |
| DPB_HW_REVISION | OTHERS | BUS | 4 | 5 | 5 | 10 | 5 | 14 | 6 | 10 | 12 | 12 | 12 | 12 |  | 50 Ohms | TOP=L2:L3=L2/L4:L6=L5/L7:BOTTOM=L7 |
| DPB_HW_REVISION | OTHERS | BUS | 5 | 5 | 5 | 10 | 5 | 14 | 6 | 10 | 12 | 12 | 12 | 12 |  | 50 Ohms | TOP=L2:L3=L2/L4:L6=L5/L7:BOTTOM=L7 |
| DPB_HW_REVISION | OTHERS | BUS | 6 | 5 | 5 | 10 | 5 | 14 | 6 | 10 | 12 | 12 | 12 | 12 |  | 50 Ohms | TOP=L2:L3=L2/L4:L6=L5/L7:BOTTOM=L7 |
| DPB_HW_REVISION | OTHERS | BUS | 7 | 5 | 5 | 10 | 5 | 14 | 6 | 10 | 12 | 12 | 12 | 12 |  | 50 Ohms | TOP=L2:L3=L2/L4:L6=L5/L7:BOTTOM=L7 |
| DPB_HW_REVISION | OTHERS | BUS | 8 | 4.75 | 5 | 10 | 5 | 14 | 6 | 9.5 | 12 | 12 | 12 | 12 |  | 50 Ohms | TOP=L2:L3=L2/L4:L6=L5/L7:BOTTOM=L7 |
| DUT_TAP_SEL | OTHERS | BUS | 1 | 4.75 | 5 | 10 | 5 | 14 | 6 | 9.5 | 12 | 12 | 12 | 12 |  | 50 Ohms | TOP=L2:L3=L2/L4:L6=L5/L7:BOTTOM=L7 |
| DUT_TAP_SEL | OTHERS | BUS | 2 | 5 | 5 | 10 | 5 | 14 | 6 | 10 | 12 | 12 | 12 | 12 |  | 50 Ohms | TOP=L2:L3=L2/L4:L6=L5/L7:BOTTOM=L7 |
| DUT_TAP_SEL | OTHERS | BUS | 3 | 5 | 5 | 10 | 5 | 14 | 6 | 10 | 12 | 12 | 12 | 12 |  | 50 Ohms | TOP=L2:L3=L2/L4:L6=L5/L7:BOTTOM=L7 |
| DUT_TAP_SEL | OTHERS | BUS | 4 | 5 | 5 | 10 | 5 | 14 | 6 | 10 | 12 | 12 | 12 | 12 |  | 50 Ohms | TOP=L2:L3=L2/L4:L6=L5/L7:BOTTOM=L7 |
| DUT_TAP_SEL | OTHERS | BUS | 5 | 5 | 5 | 10 | 5 | 14 | 6 | 10 | 12 | 12 | 12 | 12 |  | 50 Ohms | TOP=L2:L3=L2/L4:L6=L5/L7:BOTTOM=L7 |
| DUT_TAP_SEL | OTHERS | BUS | 6 | 5 | 5 | 10 | 5 | 14 | 6 | 10 | 12 | 12 | 12 | 12 |  | 50 Ohms | TOP=L2:L3=L2/L4:L6=L5/L7:BOTTOM=L7 |
| DUT_TAP_SEL | OTHERS | BUS | 7 | 5 | 5 | 10 | 5 | 14 | 6 | 10 | 12 | 12 | 12 | 12 |  | 50 Ohms | TOP=L2:L3=L2/L4:L6=L5/L7:BOTTOM=L7 |
| DUT_TAP_SEL | OTHERS | BUS | 8 | 4.75 | 5 | 10 | 5 | 14 | 6 | 9.5 | 12 | 12 | 12 | 12 |  | 50 Ohms | TOP=L2:L3=L2/L4:L6=L5/L7:BOTTOM=L7 |
| DUT_TAP_SEL_R | OTHERS | BUS | 1 | 4.75 | 5 | 10 | 5 | 14 | 6 | 9.5 | 12 | 12 | 12 | 12 |  | 50 Ohms | TOP=L2:L3=L2/L4:L6=L5/L7:BOTTOM=L7 |
| DUT_TAP_SEL_R | OTHERS | BUS | 2 | 5 | 5 | 10 | 5 | 14 | 6 | 10 | 12 | 12 | 12 | 12 |  | 50 Ohms | TOP=L2:L3=L2/L4:L6=L5/L7:BOTTOM=L7 |
| DUT_TAP_SEL_R | OTHERS | BUS | 3 | 5 | 5 | 10 | 5 | 14 | 6 | 10 | 12 | 12 | 12 | 12 |  | 50 Ohms | TOP=L2:L3=L2/L4:L6=L5/L7:BOTTOM=L7 |
| DUT_TAP_SEL_R | OTHERS | BUS | 4 | 5 | 5 | 10 | 5 | 14 | 6 | 10 | 12 | 12 | 12 | 12 |  | 50 Ohms | TOP=L2:L3=L2/L4:L6=L5/L7:BOTTOM=L7 |
| DUT_TAP_SEL_R | OTHERS | BUS | 5 | 5 | 5 | 10 | 5 | 14 | 6 | 10 | 12 | 12 | 12 | 12 |  | 50 Ohms | TOP=L2:L3=L2/L4:L6=L5/L7:BOTTOM=L7 |
| DUT_TAP_SEL_R | OTHERS | BUS | 6 | 5 | 5 | 10 | 5 | 14 | 6 | 10 | 12 | 12 | 12 | 12 |  | 50 Ohms | TOP=L2:L3=L2/L4:L6=L5/L7:BOTTOM=L7 |
| DUT_TAP_SEL_R | OTHERS | BUS | 7 | 5 | 5 | 10 | 5 | 14 | 6 | 10 | 12 | 12 | 12 | 12 |  | 50 Ohms | TOP=L2:L3=L2/L4:L6=L5/L7:BOTTOM=L7 |
| DUT_TAP_SEL_R | OTHERS | BUS | 8 | 4.75 | 5 | 10 | 5 | 14 | 6 | 9.5 | 12 | 12 | 12 | 12 |  | 50 Ohms | TOP=L2:L3=L2/L4:L6=L5/L7:BOTTOM=L7 |
| DUT_TDI | OTHERS | BUS | 1 | 4.75 | 5 | 10 | 5 | 14 | 6 | 9.5 | 12 | 12 | 12 | 12 |  | 50 Ohms | TOP=L2:L3=L2/L4:L6=L5/L7:BOTTOM=L7 |
| DUT_TDI | OTHERS | BUS | 2 | 5 | 5 | 10 | 5 | 14 | 6 | 10 | 12 | 12 | 12 | 12 |  | 50 Ohms | TOP=L2:L3=L2/L4:L6=L5/L7:BOTTOM=L7 |
| DUT_TDI | OTHERS | BUS | 3 | 5 | 5 | 10 | 5 | 14 | 6 | 10 | 12 | 12 | 12 | 12 |  | 50 Ohms | TOP=L2:L3=L2/L4:L6=L5/L7:BOTTOM=L7 |
| DUT_TDI | OTHERS | BUS | 4 | 5 | 5 | 10 | 5 | 14 | 6 | 10 | 12 | 12 | 12 | 12 |  | 50 Ohms | TOP=L2:L3=L2/L4:L6=L5/L7:BOTTOM=L7 |
| DUT_TDI | OTHERS | BUS | 5 | 5 | 5 | 10 | 5 | 14 | 6 | 10 | 12 | 12 | 12 | 12 |  | 50 Ohms | TOP=L2:L3=L2/L4:L6=L5/L7:BOTTOM=L7 |
| DUT_TDI | OTHERS | BUS | 6 | 5 | 5 | 10 | 5 | 14 | 6 | 10 | 12 | 12 | 12 | 12 |  | 50 Ohms | TOP=L2:L3=L2/L4:L6=L5/L7:BOTTOM=L7 |
| DUT_TDI | OTHERS | BUS | 7 | 5 | 5 | 10 | 5 | 14 | 6 | 10 | 12 | 12 | 12 | 12 |  | 50 Ohms | TOP=L2:L3=L2/L4:L6=L5/L7:BOTTOM=L7 |
| DUT_TDI | OTHERS | BUS | 8 | 4.75 | 5 | 10 | 5 | 14 | 6 | 9.5 | 12 | 12 | 12 | 12 |  | 50 Ohms | TOP=L2:L3=L2/L4:L6=L5/L7:BOTTOM=L7 |
| DUT_TDI_R | OTHERS | BUS | 1 | 4.75 | 5 | 10 | 5 | 14 | 6 | 9.5 | 12 | 12 | 12 | 12 |  | 50 Ohms | TOP=L2:L3=L2/L4:L6=L5/L7:BOTTOM=L7 |
| DUT_TDI_R | OTHERS | BUS | 2 | 5 | 5 | 10 | 5 | 14 | 6 | 10 | 12 | 12 | 12 | 12 |  | 50 Ohms | TOP=L2:L3=L2/L4:L6=L5/L7:BOTTOM=L7 |
| DUT_TDI_R | OTHERS | BUS | 3 | 5 | 5 | 10 | 5 | 14 | 6 | 10 | 12 | 12 | 12 | 12 |  | 50 Ohms | TOP=L2:L3=L2/L4:L6=L5/L7:BOTTOM=L7 |
| DUT_TDI_R | OTHERS | BUS | 4 | 5 | 5 | 10 | 5 | 14 | 6 | 10 | 12 | 12 | 12 | 12 |  | 50 Ohms | TOP=L2:L3=L2/L4:L6=L5/L7:BOTTOM=L7 |
| DUT_TDI_R | OTHERS | BUS | 5 | 5 | 5 | 10 | 5 | 14 | 6 | 10 | 12 | 12 | 12 | 12 |  | 50 Ohms | TOP=L2:L3=L2/L4:L6=L5/L7:BOTTOM=L7 |
| DUT_TDI_R | OTHERS | BUS | 6 | 5 | 5 | 10 | 5 | 14 | 6 | 10 | 12 | 12 | 12 | 12 |  | 50 Ohms | TOP=L2:L3=L2/L4:L6=L5/L7:BOTTOM=L7 |
| DUT_TDI_R | OTHERS | BUS | 7 | 5 | 5 | 10 | 5 | 14 | 6 | 10 | 12 | 12 | 12 | 12 |  | 50 Ohms | TOP=L2:L3=L2/L4:L6=L5/L7:BOTTOM=L7 |
| DUT_TDI_R | OTHERS | BUS | 8 | 4.75 | 5 | 10 | 5 | 14 | 6 | 9.5 | 12 | 12 | 12 | 12 |  | 50 Ohms | TOP=L2:L3=L2/L4:L6=L5/L7:BOTTOM=L7 |
| DUT_TDO | OTHERS | BUS | 1 | 4.75 | 5 | 10 | 5 | 14 | 6 | 9.5 | 12 | 12 | 12 | 12 |  | 50 Ohms | TOP=L2:L3=L2/L4:L6=L5/L7:BOTTOM=L7 |
| DUT_TDO | OTHERS | BUS | 2 | 5 | 5 | 10 | 5 | 14 | 6 | 10 | 12 | 12 | 12 | 12 |  | 50 Ohms | TOP=L2:L3=L2/L4:L6=L5/L7:BOTTOM=L7 |
| DUT_TDO | OTHERS | BUS | 3 | 5 | 5 | 10 | 5 | 14 | 6 | 10 | 12 | 12 | 12 | 12 |  | 50 Ohms | TOP=L2:L3=L2/L4:L6=L5/L7:BOTTOM=L7 |
| DUT_TDO | OTHERS | BUS | 4 | 5 | 5 | 10 | 5 | 14 | 6 | 10 | 12 | 12 | 12 | 12 |  | 50 Ohms | TOP=L2:L3=L2/L4:L6=L5/L7:BOTTOM=L7 |
| DUT_TDO | OTHERS | BUS | 5 | 5 | 5 | 10 | 5 | 14 | 6 | 10 | 12 | 12 | 12 | 12 |  | 50 Ohms | TOP=L2:L3=L2/L4:L6=L5/L7:BOTTOM=L7 |
| DUT_TDO | OTHERS | BUS | 6 | 5 | 5 | 10 | 5 | 14 | 6 | 10 | 12 | 12 | 12 | 12 |  | 50 Ohms | TOP=L2:L3=L2/L4:L6=L5/L7:BOTTOM=L7 |
| DUT_TDO | OTHERS | BUS | 7 | 5 | 5 | 10 | 5 | 14 | 6 | 10 | 12 | 12 | 12 | 12 |  | 50 Ohms | TOP=L2:L3=L2/L4:L6=L5/L7:BOTTOM=L7 |
| DUT_TDO | OTHERS | BUS | 8 | 4.75 | 5 | 10 | 5 | 14 | 6 | 9.5 | 12 | 12 | 12 | 12 |  | 50 Ohms | TOP=L2:L3=L2/L4:L6=L5/L7:BOTTOM=L7 |
| DUT_TDO_R | OTHERS | BUS | 1 | 4.75 | 5 | 10 | 5 | 14 | 6 | 9.5 | 12 | 12 | 12 | 12 |  | 50 Ohms | TOP=L2:L3=L2/L4:L6=L5/L7:BOTTOM=L7 |
| DUT_TDO_R | OTHERS | BUS | 2 | 5 | 5 | 10 | 5 | 14 | 6 | 10 | 12 | 12 | 12 | 12 |  | 50 Ohms | TOP=L2:L3=L2/L4:L6=L5/L7:BOTTOM=L7 |
| DUT_TDO_R | OTHERS | BUS | 3 | 5 | 5 | 10 | 5 | 14 | 6 | 10 | 12 | 12 | 12 | 12 |  | 50 Ohms | TOP=L2:L3=L2/L4:L6=L5/L7:BOTTOM=L7 |
| DUT_TDO_R | OTHERS | BUS | 4 | 5 | 5 | 10 | 5 | 14 | 6 | 10 | 12 | 12 | 12 | 12 |  | 50 Ohms | TOP=L2:L3=L2/L4:L6=L5/L7:BOTTOM=L7 |
| DUT_TDO_R | OTHERS | BUS | 5 | 5 | 5 | 10 | 5 | 14 | 6 | 10 | 12 | 12 | 12 | 12 |  | 50 Ohms | TOP=L2:L3=L2/L4:L6=L5/L7:BOTTOM=L7 |
| DUT_TDO_R | OTHERS | BUS | 6 | 5 | 5 | 10 | 5 | 14 | 6 | 10 | 12 | 12 | 12 | 12 |  | 50 Ohms | TOP=L2:L3=L2/L4:L6=L5/L7:BOTTOM=L7 |
| DUT_TDO_R | OTHERS | BUS | 7 | 5 | 5 | 10 | 5 | 14 | 6 | 10 | 12 | 12 | 12 | 12 |  | 50 Ohms | TOP=L2:L3=L2/L4:L6=L5/L7:BOTTOM=L7 |
| DUT_TDO_R | OTHERS | BUS | 8 | 4.75 | 5 | 10 | 5 | 14 | 6 | 9.5 | 12 | 12 | 12 | 12 |  | 50 Ohms | TOP=L2:L3=L2/L4:L6=L5/L7:BOTTOM=L7 |
| EEPROM_A0 | OTHERS | BUS | 1 | 4.75 | 5 | 10 | 5 | 14 | 6 | 9.5 | 12 | 12 | 12 | 12 |  | 50 Ohms | TOP=L2:L3=L2/L4:L6=L5/L7:BOTTOM=L7 |
| EEPROM_A0 | OTHERS | BUS | 2 | 5 | 5 | 10 | 5 | 14 | 6 | 10 | 12 | 12 | 12 | 12 |  | 50 Ohms | TOP=L2:L3=L2/L4:L6=L5/L7:BOTTOM=L7 |
| EEPROM_A0 | OTHERS | BUS | 3 | 5 | 5 | 10 | 5 | 14 | 6 | 10 | 12 | 12 | 12 | 12 |  | 50 Ohms | TOP=L2:L3=L2/L4:L6=L5/L7:BOTTOM=L7 |
| EEPROM_A0 | OTHERS | BUS | 4 | 5 | 5 | 10 | 5 | 14 | 6 | 10 | 12 | 12 | 12 | 12 |  | 50 Ohms | TOP=L2:L3=L2/L4:L6=L5/L7:BOTTOM=L7 |
| EEPROM_A0 | OTHERS | BUS | 5 | 5 | 5 | 10 | 5 | 14 | 6 | 10 | 12 | 12 | 12 | 12 |  | 50 Ohms | TOP=L2:L3=L2/L4:L6=L5/L7:BOTTOM=L7 |
| EEPROM_A0 | OTHERS | BUS | 6 | 5 | 5 | 10 | 5 | 14 | 6 | 10 | 12 | 12 | 12 | 12 |  | 50 Ohms | TOP=L2:L3=L2/L4:L6=L5/L7:BOTTOM=L7 |
| EEPROM_A0 | OTHERS | BUS | 7 | 5 | 5 | 10 | 5 | 14 | 6 | 10 | 12 | 12 | 12 | 12 |  | 50 Ohms | TOP=L2:L3=L2/L4:L6=L5/L7:BOTTOM=L7 |
| EEPROM_A0 | OTHERS | BUS | 8 | 4.75 | 5 | 10 | 5 | 14 | 6 | 9.5 | 12 | 12 | 12 | 12 |  | 50 Ohms | TOP=L2:L3=L2/L4:L6=L5/L7:BOTTOM=L7 |
| EEPROM_A0_R | OTHERS | BUS | 1 | 4.75 | 5 | 10 | 5 | 14 | 6 | 9.5 | 12 | 12 | 12 | 12 |  | 50 Ohms | TOP=L2:L3=L2/L4:L6=L5/L7:BOTTOM=L7 |
| EEPROM_A0_R | OTHERS | BUS | 2 | 5 | 5 | 10 | 5 | 14 | 6 | 10 | 12 | 12 | 12 | 12 |  | 50 Ohms | TOP=L2:L3=L2/L4:L6=L5/L7:BOTTOM=L7 |
| EEPROM_A0_R | OTHERS | BUS | 3 | 5 | 5 | 10 | 5 | 14 | 6 | 10 | 12 | 12 | 12 | 12 |  | 50 Ohms | TOP=L2:L3=L2/L4:L6=L5/L7:BOTTOM=L7 |
| EEPROM_A0_R | OTHERS | BUS | 4 | 5 | 5 | 10 | 5 | 14 | 6 | 10 | 12 | 12 | 12 | 12 |  | 50 Ohms | TOP=L2:L3=L2/L4:L6=L5/L7:BOTTOM=L7 |
| EEPROM_A0_R | OTHERS | BUS | 5 | 5 | 5 | 10 | 5 | 14 | 6 | 10 | 12 | 12 | 12 | 12 |  | 50 Ohms | TOP=L2:L3=L2/L4:L6=L5/L7:BOTTOM=L7 |
| EEPROM_A0_R | OTHERS | BUS | 6 | 5 | 5 | 10 | 5 | 14 | 6 | 10 | 12 | 12 | 12 | 12 |  | 50 Ohms | TOP=L2:L3=L2/L4:L6=L5/L7:BOTTOM=L7 |
| EEPROM_A0_R | OTHERS | BUS | 7 | 5 | 5 | 10 | 5 | 14 | 6 | 10 | 12 | 12 | 12 | 12 |  | 50 Ohms | TOP=L2:L3=L2/L4:L6=L5/L7:BOTTOM=L7 |
| EEPROM_A0_R | OTHERS | BUS | 8 | 4.75 | 5 | 10 | 5 | 14 | 6 | 9.5 | 12 | 12 | 12 | 12 |  | 50 Ohms | TOP=L2:L3=L2/L4:L6=L5/L7:BOTTOM=L7 |
| EEPROM_A1 | OTHERS | BUS | 1 | 4.75 | 5 | 10 | 5 | 14 | 6 | 9.5 | 12 | 12 | 12 | 12 |  | 50 Ohms | TOP=L2:L3=L2/L4:L6=L5/L7:BOTTOM=L7 |
| EEPROM_A1 | OTHERS | BUS | 2 | 5 | 5 | 10 | 5 | 14 | 6 | 10 | 12 | 12 | 12 | 12 |  | 50 Ohms | TOP=L2:L3=L2/L4:L6=L5/L7:BOTTOM=L7 |
| EEPROM_A1 | OTHERS | BUS | 3 | 5 | 5 | 10 | 5 | 14 | 6 | 10 | 12 | 12 | 12 | 12 |  | 50 Ohms | TOP=L2:L3=L2/L4:L6=L5/L7:BOTTOM=L7 |
| EEPROM_A1 | OTHERS | BUS | 4 | 5 | 5 | 10 | 5 | 14 | 6 | 10 | 12 | 12 | 12 | 12 |  | 50 Ohms | TOP=L2:L3=L2/L4:L6=L5/L7:BOTTOM=L7 |
| EEPROM_A1 | OTHERS | BUS | 5 | 5 | 5 | 10 | 5 | 14 | 6 | 10 | 12 | 12 | 12 | 12 |  | 50 Ohms | TOP=L2:L3=L2/L4:L6=L5/L7:BOTTOM=L7 |
| EEPROM_A1 | OTHERS | BUS | 6 | 5 | 5 | 10 | 5 | 14 | 6 | 10 | 12 | 12 | 12 | 12 |  | 50 Ohms | TOP=L2:L3=L2/L4:L6=L5/L7:BOTTOM=L7 |
| EEPROM_A1 | OTHERS | BUS | 7 | 5 | 5 | 10 | 5 | 14 | 6 | 10 | 12 | 12 | 12 | 12 |  | 50 Ohms | TOP=L2:L3=L2/L4:L6=L5/L7:BOTTOM=L7 |
| EEPROM_A1 | OTHERS | BUS | 8 | 4.75 | 5 | 10 | 5 | 14 | 6 | 9.5 | 12 | 12 | 12 | 12 |  | 50 Ohms | TOP=L2:L3=L2/L4:L6=L5/L7:BOTTOM=L7 |
| EEPROM_A1_R | OTHERS | BUS | 1 | 4.75 | 5 | 10 | 5 | 14 | 6 | 9.5 | 12 | 12 | 12 | 12 |  | 50 Ohms | TOP=L2:L3=L2/L4:L6=L5/L7:BOTTOM=L7 |
| EEPROM_A1_R | OTHERS | BUS | 2 | 5 | 5 | 10 | 5 | 14 | 6 | 10 | 12 | 12 | 12 | 12 |  | 50 Ohms | TOP=L2:L3=L2/L4:L6=L5/L7:BOTTOM=L7 |
| EEPROM_A1_R | OTHERS | BUS | 3 | 5 | 5 | 10 | 5 | 14 | 6 | 10 | 12 | 12 | 12 | 12 |  | 50 Ohms | TOP=L2:L3=L2/L4:L6=L5/L7:BOTTOM=L7 |
| EEPROM_A1_R | OTHERS | BUS | 4 | 5 | 5 | 10 | 5 | 14 | 6 | 10 | 12 | 12 | 12 | 12 |  | 50 Ohms | TOP=L2:L3=L2/L4:L6=L5/L7:BOTTOM=L7 |
| EEPROM_A1_R | OTHERS | BUS | 5 | 5 | 5 | 10 | 5 | 14 | 6 | 10 | 12 | 12 | 12 | 12 |  | 50 Ohms | TOP=L2:L3=L2/L4:L6=L5/L7:BOTTOM=L7 |
| EEPROM_A1_R | OTHERS | BUS | 6 | 5 | 5 | 10 | 5 | 14 | 6 | 10 | 12 | 12 | 12 | 12 |  | 50 Ohms | TOP=L2:L3=L2/L4:L6=L5/L7:BOTTOM=L7 |
| EEPROM_A1_R | OTHERS | BUS | 7 | 5 | 5 | 10 | 5 | 14 | 6 | 10 | 12 | 12 | 12 | 12 |  | 50 Ohms | TOP=L2:L3=L2/L4:L6=L5/L7:BOTTOM=L7 |
| EEPROM_A1_R | OTHERS | BUS | 8 | 4.75 | 5 | 10 | 5 | 14 | 6 | 9.5 | 12 | 12 | 12 | 12 |  | 50 Ohms | TOP=L2:L3=L2/L4:L6=L5/L7:BOTTOM=L7 |
| EEPROM_A2 | OTHERS | BUS | 1 | 4.75 | 5 | 10 | 5 | 14 | 6 | 9.5 | 12 | 12 | 12 | 12 |  | 50 Ohms | TOP=L2:L3=L2/L4:L6=L5/L7:BOTTOM=L7 |
| EEPROM_A2 | OTHERS | BUS | 2 | 5 | 5 | 10 | 5 | 14 | 6 | 10 | 12 | 12 | 12 | 12 |  | 50 Ohms | TOP=L2:L3=L2/L4:L6=L5/L7:BOTTOM=L7 |
| EEPROM_A2 | OTHERS | BUS | 3 | 5 | 5 | 10 | 5 | 14 | 6 | 10 | 12 | 12 | 12 | 12 |  | 50 Ohms | TOP=L2:L3=L2/L4:L6=L5/L7:BOTTOM=L7 |
| EEPROM_A2 | OTHERS | BUS | 4 | 5 | 5 | 10 | 5 | 14 | 6 | 10 | 12 | 12 | 12 | 12 |  | 50 Ohms | TOP=L2:L3=L2/L4:L6=L5/L7:BOTTOM=L7 |
| EEPROM_A2 | OTHERS | BUS | 5 | 5 | 5 | 10 | 5 | 14 | 6 | 10 | 12 | 12 | 12 | 12 |  | 50 Ohms | TOP=L2:L3=L2/L4:L6=L5/L7:BOTTOM=L7 |
| EEPROM_A2 | OTHERS | BUS | 6 | 5 | 5 | 10 | 5 | 14 | 6 | 10 | 12 | 12 | 12 | 12 |  | 50 Ohms | TOP=L2:L3=L2/L4:L6=L5/L7:BOTTOM=L7 |
| EEPROM_A2 | OTHERS | BUS | 7 | 5 | 5 | 10 | 5 | 14 | 6 | 10 | 12 | 12 | 12 | 12 |  | 50 Ohms | TOP=L2:L3=L2/L4:L6=L5/L7:BOTTOM=L7 |
| EEPROM_A2 | OTHERS | BUS | 8 | 4.75 | 5 | 10 | 5 | 14 | 6 | 9.5 | 12 | 12 | 12 | 12 |  | 50 Ohms | TOP=L2:L3=L2/L4:L6=L5/L7:BOTTOM=L7 |
| EEPROM_A2_R | OTHERS | BUS | 1 | 4.75 | 5 | 10 | 5 | 14 | 6 | 9.5 | 12 | 12 | 12 | 12 |  | 50 Ohms | TOP=L2:L3=L2/L4:L6=L5/L7:BOTTOM=L7 |
| EEPROM_A2_R | OTHERS | BUS | 2 | 5 | 5 | 10 | 5 | 14 | 6 | 10 | 12 | 12 | 12 | 12 |  | 50 Ohms | TOP=L2:L3=L2/L4:L6=L5/L7:BOTTOM=L7 |
| EEPROM_A2_R | OTHERS | BUS | 3 | 5 | 5 | 10 | 5 | 14 | 6 | 10 | 12 | 12 | 12 | 12 |  | 50 Ohms | TOP=L2:L3=L2/L4:L6=L5/L7:BOTTOM=L7 |
| EEPROM_A2_R | OTHERS | BUS | 4 | 5 | 5 | 10 | 5 | 14 | 6 | 10 | 12 | 12 | 12 | 12 |  | 50 Ohms | TOP=L2:L3=L2/L4:L6=L5/L7:BOTTOM=L7 |
| EEPROM_A2_R | OTHERS | BUS | 5 | 5 | 5 | 10 | 5 | 14 | 6 | 10 | 12 | 12 | 12 | 12 |  | 50 Ohms | TOP=L2:L3=L2/L4:L6=L5/L7:BOTTOM=L7 |
| EEPROM_A2_R | OTHERS | BUS | 6 | 5 | 5 | 10 | 5 | 14 | 6 | 10 | 12 | 12 | 12 | 12 |  | 50 Ohms | TOP=L2:L3=L2/L4:L6=L5/L7:BOTTOM=L7 |
| EEPROM_A2_R | OTHERS | BUS | 7 | 5 | 5 | 10 | 5 | 14 | 6 | 10 | 12 | 12 | 12 | 12 |  | 50 Ohms | TOP=L2:L3=L2/L4:L6=L5/L7:BOTTOM=L7 |
| EEPROM_A2_R | OTHERS | BUS | 8 | 4.75 | 5 | 10 | 5 | 14 | 6 | 9.5 | 12 | 12 | 12 | 12 |  | 50 Ohms | TOP=L2:L3=L2/L4:L6=L5/L7:BOTTOM=L7 |
| EEPROM_WP | OTHERS | BUS | 1 | 4.75 | 5 | 10 | 5 | 14 | 6 | 9.5 | 12 | 12 | 12 | 12 |  | 50 Ohms | TOP=L2:L3=L2/L4:L6=L5/L7:BOTTOM=L7 |
| EEPROM_WP | OTHERS | BUS | 2 | 5 | 5 | 10 | 5 | 14 | 6 | 10 | 12 | 12 | 12 | 12 |  | 50 Ohms | TOP=L2:L3=L2/L4:L6=L5/L7:BOTTOM=L7 |
| EEPROM_WP | OTHERS | BUS | 3 | 5 | 5 | 10 | 5 | 14 | 6 | 10 | 12 | 12 | 12 | 12 |  | 50 Ohms | TOP=L2:L3=L2/L4:L6=L5/L7:BOTTOM=L7 |
| EEPROM_WP | OTHERS | BUS | 4 | 5 | 5 | 10 | 5 | 14 | 6 | 10 | 12 | 12 | 12 | 12 |  | 50 Ohms | TOP=L2:L3=L2/L4:L6=L5/L7:BOTTOM=L7 |
| EEPROM_WP | OTHERS | BUS | 5 | 5 | 5 | 10 | 5 | 14 | 6 | 10 | 12 | 12 | 12 | 12 |  | 50 Ohms | TOP=L2:L3=L2/L4:L6=L5/L7:BOTTOM=L7 |
| EEPROM_WP | OTHERS | BUS | 6 | 5 | 5 | 10 | 5 | 14 | 6 | 10 | 12 | 12 | 12 | 12 |  | 50 Ohms | TOP=L2:L3=L2/L4:L6=L5/L7:BOTTOM=L7 |
| EEPROM_WP | OTHERS | BUS | 7 | 5 | 5 | 10 | 5 | 14 | 6 | 10 | 12 | 12 | 12 | 12 |  | 50 Ohms | TOP=L2:L3=L2/L4:L6=L5/L7:BOTTOM=L7 |
| EEPROM_WP | OTHERS | BUS | 8 | 4.75 | 5 | 10 | 5 | 14 | 6 | 9.5 | 12 | 12 | 12 | 12 |  | 50 Ohms | TOP=L2:L3=L2/L4:L6=L5/L7:BOTTOM=L7 |
| EEPROM_WP_8536 | OTHERS | BUS | 1 | 4.75 | 5 | 10 | 5 | 14 | 6 | 9.5 | 12 | 12 | 12 | 12 |  | 50 Ohms | TOP=L2:L3=L2/L4:L6=L5/L7:BOTTOM=L7 |
| EEPROM_WP_8536 | OTHERS | BUS | 2 | 5 | 5 | 10 | 5 | 14 | 6 | 10 | 12 | 12 | 12 | 12 |  | 50 Ohms | TOP=L2:L3=L2/L4:L6=L5/L7:BOTTOM=L7 |
| EEPROM_WP_8536 | OTHERS | BUS | 3 | 5 | 5 | 10 | 5 | 14 | 6 | 10 | 12 | 12 | 12 | 12 |  | 50 Ohms | TOP=L2:L3=L2/L4:L6=L5/L7:BOTTOM=L7 |
| EEPROM_WP_8536 | OTHERS | BUS | 4 | 5 | 5 | 10 | 5 | 14 | 6 | 10 | 12 | 12 | 12 | 12 |  | 50 Ohms | TOP=L2:L3=L2/L4:L6=L5/L7:BOTTOM=L7 |
| EEPROM_WP_8536 | OTHERS | BUS | 5 | 5 | 5 | 10 | 5 | 14 | 6 | 10 | 12 | 12 | 12 | 12 |  | 50 Ohms | TOP=L2:L3=L2/L4:L6=L5/L7:BOTTOM=L7 |
| EEPROM_WP_8536 | OTHERS | BUS | 6 | 5 | 5 | 10 | 5 | 14 | 6 | 10 | 12 | 12 | 12 | 12 |  | 50 Ohms | TOP=L2:L3=L2/L4:L6=L5/L7:BOTTOM=L7 |
| EEPROM_WP_8536 | OTHERS | BUS | 7 | 5 | 5 | 10 | 5 | 14 | 6 | 10 | 12 | 12 | 12 | 12 |  | 50 Ohms | TOP=L2:L3=L2/L4:L6=L5/L7:BOTTOM=L7 |
| EEPROM_WP_8536 | OTHERS | BUS | 8 | 4.75 | 5 | 10 | 5 | 14 | 6 | 9.5 | 12 | 12 | 12 | 12 |  | 50 Ohms | TOP=L2:L3=L2/L4:L6=L5/L7:BOTTOM=L7 |
| EJTAG_DINT | OTHERS | BUS | 1 | 4.75 | 5 | 10 | 5 | 14 | 6 | 9.5 | 12 | 12 | 12 | 12 |  | 50 Ohms | TOP=L2:L3=L2/L4:L6=L5/L7:BOTTOM=L7 |
| EJTAG_DINT | OTHERS | BUS | 2 | 5 | 5 | 10 | 5 | 14 | 6 | 10 | 12 | 12 | 12 | 12 |  | 50 Ohms | TOP=L2:L3=L2/L4:L6=L5/L7:BOTTOM=L7 |
| EJTAG_DINT | OTHERS | BUS | 3 | 5 | 5 | 10 | 5 | 14 | 6 | 10 | 12 | 12 | 12 | 12 |  | 50 Ohms | TOP=L2:L3=L2/L4:L6=L5/L7:BOTTOM=L7 |
| EJTAG_DINT | OTHERS | BUS | 4 | 5 | 5 | 10 | 5 | 14 | 6 | 10 | 12 | 12 | 12 | 12 |  | 50 Ohms | TOP=L2:L3=L2/L4:L6=L5/L7:BOTTOM=L7 |
| EJTAG_DINT | OTHERS | BUS | 5 | 5 | 5 | 10 | 5 | 14 | 6 | 10 | 12 | 12 | 12 | 12 |  | 50 Ohms | TOP=L2:L3=L2/L4:L6=L5/L7:BOTTOM=L7 |
| EJTAG_DINT | OTHERS | BUS | 6 | 5 | 5 | 10 | 5 | 14 | 6 | 10 | 12 | 12 | 12 | 12 |  | 50 Ohms | TOP=L2:L3=L2/L4:L6=L5/L7:BOTTOM=L7 |
| EJTAG_DINT | OTHERS | BUS | 7 | 5 | 5 | 10 | 5 | 14 | 6 | 10 | 12 | 12 | 12 | 12 |  | 50 Ohms | TOP=L2:L3=L2/L4:L6=L5/L7:BOTTOM=L7 |
| EJTAG_DINT | OTHERS | BUS | 8 | 4.75 | 5 | 10 | 5 | 14 | 6 | 9.5 | 12 | 12 | 12 | 12 |  | 50 Ohms | TOP=L2:L3=L2/L4:L6=L5/L7:BOTTOM=L7 |
| EJTAG_PWR | OTHERS | BUS | 1 | 4.75 | 5 | 10 | 5 | 14 | 6 | 9.5 | 12 | 12 | 12 | 12 |  | 50 Ohms | TOP=L2:L3=L2/L4:L6=L5/L7:BOTTOM=L7 |
| EJTAG_PWR | OTHERS | BUS | 2 | 5 | 5 | 10 | 5 | 14 | 6 | 10 | 12 | 12 | 12 | 12 |  | 50 Ohms | TOP=L2:L3=L2/L4:L6=L5/L7:BOTTOM=L7 |
| EJTAG_PWR | OTHERS | BUS | 3 | 5 | 5 | 10 | 5 | 14 | 6 | 10 | 12 | 12 | 12 | 12 |  | 50 Ohms | TOP=L2:L3=L2/L4:L6=L5/L7:BOTTOM=L7 |
| EJTAG_PWR | OTHERS | BUS | 4 | 5 | 5 | 10 | 5 | 14 | 6 | 10 | 12 | 12 | 12 | 12 |  | 50 Ohms | TOP=L2:L3=L2/L4:L6=L5/L7:BOTTOM=L7 |
| EJTAG_PWR | OTHERS | BUS | 5 | 5 | 5 | 10 | 5 | 14 | 6 | 10 | 12 | 12 | 12 | 12 |  | 50 Ohms | TOP=L2:L3=L2/L4:L6=L5/L7:BOTTOM=L7 |
| EJTAG_PWR | OTHERS | BUS | 6 | 5 | 5 | 10 | 5 | 14 | 6 | 10 | 12 | 12 | 12 | 12 |  | 50 Ohms | TOP=L2:L3=L2/L4:L6=L5/L7:BOTTOM=L7 |
| EJTAG_PWR | OTHERS | BUS | 7 | 5 | 5 | 10 | 5 | 14 | 6 | 10 | 12 | 12 | 12 | 12 |  | 50 Ohms | TOP=L2:L3=L2/L4:L6=L5/L7:BOTTOM=L7 |
| EJTAG_PWR | OTHERS | BUS | 8 | 4.75 | 5 | 10 | 5 | 14 | 6 | 9.5 | 12 | 12 | 12 | 12 |  | 50 Ohms | TOP=L2:L3=L2/L4:L6=L5/L7:BOTTOM=L7 |
| EJTAG_RSTB | OTHERS | BUS | 1 | 4.75 | 5 | 10 | 5 | 14 | 6 | 9.5 | 12 | 12 | 12 | 12 |  | 50 Ohms | TOP=L2:L3=L2/L4:L6=L5/L7:BOTTOM=L7 |
| EJTAG_RSTB | OTHERS | BUS | 2 | 5 | 5 | 10 | 5 | 14 | 6 | 10 | 12 | 12 | 12 | 12 |  | 50 Ohms | TOP=L2:L3=L2/L4:L6=L5/L7:BOTTOM=L7 |
| EJTAG_RSTB | OTHERS | BUS | 3 | 5 | 5 | 10 | 5 | 14 | 6 | 10 | 12 | 12 | 12 | 12 |  | 50 Ohms | TOP=L2:L3=L2/L4:L6=L5/L7:BOTTOM=L7 |
| EJTAG_RSTB | OTHERS | BUS | 4 | 5 | 5 | 10 | 5 | 14 | 6 | 10 | 12 | 12 | 12 | 12 |  | 50 Ohms | TOP=L2:L3=L2/L4:L6=L5/L7:BOTTOM=L7 |
| EJTAG_RSTB | OTHERS | BUS | 5 | 5 | 5 | 10 | 5 | 14 | 6 | 10 | 12 | 12 | 12 | 12 |  | 50 Ohms | TOP=L2:L3=L2/L4:L6=L5/L7:BOTTOM=L7 |
| EJTAG_RSTB | OTHERS | BUS | 6 | 5 | 5 | 10 | 5 | 14 | 6 | 10 | 12 | 12 | 12 | 12 |  | 50 Ohms | TOP=L2:L3=L2/L4:L6=L5/L7:BOTTOM=L7 |
| EJTAG_RSTB | OTHERS | BUS | 7 | 5 | 5 | 10 | 5 | 14 | 6 | 10 | 12 | 12 | 12 | 12 |  | 50 Ohms | TOP=L2:L3=L2/L4:L6=L5/L7:BOTTOM=L7 |
| EJTAG_RSTB | OTHERS | BUS | 8 | 4.75 | 5 | 10 | 5 | 14 | 6 | 9.5 | 12 | 12 | 12 | 12 |  | 50 Ohms | TOP=L2:L3=L2/L4:L6=L5/L7:BOTTOM=L7 |
| EJTAG_TCK | OTHERS | BUS | 1 | 4.75 | 5 | 10 | 5 | 14 | 6 | 9.5 | 12 | 12 | 12 | 12 |  | 50 Ohms | TOP=L2:L3=L2/L4:L6=L5/L7:BOTTOM=L7 |
| EJTAG_TCK | OTHERS | BUS | 2 | 5 | 5 | 10 | 5 | 14 | 6 | 10 | 12 | 12 | 12 | 12 |  | 50 Ohms | TOP=L2:L3=L2/L4:L6=L5/L7:BOTTOM=L7 |
| EJTAG_TCK | OTHERS | BUS | 3 | 5 | 5 | 10 | 5 | 14 | 6 | 10 | 12 | 12 | 12 | 12 |  | 50 Ohms | TOP=L2:L3=L2/L4:L6=L5/L7:BOTTOM=L7 |
| EJTAG_TCK | OTHERS | BUS | 4 | 5 | 5 | 10 | 5 | 14 | 6 | 10 | 12 | 12 | 12 | 12 |  | 50 Ohms | TOP=L2:L3=L2/L4:L6=L5/L7:BOTTOM=L7 |
| EJTAG_TCK | OTHERS | BUS | 5 | 5 | 5 | 10 | 5 | 14 | 6 | 10 | 12 | 12 | 12 | 12 |  | 50 Ohms | TOP=L2:L3=L2/L4:L6=L5/L7:BOTTOM=L7 |
| EJTAG_TCK | OTHERS | BUS | 6 | 5 | 5 | 10 | 5 | 14 | 6 | 10 | 12 | 12 | 12 | 12 |  | 50 Ohms | TOP=L2:L3=L2/L4:L6=L5/L7:BOTTOM=L7 |
| EJTAG_TCK | OTHERS | BUS | 7 | 5 | 5 | 10 | 5 | 14 | 6 | 10 | 12 | 12 | 12 | 12 |  | 50 Ohms | TOP=L2:L3=L2/L4:L6=L5/L7:BOTTOM=L7 |
| EJTAG_TCK | OTHERS | BUS | 8 | 4.75 | 5 | 10 | 5 | 14 | 6 | 9.5 | 12 | 12 | 12 | 12 |  | 50 Ohms | TOP=L2:L3=L2/L4:L6=L5/L7:BOTTOM=L7 |
| EJTAG_TCK_R | OTHERS | BUS | 1 | 4.75 | 5 | 10 | 5 | 14 | 6 | 9.5 | 12 | 12 | 12 | 12 |  | 50 Ohms | TOP=L2:L3=L2/L4:L6=L5/L7:BOTTOM=L7 |
| EJTAG_TCK_R | OTHERS | BUS | 2 | 5 | 5 | 10 | 5 | 14 | 6 | 10 | 12 | 12 | 12 | 12 |  | 50 Ohms | TOP=L2:L3=L2/L4:L6=L5/L7:BOTTOM=L7 |
| EJTAG_TCK_R | OTHERS | BUS | 3 | 5 | 5 | 10 | 5 | 14 | 6 | 10 | 12 | 12 | 12 | 12 |  | 50 Ohms | TOP=L2:L3=L2/L4:L6=L5/L7:BOTTOM=L7 |
| EJTAG_TCK_R | OTHERS | BUS | 4 | 5 | 5 | 10 | 5 | 14 | 6 | 10 | 12 | 12 | 12 | 12 |  | 50 Ohms | TOP=L2:L3=L2/L4:L6=L5/L7:BOTTOM=L7 |
| EJTAG_TCK_R | OTHERS | BUS | 5 | 5 | 5 | 10 | 5 | 14 | 6 | 10 | 12 | 12 | 12 | 12 |  | 50 Ohms | TOP=L2:L3=L2/L4:L6=L5/L7:BOTTOM=L7 |
| EJTAG_TCK_R | OTHERS | BUS | 6 | 5 | 5 | 10 | 5 | 14 | 6 | 10 | 12 | 12 | 12 | 12 |  | 50 Ohms | TOP=L2:L3=L2/L4:L6=L5/L7:BOTTOM=L7 |
| EJTAG_TCK_R | OTHERS | BUS | 7 | 5 | 5 | 10 | 5 | 14 | 6 | 10 | 12 | 12 | 12 | 12 |  | 50 Ohms | TOP=L2:L3=L2/L4:L6=L5/L7:BOTTOM=L7 |
| EJTAG_TCK_R | OTHERS | BUS | 8 | 4.75 | 5 | 10 | 5 | 14 | 6 | 9.5 | 12 | 12 | 12 | 12 |  | 50 Ohms | TOP=L2:L3=L2/L4:L6=L5/L7:BOTTOM=L7 |
| EJTAG_TDI | OTHERS | BUS | 1 | 4.75 | 5 | 10 | 5 | 14 | 6 | 9.5 | 12 | 12 | 12 | 12 |  | 50 Ohms | TOP=L2:L3=L2/L4:L6=L5/L7:BOTTOM=L7 |
| EJTAG_TDI | OTHERS | BUS | 2 | 5 | 5 | 10 | 5 | 14 | 6 | 10 | 12 | 12 | 12 | 12 |  | 50 Ohms | TOP=L2:L3=L2/L4:L6=L5/L7:BOTTOM=L7 |
| EJTAG_TDI | OTHERS | BUS | 3 | 5 | 5 | 10 | 5 | 14 | 6 | 10 | 12 | 12 | 12 | 12 |  | 50 Ohms | TOP=L2:L3=L2/L4:L6=L5/L7:BOTTOM=L7 |
| EJTAG_TDI | OTHERS | BUS | 4 | 5 | 5 | 10 | 5 | 14 | 6 | 10 | 12 | 12 | 12 | 12 |  | 50 Ohms | TOP=L2:L3=L2/L4:L6=L5/L7:BOTTOM=L7 |
| EJTAG_TDI | OTHERS | BUS | 5 | 5 | 5 | 10 | 5 | 14 | 6 | 10 | 12 | 12 | 12 | 12 |  | 50 Ohms | TOP=L2:L3=L2/L4:L6=L5/L7:BOTTOM=L7 |
| EJTAG_TDI | OTHERS | BUS | 6 | 5 | 5 | 10 | 5 | 14 | 6 | 10 | 12 | 12 | 12 | 12 |  | 50 Ohms | TOP=L2:L3=L2/L4:L6=L5/L7:BOTTOM=L7 |
| EJTAG_TDI | OTHERS | BUS | 7 | 5 | 5 | 10 | 5 | 14 | 6 | 10 | 12 | 12 | 12 | 12 |  | 50 Ohms | TOP=L2:L3=L2/L4:L6=L5/L7:BOTTOM=L7 |
| EJTAG_TDI | OTHERS | BUS | 8 | 4.75 | 5 | 10 | 5 | 14 | 6 | 9.5 | 12 | 12 | 12 | 12 |  | 50 Ohms | TOP=L2:L3=L2/L4:L6=L5/L7:BOTTOM=L7 |
| EJTAG_TDO | OTHERS | BUS | 1 | 4.75 | 5 | 10 | 5 | 14 | 6 | 9.5 | 12 | 12 | 12 | 12 |  | 50 Ohms | TOP=L2:L3=L2/L4:L6=L5/L7:BOTTOM=L7 |
| EJTAG_TDO | OTHERS | BUS | 2 | 5 | 5 | 10 | 5 | 14 | 6 | 10 | 12 | 12 | 12 | 12 |  | 50 Ohms | TOP=L2:L3=L2/L4:L6=L5/L7:BOTTOM=L7 |
| EJTAG_TDO | OTHERS | BUS | 3 | 5 | 5 | 10 | 5 | 14 | 6 | 10 | 12 | 12 | 12 | 12 |  | 50 Ohms | TOP=L2:L3=L2/L4:L6=L5/L7:BOTTOM=L7 |
| EJTAG_TDO | OTHERS | BUS | 4 | 5 | 5 | 10 | 5 | 14 | 6 | 10 | 12 | 12 | 12 | 12 |  | 50 Ohms | TOP=L2:L3=L2/L4:L6=L5/L7:BOTTOM=L7 |
| EJTAG_TDO | OTHERS | BUS | 5 | 5 | 5 | 10 | 5 | 14 | 6 | 10 | 12 | 12 | 12 | 12 |  | 50 Ohms | TOP=L2:L3=L2/L4:L6=L5/L7:BOTTOM=L7 |
| EJTAG_TDO | OTHERS | BUS | 6 | 5 | 5 | 10 | 5 | 14 | 6 | 10 | 12 | 12 | 12 | 12 |  | 50 Ohms | TOP=L2:L3=L2/L4:L6=L5/L7:BOTTOM=L7 |
| EJTAG_TDO | OTHERS | BUS | 7 | 5 | 5 | 10 | 5 | 14 | 6 | 10 | 12 | 12 | 12 | 12 |  | 50 Ohms | TOP=L2:L3=L2/L4:L6=L5/L7:BOTTOM=L7 |
| EJTAG_TDO | OTHERS | BUS | 8 | 4.75 | 5 | 10 | 5 | 14 | 6 | 9.5 | 12 | 12 | 12 | 12 |  | 50 Ohms | TOP=L2:L3=L2/L4:L6=L5/L7:BOTTOM=L7 |
| EJTAG_TMS | OTHERS | BUS | 1 | 4.75 | 5 | 10 | 5 | 14 | 6 | 9.5 | 12 | 12 | 12 | 12 |  | 50 Ohms | TOP=L2:L3=L2/L4:L6=L5/L7:BOTTOM=L7 |
| EJTAG_TMS | OTHERS | BUS | 2 | 5 | 5 | 10 | 5 | 14 | 6 | 10 | 12 | 12 | 12 | 12 |  | 50 Ohms | TOP=L2:L3=L2/L4:L6=L5/L7:BOTTOM=L7 |
| EJTAG_TMS | OTHERS | BUS | 3 | 5 | 5 | 10 | 5 | 14 | 6 | 10 | 12 | 12 | 12 | 12 |  | 50 Ohms | TOP=L2:L3=L2/L4:L6=L5/L7:BOTTOM=L7 |
| EJTAG_TMS | OTHERS | BUS | 4 | 5 | 5 | 10 | 5 | 14 | 6 | 10 | 12 | 12 | 12 | 12 |  | 50 Ohms | TOP=L2:L3=L2/L4:L6=L5/L7:BOTTOM=L7 |
| EJTAG_TMS | OTHERS | BUS | 5 | 5 | 5 | 10 | 5 | 14 | 6 | 10 | 12 | 12 | 12 | 12 |  | 50 Ohms | TOP=L2:L3=L2/L4:L6=L5/L7:BOTTOM=L7 |
| EJTAG_TMS | OTHERS | BUS | 6 | 5 | 5 | 10 | 5 | 14 | 6 | 10 | 12 | 12 | 12 | 12 |  | 50 Ohms | TOP=L2:L3=L2/L4:L6=L5/L7:BOTTOM=L7 |
| EJTAG_TMS | OTHERS | BUS | 7 | 5 | 5 | 10 | 5 | 14 | 6 | 10 | 12 | 12 | 12 | 12 |  | 50 Ohms | TOP=L2:L3=L2/L4:L6=L5/L7:BOTTOM=L7 |
| EJTAG_TMS | OTHERS | BUS | 8 | 4.75 | 5 | 10 | 5 | 14 | 6 | 9.5 | 12 | 12 | 12 | 12 |  | 50 Ohms | TOP=L2:L3=L2/L4:L6=L5/L7:BOTTOM=L7 |
| EJTAG_TMS_R | OTHERS | BUS | 1 | 4.75 | 5 | 10 | 5 | 14 | 6 | 9.5 | 12 | 12 | 12 | 12 |  | 50 Ohms | TOP=L2:L3=L2/L4:L6=L5/L7:BOTTOM=L7 |
| EJTAG_TMS_R | OTHERS | BUS | 2 | 5 | 5 | 10 | 5 | 14 | 6 | 10 | 12 | 12 | 12 | 12 |  | 50 Ohms | TOP=L2:L3=L2/L4:L6=L5/L7:BOTTOM=L7 |
| EJTAG_TMS_R | OTHERS | BUS | 3 | 5 | 5 | 10 | 5 | 14 | 6 | 10 | 12 | 12 | 12 | 12 |  | 50 Ohms | TOP=L2:L3=L2/L4:L6=L5/L7:BOTTOM=L7 |
| EJTAG_TMS_R | OTHERS | BUS | 4 | 5 | 5 | 10 | 5 | 14 | 6 | 10 | 12 | 12 | 12 | 12 |  | 50 Ohms | TOP=L2:L3=L2/L4:L6=L5/L7:BOTTOM=L7 |
| EJTAG_TMS_R | OTHERS | BUS | 5 | 5 | 5 | 10 | 5 | 14 | 6 | 10 | 12 | 12 | 12 | 12 |  | 50 Ohms | TOP=L2:L3=L2/L4:L6=L5/L7:BOTTOM=L7 |
| EJTAG_TMS_R | OTHERS | BUS | 6 | 5 | 5 | 10 | 5 | 14 | 6 | 10 | 12 | 12 | 12 | 12 |  | 50 Ohms | TOP=L2:L3=L2/L4:L6=L5/L7:BOTTOM=L7 |
| EJTAG_TMS_R | OTHERS | BUS | 7 | 5 | 5 | 10 | 5 | 14 | 6 | 10 | 12 | 12 | 12 | 12 |  | 50 Ohms | TOP=L2:L3=L2/L4:L6=L5/L7:BOTTOM=L7 |
| EJTAG_TMS_R | OTHERS | BUS | 8 | 4.75 | 5 | 10 | 5 | 14 | 6 | 9.5 | 12 | 12 | 12 | 12 |  | 50 Ohms | TOP=L2:L3=L2/L4:L6=L5/L7:BOTTOM=L7 |
| EJTAG_TRSTB | OTHERS | BUS | 1 | 4.75 | 5 | 10 | 5 | 14 | 6 | 9.5 | 12 | 12 | 12 | 12 |  | 50 Ohms | TOP=L2:L3=L2/L4:L6=L5/L7:BOTTOM=L7 |
| EJTAG_TRSTB | OTHERS | BUS | 2 | 5 | 5 | 10 | 5 | 14 | 6 | 10 | 12 | 12 | 12 | 12 |  | 50 Ohms | TOP=L2:L3=L2/L4:L6=L5/L7:BOTTOM=L7 |
| EJTAG_TRSTB | OTHERS | BUS | 3 | 5 | 5 | 10 | 5 | 14 | 6 | 10 | 12 | 12 | 12 | 12 |  | 50 Ohms | TOP=L2:L3=L2/L4:L6=L5/L7:BOTTOM=L7 |
| EJTAG_TRSTB | OTHERS | BUS | 4 | 5 | 5 | 10 | 5 | 14 | 6 | 10 | 12 | 12 | 12 | 12 |  | 50 Ohms | TOP=L2:L3=L2/L4:L6=L5/L7:BOTTOM=L7 |
| EJTAG_TRSTB | OTHERS | BUS | 5 | 5 | 5 | 10 | 5 | 14 | 6 | 10 | 12 | 12 | 12 | 12 |  | 50 Ohms | TOP=L2:L3=L2/L4:L6=L5/L7:BOTTOM=L7 |
| EJTAG_TRSTB | OTHERS | BUS | 6 | 5 | 5 | 10 | 5 | 14 | 6 | 10 | 12 | 12 | 12 | 12 |  | 50 Ohms | TOP=L2:L3=L2/L4:L6=L5/L7:BOTTOM=L7 |
| EJTAG_TRSTB | OTHERS | BUS | 7 | 5 | 5 | 10 | 5 | 14 | 6 | 10 | 12 | 12 | 12 | 12 |  | 50 Ohms | TOP=L2:L3=L2/L4:L6=L5/L7:BOTTOM=L7 |
| EJTAG_TRSTB | OTHERS | BUS | 8 | 4.75 | 5 | 10 | 5 | 14 | 6 | 9.5 | 12 | 12 | 12 | 12 |  | 50 Ohms | TOP=L2:L3=L2/L4:L6=L5/L7:BOTTOM=L7 |
| EJTAG_TRSTB_R | OTHERS | BUS | 1 | 4.75 | 5 | 10 | 5 | 14 | 6 | 9.5 | 12 | 12 | 12 | 12 |  | 50 Ohms | TOP=L2:L3=L2/L4:L6=L5/L7:BOTTOM=L7 |
| EJTAG_TRSTB_R | OTHERS | BUS | 2 | 5 | 5 | 10 | 5 | 14 | 6 | 10 | 12 | 12 | 12 | 12 |  | 50 Ohms | TOP=L2:L3=L2/L4:L6=L5/L7:BOTTOM=L7 |
| EJTAG_TRSTB_R | OTHERS | BUS | 3 | 5 | 5 | 10 | 5 | 14 | 6 | 10 | 12 | 12 | 12 | 12 |  | 50 Ohms | TOP=L2:L3=L2/L4:L6=L5/L7:BOTTOM=L7 |
| EJTAG_TRSTB_R | OTHERS | BUS | 4 | 5 | 5 | 10 | 5 | 14 | 6 | 10 | 12 | 12 | 12 | 12 |  | 50 Ohms | TOP=L2:L3=L2/L4:L6=L5/L7:BOTTOM=L7 |
| EJTAG_TRSTB_R | OTHERS | BUS | 5 | 5 | 5 | 10 | 5 | 14 | 6 | 10 | 12 | 12 | 12 | 12 |  | 50 Ohms | TOP=L2:L3=L2/L4:L6=L5/L7:BOTTOM=L7 |
| EJTAG_TRSTB_R | OTHERS | BUS | 6 | 5 | 5 | 10 | 5 | 14 | 6 | 10 | 12 | 12 | 12 | 12 |  | 50 Ohms | TOP=L2:L3=L2/L4:L6=L5/L7:BOTTOM=L7 |
| EJTAG_TRSTB_R | OTHERS | BUS | 7 | 5 | 5 | 10 | 5 | 14 | 6 | 10 | 12 | 12 | 12 | 12 |  | 50 Ohms | TOP=L2:L3=L2/L4:L6=L5/L7:BOTTOM=L7 |
| EJTAG_TRSTB_R | OTHERS | BUS | 8 | 4.75 | 5 | 10 | 5 | 14 | 6 | 9.5 | 12 | 12 | 12 | 12 |  | 50 Ohms | TOP=L2:L3=L2/L4:L6=L5/L7:BOTTOM=L7 |
| ENCLO_LED_BLUE_OUT | OTHERS | BUS | 1 | 4.75 | 5 | 10 | 5 | 14 | 6 | 9.5 | 12 | 12 | 12 | 12 |  | 50 Ohms | TOP=L2:L3=L2/L4:L6=L5/L7:BOTTOM=L7 |
| ENCLO_LED_BLUE_OUT | OTHERS | BUS | 2 | 5 | 5 | 10 | 5 | 14 | 6 | 10 | 12 | 12 | 12 | 12 |  | 50 Ohms | TOP=L2:L3=L2/L4:L6=L5/L7:BOTTOM=L7 |
| ENCLO_LED_BLUE_OUT | OTHERS | BUS | 3 | 5 | 5 | 10 | 5 | 14 | 6 | 10 | 12 | 12 | 12 | 12 |  | 50 Ohms | TOP=L2:L3=L2/L4:L6=L5/L7:BOTTOM=L7 |
| ENCLO_LED_BLUE_OUT | OTHERS | BUS | 4 | 5 | 5 | 10 | 5 | 14 | 6 | 10 | 12 | 12 | 12 | 12 |  | 50 Ohms | TOP=L2:L3=L2/L4:L6=L5/L7:BOTTOM=L7 |
| ENCLO_LED_BLUE_OUT | OTHERS | BUS | 5 | 5 | 5 | 10 | 5 | 14 | 6 | 10 | 12 | 12 | 12 | 12 |  | 50 Ohms | TOP=L2:L3=L2/L4:L6=L5/L7:BOTTOM=L7 |
| ENCLO_LED_BLUE_OUT | OTHERS | BUS | 6 | 5 | 5 | 10 | 5 | 14 | 6 | 10 | 12 | 12 | 12 | 12 |  | 50 Ohms | TOP=L2:L3=L2/L4:L6=L5/L7:BOTTOM=L7 |
| ENCLO_LED_BLUE_OUT | OTHERS | BUS | 7 | 5 | 5 | 10 | 5 | 14 | 6 | 10 | 12 | 12 | 12 | 12 |  | 50 Ohms | TOP=L2:L3=L2/L4:L6=L5/L7:BOTTOM=L7 |
| ENCLO_LED_BLUE_OUT | OTHERS | BUS | 8 | 4.75 | 5 | 10 | 5 | 14 | 6 | 9.5 | 12 | 12 | 12 | 12 |  | 50 Ohms | TOP=L2:L3=L2/L4:L6=L5/L7:BOTTOM=L7 |
| ENCLO_LED_RED | OTHERS | BUS | 1 | 4.75 | 5 | 10 | 5 | 14 | 6 | 9.5 | 12 | 12 | 12 | 12 |  | 50 Ohms | TOP=L2:L3=L2/L4:L6=L5/L7:BOTTOM=L7 |
| ENCLO_LED_RED | OTHERS | BUS | 2 | 5 | 5 | 10 | 5 | 14 | 6 | 10 | 12 | 12 | 12 | 12 |  | 50 Ohms | TOP=L2:L3=L2/L4:L6=L5/L7:BOTTOM=L7 |
| ENCLO_LED_RED | OTHERS | BUS | 3 | 5 | 5 | 10 | 5 | 14 | 6 | 10 | 12 | 12 | 12 | 12 |  | 50 Ohms | TOP=L2:L3=L2/L4:L6=L5/L7:BOTTOM=L7 |
| ENCLO_LED_RED | OTHERS | BUS | 4 | 5 | 5 | 10 | 5 | 14 | 6 | 10 | 12 | 12 | 12 | 12 |  | 50 Ohms | TOP=L2:L3=L2/L4:L6=L5/L7:BOTTOM=L7 |
| ENCLO_LED_RED | OTHERS | BUS | 5 | 5 | 5 | 10 | 5 | 14 | 6 | 10 | 12 | 12 | 12 | 12 |  | 50 Ohms | TOP=L2:L3=L2/L4:L6=L5/L7:BOTTOM=L7 |
| ENCLO_LED_RED | OTHERS | BUS | 6 | 5 | 5 | 10 | 5 | 14 | 6 | 10 | 12 | 12 | 12 | 12 |  | 50 Ohms | TOP=L2:L3=L2/L4:L6=L5/L7:BOTTOM=L7 |
| ENCLO_LED_RED | OTHERS | BUS | 7 | 5 | 5 | 10 | 5 | 14 | 6 | 10 | 12 | 12 | 12 | 12 |  | 50 Ohms | TOP=L2:L3=L2/L4:L6=L5/L7:BOTTOM=L7 |
| ENCLO_LED_RED | OTHERS | BUS | 8 | 4.75 | 5 | 10 | 5 | 14 | 6 | 9.5 | 12 | 12 | 12 | 12 |  | 50 Ohms | TOP=L2:L3=L2/L4:L6=L5/L7:BOTTOM=L7 |
| ENCLO_LED_RED_D | OTHERS | BUS | 1 | 4.75 | 5 | 10 | 5 | 14 | 6 | 9.5 | 12 | 12 | 12 | 12 |  | 50 Ohms | TOP=L2:L3=L2/L4:L6=L5/L7:BOTTOM=L7 |
| ENCLO_LED_RED_D | OTHERS | BUS | 2 | 5 | 5 | 10 | 5 | 14 | 6 | 10 | 12 | 12 | 12 | 12 |  | 50 Ohms | TOP=L2:L3=L2/L4:L6=L5/L7:BOTTOM=L7 |
| ENCLO_LED_RED_D | OTHERS | BUS | 3 | 5 | 5 | 10 | 5 | 14 | 6 | 10 | 12 | 12 | 12 | 12 |  | 50 Ohms | TOP=L2:L3=L2/L4:L6=L5/L7:BOTTOM=L7 |
| ENCLO_LED_RED_D | OTHERS | BUS | 4 | 5 | 5 | 10 | 5 | 14 | 6 | 10 | 12 | 12 | 12 | 12 |  | 50 Ohms | TOP=L2:L3=L2/L4:L6=L5/L7:BOTTOM=L7 |
| ENCLO_LED_RED_D | OTHERS | BUS | 5 | 5 | 5 | 10 | 5 | 14 | 6 | 10 | 12 | 12 | 12 | 12 |  | 50 Ohms | TOP=L2:L3=L2/L4:L6=L5/L7:BOTTOM=L7 |
| ENCLO_LED_RED_D | OTHERS | BUS | 6 | 5 | 5 | 10 | 5 | 14 | 6 | 10 | 12 | 12 | 12 | 12 |  | 50 Ohms | TOP=L2:L3=L2/L4:L6=L5/L7:BOTTOM=L7 |
| ENCLO_LED_RED_D | OTHERS | BUS | 7 | 5 | 5 | 10 | 5 | 14 | 6 | 10 | 12 | 12 | 12 | 12 |  | 50 Ohms | TOP=L2:L3=L2/L4:L6=L5/L7:BOTTOM=L7 |
| ENCLO_LED_RED_D | OTHERS | BUS | 8 | 4.75 | 5 | 10 | 5 | 14 | 6 | 9.5 | 12 | 12 | 12 | 12 |  | 50 Ohms | TOP=L2:L3=L2/L4:L6=L5/L7:BOTTOM=L7 |
| ENCLO_LED_RED_G | OTHERS | BUS | 1 | 4.75 | 5 | 10 | 5 | 14 | 6 | 9.5 | 12 | 12 | 12 | 12 |  | 50 Ohms | TOP=L2:L3=L2/L4:L6=L5/L7:BOTTOM=L7 |
| ENCLO_LED_RED_G | OTHERS | BUS | 2 | 5 | 5 | 10 | 5 | 14 | 6 | 10 | 12 | 12 | 12 | 12 |  | 50 Ohms | TOP=L2:L3=L2/L4:L6=L5/L7:BOTTOM=L7 |
| ENCLO_LED_RED_G | OTHERS | BUS | 3 | 5 | 5 | 10 | 5 | 14 | 6 | 10 | 12 | 12 | 12 | 12 |  | 50 Ohms | TOP=L2:L3=L2/L4:L6=L5/L7:BOTTOM=L7 |
| ENCLO_LED_RED_G | OTHERS | BUS | 4 | 5 | 5 | 10 | 5 | 14 | 6 | 10 | 12 | 12 | 12 | 12 |  | 50 Ohms | TOP=L2:L3=L2/L4:L6=L5/L7:BOTTOM=L7 |
| ENCLO_LED_RED_G | OTHERS | BUS | 5 | 5 | 5 | 10 | 5 | 14 | 6 | 10 | 12 | 12 | 12 | 12 |  | 50 Ohms | TOP=L2:L3=L2/L4:L6=L5/L7:BOTTOM=L7 |
| ENCLO_LED_RED_G | OTHERS | BUS | 6 | 5 | 5 | 10 | 5 | 14 | 6 | 10 | 12 | 12 | 12 | 12 |  | 50 Ohms | TOP=L2:L3=L2/L4:L6=L5/L7:BOTTOM=L7 |
| ENCLO_LED_RED_G | OTHERS | BUS | 7 | 5 | 5 | 10 | 5 | 14 | 6 | 10 | 12 | 12 | 12 | 12 |  | 50 Ohms | TOP=L2:L3=L2/L4:L6=L5/L7:BOTTOM=L7 |
| ENCLO_LED_RED_G | OTHERS | BUS | 8 | 4.75 | 5 | 10 | 5 | 14 | 6 | 9.5 | 12 | 12 | 12 | 12 |  | 50 Ohms | TOP=L2:L3=L2/L4:L6=L5/L7:BOTTOM=L7 |
| ENCLO_LED_RED_R | OTHERS | BUS | 1 | 4.75 | 5 | 10 | 5 | 14 | 6 | 9.5 | 12 | 12 | 12 | 12 |  | 50 Ohms | TOP=L2:L3=L2/L4:L6=L5/L7:BOTTOM=L7 |
| ENCLO_LED_RED_R | OTHERS | BUS | 2 | 5 | 5 | 10 | 5 | 14 | 6 | 10 | 12 | 12 | 12 | 12 |  | 50 Ohms | TOP=L2:L3=L2/L4:L6=L5/L7:BOTTOM=L7 |
| ENCLO_LED_RED_R | OTHERS | BUS | 3 | 5 | 5 | 10 | 5 | 14 | 6 | 10 | 12 | 12 | 12 | 12 |  | 50 Ohms | TOP=L2:L3=L2/L4:L6=L5/L7:BOTTOM=L7 |
| ENCLO_LED_RED_R | OTHERS | BUS | 4 | 5 | 5 | 10 | 5 | 14 | 6 | 10 | 12 | 12 | 12 | 12 |  | 50 Ohms | TOP=L2:L3=L2/L4:L6=L5/L7:BOTTOM=L7 |
| ENCLO_LED_RED_R | OTHERS | BUS | 5 | 5 | 5 | 10 | 5 | 14 | 6 | 10 | 12 | 12 | 12 | 12 |  | 50 Ohms | TOP=L2:L3=L2/L4:L6=L5/L7:BOTTOM=L7 |
| ENCLO_LED_RED_R | OTHERS | BUS | 6 | 5 | 5 | 10 | 5 | 14 | 6 | 10 | 12 | 12 | 12 | 12 |  | 50 Ohms | TOP=L2:L3=L2/L4:L6=L5/L7:BOTTOM=L7 |
| ENCLO_LED_RED_R | OTHERS | BUS | 7 | 5 | 5 | 10 | 5 | 14 | 6 | 10 | 12 | 12 | 12 | 12 |  | 50 Ohms | TOP=L2:L3=L2/L4:L6=L5/L7:BOTTOM=L7 |
| ENCLO_LED_RED_R | OTHERS | BUS | 8 | 4.75 | 5 | 10 | 5 | 14 | 6 | 9.5 | 12 | 12 | 12 | 12 |  | 50 Ohms | TOP=L2:L3=L2/L4:L6=L5/L7:BOTTOM=L7 |
| EXP_BMC_HB_LED_D | OTHERS | BUS | 1 | 4.75 | 5 | 10 | 5 | 14 | 6 | 9.5 | 12 | 12 | 12 | 12 |  | 50 Ohms | TOP=L2:L3=L2/L4:L6=L5/L7:BOTTOM=L7 |
| EXP_BMC_HB_LED_D | OTHERS | BUS | 2 | 5 | 5 | 10 | 5 | 14 | 6 | 10 | 12 | 12 | 12 | 12 |  | 50 Ohms | TOP=L2:L3=L2/L4:L6=L5/L7:BOTTOM=L7 |
| EXP_BMC_HB_LED_D | OTHERS | BUS | 3 | 5 | 5 | 10 | 5 | 14 | 6 | 10 | 12 | 12 | 12 | 12 |  | 50 Ohms | TOP=L2:L3=L2/L4:L6=L5/L7:BOTTOM=L7 |
| EXP_BMC_HB_LED_D | OTHERS | BUS | 4 | 5 | 5 | 10 | 5 | 14 | 6 | 10 | 12 | 12 | 12 | 12 |  | 50 Ohms | TOP=L2:L3=L2/L4:L6=L5/L7:BOTTOM=L7 |
| EXP_BMC_HB_LED_D | OTHERS | BUS | 5 | 5 | 5 | 10 | 5 | 14 | 6 | 10 | 12 | 12 | 12 | 12 |  | 50 Ohms | TOP=L2:L3=L2/L4:L6=L5/L7:BOTTOM=L7 |
| EXP_BMC_HB_LED_D | OTHERS | BUS | 6 | 5 | 5 | 10 | 5 | 14 | 6 | 10 | 12 | 12 | 12 | 12 |  | 50 Ohms | TOP=L2:L3=L2/L4:L6=L5/L7:BOTTOM=L7 |
| EXP_BMC_HB_LED_D | OTHERS | BUS | 7 | 5 | 5 | 10 | 5 | 14 | 6 | 10 | 12 | 12 | 12 | 12 |  | 50 Ohms | TOP=L2:L3=L2/L4:L6=L5/L7:BOTTOM=L7 |
| EXP_BMC_HB_LED_D | OTHERS | BUS | 8 | 4.75 | 5 | 10 | 5 | 14 | 6 | 9.5 | 12 | 12 | 12 | 12 |  | 50 Ohms | TOP=L2:L3=L2/L4:L6=L5/L7:BOTTOM=L7 |
| EXP_BMC_HB_LED_R | OTHERS | BUS | 1 | 4.75 | 5 | 10 | 5 | 14 | 6 | 9.5 | 12 | 12 | 12 | 12 |  | 50 Ohms | TOP=L2:L3=L2/L4:L6=L5/L7:BOTTOM=L7 |
| EXP_BMC_HB_LED_R | OTHERS | BUS | 2 | 5 | 5 | 10 | 5 | 14 | 6 | 10 | 12 | 12 | 12 | 12 |  | 50 Ohms | TOP=L2:L3=L2/L4:L6=L5/L7:BOTTOM=L7 |
| EXP_BMC_HB_LED_R | OTHERS | BUS | 3 | 5 | 5 | 10 | 5 | 14 | 6 | 10 | 12 | 12 | 12 | 12 |  | 50 Ohms | TOP=L2:L3=L2/L4:L6=L5/L7:BOTTOM=L7 |
| EXP_BMC_HB_LED_R | OTHERS | BUS | 4 | 5 | 5 | 10 | 5 | 14 | 6 | 10 | 12 | 12 | 12 | 12 |  | 50 Ohms | TOP=L2:L3=L2/L4:L6=L5/L7:BOTTOM=L7 |
| EXP_BMC_HB_LED_R | OTHERS | BUS | 5 | 5 | 5 | 10 | 5 | 14 | 6 | 10 | 12 | 12 | 12 | 12 |  | 50 Ohms | TOP=L2:L3=L2/L4:L6=L5/L7:BOTTOM=L7 |
| EXP_BMC_HB_LED_R | OTHERS | BUS | 6 | 5 | 5 | 10 | 5 | 14 | 6 | 10 | 12 | 12 | 12 | 12 |  | 50 Ohms | TOP=L2:L3=L2/L4:L6=L5/L7:BOTTOM=L7 |
| EXP_BMC_HB_LED_R | OTHERS | BUS | 7 | 5 | 5 | 10 | 5 | 14 | 6 | 10 | 12 | 12 | 12 | 12 |  | 50 Ohms | TOP=L2:L3=L2/L4:L6=L5/L7:BOTTOM=L7 |
| EXP_BMC_HB_LED_R | OTHERS | BUS | 8 | 4.75 | 5 | 10 | 5 | 14 | 6 | 9.5 | 12 | 12 | 12 | 12 |  | 50 Ohms | TOP=L2:L3=L2/L4:L6=L5/L7:BOTTOM=L7 |
| EXP_TRAY_ID | OTHERS | BUS | 1 | 4.75 | 5 | 10 | 5 | 14 | 6 | 9.5 | 12 | 12 | 12 | 12 |  | 50 Ohms | TOP=L2:L3=L2/L4:L6=L5/L7:BOTTOM=L7 |
| EXP_TRAY_ID | OTHERS | BUS | 2 | 5 | 5 | 10 | 5 | 14 | 6 | 10 | 12 | 12 | 12 | 12 |  | 50 Ohms | TOP=L2:L3=L2/L4:L6=L5/L7:BOTTOM=L7 |
| EXP_TRAY_ID | OTHERS | BUS | 3 | 5 | 5 | 10 | 5 | 14 | 6 | 10 | 12 | 12 | 12 | 12 |  | 50 Ohms | TOP=L2:L3=L2/L4:L6=L5/L7:BOTTOM=L7 |
| EXP_TRAY_ID | OTHERS | BUS | 4 | 5 | 5 | 10 | 5 | 14 | 6 | 10 | 12 | 12 | 12 | 12 |  | 50 Ohms | TOP=L2:L3=L2/L4:L6=L5/L7:BOTTOM=L7 |
| EXP_TRAY_ID | OTHERS | BUS | 5 | 5 | 5 | 10 | 5 | 14 | 6 | 10 | 12 | 12 | 12 | 12 |  | 50 Ohms | TOP=L2:L3=L2/L4:L6=L5/L7:BOTTOM=L7 |
| EXP_TRAY_ID | OTHERS | BUS | 6 | 5 | 5 | 10 | 5 | 14 | 6 | 10 | 12 | 12 | 12 | 12 |  | 50 Ohms | TOP=L2:L3=L2/L4:L6=L5/L7:BOTTOM=L7 |
| EXP_TRAY_ID | OTHERS | BUS | 7 | 5 | 5 | 10 | 5 | 14 | 6 | 10 | 12 | 12 | 12 | 12 |  | 50 Ohms | TOP=L2:L3=L2/L4:L6=L5/L7:BOTTOM=L7 |
| EXP_TRAY_ID | OTHERS | BUS | 8 | 4.75 | 5 | 10 | 5 | 14 | 6 | 9.5 | 12 | 12 | 12 | 12 |  | 50 Ohms | TOP=L2:L3=L2/L4:L6=L5/L7:BOTTOM=L7 |
| EXP_TRAY_ID_BMC | OTHERS | BUS | 1 | 4.75 | 5 | 10 | 5 | 14 | 6 | 9.5 | 12 | 12 | 12 | 12 |  | 50 Ohms | TOP=L2:L3=L2/L4:L6=L5/L7:BOTTOM=L7 |
| EXP_TRAY_ID_BMC | OTHERS | BUS | 2 | 5 | 5 | 10 | 5 | 14 | 6 | 10 | 12 | 12 | 12 | 12 |  | 50 Ohms | TOP=L2:L3=L2/L4:L6=L5/L7:BOTTOM=L7 |
| EXP_TRAY_ID_BMC | OTHERS | BUS | 3 | 5 | 5 | 10 | 5 | 14 | 6 | 10 | 12 | 12 | 12 | 12 |  | 50 Ohms | TOP=L2:L3=L2/L4:L6=L5/L7:BOTTOM=L7 |
| EXP_TRAY_ID_BMC | OTHERS | BUS | 4 | 5 | 5 | 10 | 5 | 14 | 6 | 10 | 12 | 12 | 12 | 12 |  | 50 Ohms | TOP=L2:L3=L2/L4:L6=L5/L7:BOTTOM=L7 |
| EXP_TRAY_ID_BMC | OTHERS | BUS | 5 | 5 | 5 | 10 | 5 | 14 | 6 | 10 | 12 | 12 | 12 | 12 |  | 50 Ohms | TOP=L2:L3=L2/L4:L6=L5/L7:BOTTOM=L7 |
| EXP_TRAY_ID_BMC | OTHERS | BUS | 6 | 5 | 5 | 10 | 5 | 14 | 6 | 10 | 12 | 12 | 12 | 12 |  | 50 Ohms | TOP=L2:L3=L2/L4:L6=L5/L7:BOTTOM=L7 |
| EXP_TRAY_ID_BMC | OTHERS | BUS | 7 | 5 | 5 | 10 | 5 | 14 | 6 | 10 | 12 | 12 | 12 | 12 |  | 50 Ohms | TOP=L2:L3=L2/L4:L6=L5/L7:BOTTOM=L7 |
| EXP_TRAY_ID_BMC | OTHERS | BUS | 8 | 4.75 | 5 | 10 | 5 | 14 | 6 | 9.5 | 12 | 12 | 12 | 12 |  | 50 Ohms | TOP=L2:L3=L2/L4:L6=L5/L7:BOTTOM=L7 |
| FAN_PWM_PCIE_BMC | OTHERS | BUS | 1 | 4.75 | 5 | 10 | 5 | 14 | 6 | 9.5 | 12 | 12 | 12 | 12 |  | 50 Ohms | TOP=L2:L3=L2/L4:L6=L5/L7:BOTTOM=L7 |
| FAN_PWM_PCIE_BMC | OTHERS | BUS | 2 | 5 | 5 | 10 | 5 | 14 | 6 | 10 | 12 | 12 | 12 | 12 |  | 50 Ohms | TOP=L2:L3=L2/L4:L6=L5/L7:BOTTOM=L7 |
| FAN_PWM_PCIE_BMC | OTHERS | BUS | 3 | 5 | 5 | 10 | 5 | 14 | 6 | 10 | 12 | 12 | 12 | 12 |  | 50 Ohms | TOP=L2:L3=L2/L4:L6=L5/L7:BOTTOM=L7 |
| FAN_PWM_PCIE_BMC | OTHERS | BUS | 4 | 5 | 5 | 10 | 5 | 14 | 6 | 10 | 12 | 12 | 12 | 12 |  | 50 Ohms | TOP=L2:L3=L2/L4:L6=L5/L7:BOTTOM=L7 |
| FAN_PWM_PCIE_BMC | OTHERS | BUS | 5 | 5 | 5 | 10 | 5 | 14 | 6 | 10 | 12 | 12 | 12 | 12 |  | 50 Ohms | TOP=L2:L3=L2/L4:L6=L5/L7:BOTTOM=L7 |
| FAN_PWM_PCIE_BMC | OTHERS | BUS | 6 | 5 | 5 | 10 | 5 | 14 | 6 | 10 | 12 | 12 | 12 | 12 |  | 50 Ohms | TOP=L2:L3=L2/L4:L6=L5/L7:BOTTOM=L7 |
| FAN_PWM_PCIE_BMC | OTHERS | BUS | 7 | 5 | 5 | 10 | 5 | 14 | 6 | 10 | 12 | 12 | 12 | 12 |  | 50 Ohms | TOP=L2:L3=L2/L4:L6=L5/L7:BOTTOM=L7 |
| FAN_PWM_PCIE_BMC | OTHERS | BUS | 8 | 4.75 | 5 | 10 | 5 | 14 | 6 | 9.5 | 12 | 12 | 12 | 12 |  | 50 Ohms | TOP=L2:L3=L2/L4:L6=L5/L7:BOTTOM=L7 |
| FCB_HW_REVISION | OTHERS | BUS | 1 | 4.75 | 5 | 10 | 5 | 14 | 6 | 9.5 | 12 | 12 | 12 | 12 |  | 50 Ohms | TOP=L2:L3=L2/L4:L6=L5/L7:BOTTOM=L7 |
| FCB_HW_REVISION | OTHERS | BUS | 2 | 5 | 5 | 10 | 5 | 14 | 6 | 10 | 12 | 12 | 12 | 12 |  | 50 Ohms | TOP=L2:L3=L2/L4:L6=L5/L7:BOTTOM=L7 |
| FCB_HW_REVISION | OTHERS | BUS | 3 | 5 | 5 | 10 | 5 | 14 | 6 | 10 | 12 | 12 | 12 | 12 |  | 50 Ohms | TOP=L2:L3=L2/L4:L6=L5/L7:BOTTOM=L7 |
| FCB_HW_REVISION | OTHERS | BUS | 4 | 5 | 5 | 10 | 5 | 14 | 6 | 10 | 12 | 12 | 12 | 12 |  | 50 Ohms | TOP=L2:L3=L2/L4:L6=L5/L7:BOTTOM=L7 |
| FCB_HW_REVISION | OTHERS | BUS | 5 | 5 | 5 | 10 | 5 | 14 | 6 | 10 | 12 | 12 | 12 | 12 |  | 50 Ohms | TOP=L2:L3=L2/L4:L6=L5/L7:BOTTOM=L7 |
| FCB_HW_REVISION | OTHERS | BUS | 6 | 5 | 5 | 10 | 5 | 14 | 6 | 10 | 12 | 12 | 12 | 12 |  | 50 Ohms | TOP=L2:L3=L2/L4:L6=L5/L7:BOTTOM=L7 |
| FCB_HW_REVISION | OTHERS | BUS | 7 | 5 | 5 | 10 | 5 | 14 | 6 | 10 | 12 | 12 | 12 | 12 |  | 50 Ohms | TOP=L2:L3=L2/L4:L6=L5/L7:BOTTOM=L7 |
| FCB_HW_REVISION | OTHERS | BUS | 8 | 4.75 | 5 | 10 | 5 | 14 | 6 | 9.5 | 12 | 12 | 12 | 12 |  | 50 Ohms | TOP=L2:L3=L2/L4:L6=L5/L7:BOTTOM=L7 |
| FLA_CS | OTHERS | BUS | 1 | 4.75 | 5 | 10 | 5 | 14 | 6 | 9.5 | 12 | 12 | 12 | 12 |  | 50 Ohms | TOP=L2:L3=L2/L4:L6=L5/L7:BOTTOM=L7 |
| FLA_CS | OTHERS | BUS | 2 | 5 | 5 | 10 | 5 | 14 | 6 | 10 | 12 | 12 | 12 | 12 |  | 50 Ohms | TOP=L2:L3=L2/L4:L6=L5/L7:BOTTOM=L7 |
| FLA_CS | OTHERS | BUS | 3 | 5 | 5 | 10 | 5 | 14 | 6 | 10 | 12 | 12 | 12 | 12 |  | 50 Ohms | TOP=L2:L3=L2/L4:L6=L5/L7:BOTTOM=L7 |
| FLA_CS | OTHERS | BUS | 4 | 5 | 5 | 10 | 5 | 14 | 6 | 10 | 12 | 12 | 12 | 12 |  | 50 Ohms | TOP=L2:L3=L2/L4:L6=L5/L7:BOTTOM=L7 |
| FLA_CS | OTHERS | BUS | 5 | 5 | 5 | 10 | 5 | 14 | 6 | 10 | 12 | 12 | 12 | 12 |  | 50 Ohms | TOP=L2:L3=L2/L4:L6=L5/L7:BOTTOM=L7 |
| FLA_CS | OTHERS | BUS | 6 | 5 | 5 | 10 | 5 | 14 | 6 | 10 | 12 | 12 | 12 | 12 |  | 50 Ohms | TOP=L2:L3=L2/L4:L6=L5/L7:BOTTOM=L7 |
| FLA_CS | OTHERS | BUS | 7 | 5 | 5 | 10 | 5 | 14 | 6 | 10 | 12 | 12 | 12 | 12 |  | 50 Ohms | TOP=L2:L3=L2/L4:L6=L5/L7:BOTTOM=L7 |
| FLA_CS | OTHERS | BUS | 8 | 4.75 | 5 | 10 | 5 | 14 | 6 | 9.5 | 12 | 12 | 12 | 12 |  | 50 Ohms | TOP=L2:L3=L2/L4:L6=L5/L7:BOTTOM=L7 |
| FLA_CS_R | OTHERS | BUS | 1 | 4.75 | 5 | 10 | 5 | 14 | 6 | 9.5 | 12 | 12 | 12 | 12 |  | 50 Ohms | TOP=L2:L3=L2/L4:L6=L5/L7:BOTTOM=L7 |
| FLA_CS_R | OTHERS | BUS | 2 | 5 | 5 | 10 | 5 | 14 | 6 | 10 | 12 | 12 | 12 | 12 |  | 50 Ohms | TOP=L2:L3=L2/L4:L6=L5/L7:BOTTOM=L7 |
| FLA_CS_R | OTHERS | BUS | 3 | 5 | 5 | 10 | 5 | 14 | 6 | 10 | 12 | 12 | 12 | 12 |  | 50 Ohms | TOP=L2:L3=L2/L4:L6=L5/L7:BOTTOM=L7 |
| FLA_CS_R | OTHERS | BUS | 4 | 5 | 5 | 10 | 5 | 14 | 6 | 10 | 12 | 12 | 12 | 12 |  | 50 Ohms | TOP=L2:L3=L2/L4:L6=L5/L7:BOTTOM=L7 |
| FLA_CS_R | OTHERS | BUS | 5 | 5 | 5 | 10 | 5 | 14 | 6 | 10 | 12 | 12 | 12 | 12 |  | 50 Ohms | TOP=L2:L3=L2/L4:L6=L5/L7:BOTTOM=L7 |
| FLA_CS_R | OTHERS | BUS | 6 | 5 | 5 | 10 | 5 | 14 | 6 | 10 | 12 | 12 | 12 | 12 |  | 50 Ohms | TOP=L2:L3=L2/L4:L6=L5/L7:BOTTOM=L7 |
| FLA_CS_R | OTHERS | BUS | 7 | 5 | 5 | 10 | 5 | 14 | 6 | 10 | 12 | 12 | 12 | 12 |  | 50 Ohms | TOP=L2:L3=L2/L4:L6=L5/L7:BOTTOM=L7 |
| FLA_CS_R | OTHERS | BUS | 8 | 4.75 | 5 | 10 | 5 | 14 | 6 | 9.5 | 12 | 12 | 12 | 12 |  | 50 Ohms | TOP=L2:L3=L2/L4:L6=L5/L7:BOTTOM=L7 |
| FLA_CS1 | OTHERS | BUS | 1 | 4.75 | 5 | 10 | 5 | 14 | 6 | 9.5 | 12 | 12 | 12 | 12 |  | 50 Ohms | TOP=L2:L3=L2/L4:L6=L5/L7:BOTTOM=L7 |
| FLA_CS1 | OTHERS | BUS | 2 | 5 | 5 | 10 | 5 | 14 | 6 | 10 | 12 | 12 | 12 | 12 |  | 50 Ohms | TOP=L2:L3=L2/L4:L6=L5/L7:BOTTOM=L7 |
| FLA_CS1 | OTHERS | BUS | 3 | 5 | 5 | 10 | 5 | 14 | 6 | 10 | 12 | 12 | 12 | 12 |  | 50 Ohms | TOP=L2:L3=L2/L4:L6=L5/L7:BOTTOM=L7 |
| FLA_CS1 | OTHERS | BUS | 4 | 5 | 5 | 10 | 5 | 14 | 6 | 10 | 12 | 12 | 12 | 12 |  | 50 Ohms | TOP=L2:L3=L2/L4:L6=L5/L7:BOTTOM=L7 |
| FLA_CS1 | OTHERS | BUS | 5 | 5 | 5 | 10 | 5 | 14 | 6 | 10 | 12 | 12 | 12 | 12 |  | 50 Ohms | TOP=L2:L3=L2/L4:L6=L5/L7:BOTTOM=L7 |
| FLA_CS1 | OTHERS | BUS | 6 | 5 | 5 | 10 | 5 | 14 | 6 | 10 | 12 | 12 | 12 | 12 |  | 50 Ohms | TOP=L2:L3=L2/L4:L6=L5/L7:BOTTOM=L7 |
| FLA_CS1 | OTHERS | BUS | 7 | 5 | 5 | 10 | 5 | 14 | 6 | 10 | 12 | 12 | 12 | 12 |  | 50 Ohms | TOP=L2:L3=L2/L4:L6=L5/L7:BOTTOM=L7 |
| FLA_CS1 | OTHERS | BUS | 8 | 4.75 | 5 | 10 | 5 | 14 | 6 | 9.5 | 12 | 12 | 12 | 12 |  | 50 Ohms | TOP=L2:L3=L2/L4:L6=L5/L7:BOTTOM=L7 |
| FLA_CS1_R | OTHERS | BUS | 1 | 4.75 | 5 | 10 | 5 | 14 | 6 | 9.5 | 12 | 12 | 12 | 12 |  | 50 Ohms | TOP=L2:L3=L2/L4:L6=L5/L7:BOTTOM=L7 |
| FLA_CS1_R | OTHERS | BUS | 2 | 5 | 5 | 10 | 5 | 14 | 6 | 10 | 12 | 12 | 12 | 12 |  | 50 Ohms | TOP=L2:L3=L2/L4:L6=L5/L7:BOTTOM=L7 |
| FLA_CS1_R | OTHERS | BUS | 3 | 5 | 5 | 10 | 5 | 14 | 6 | 10 | 12 | 12 | 12 | 12 |  | 50 Ohms | TOP=L2:L3=L2/L4:L6=L5/L7:BOTTOM=L7 |
| FLA_CS1_R | OTHERS | BUS | 4 | 5 | 5 | 10 | 5 | 14 | 6 | 10 | 12 | 12 | 12 | 12 |  | 50 Ohms | TOP=L2:L3=L2/L4:L6=L5/L7:BOTTOM=L7 |
| FLA_CS1_R | OTHERS | BUS | 5 | 5 | 5 | 10 | 5 | 14 | 6 | 10 | 12 | 12 | 12 | 12 |  | 50 Ohms | TOP=L2:L3=L2/L4:L6=L5/L7:BOTTOM=L7 |
| FLA_CS1_R | OTHERS | BUS | 6 | 5 | 5 | 10 | 5 | 14 | 6 | 10 | 12 | 12 | 12 | 12 |  | 50 Ohms | TOP=L2:L3=L2/L4:L6=L5/L7:BOTTOM=L7 |
| FLA_CS1_R | OTHERS | BUS | 7 | 5 | 5 | 10 | 5 | 14 | 6 | 10 | 12 | 12 | 12 | 12 |  | 50 Ohms | TOP=L2:L3=L2/L4:L6=L5/L7:BOTTOM=L7 |
| FLA_CS1_R | OTHERS | BUS | 8 | 4.75 | 5 | 10 | 5 | 14 | 6 | 9.5 | 12 | 12 | 12 | 12 |  | 50 Ohms | TOP=L2:L3=L2/L4:L6=L5/L7:BOTTOM=L7 |
| FLA_WPN | OTHERS | BUS | 1 | 4.75 | 5 | 10 | 5 | 14 | 6 | 9.5 | 12 | 12 | 12 | 12 |  | 50 Ohms | TOP=L2:L3=L2/L4:L6=L5/L7:BOTTOM=L7 |
| FLA_WPN | OTHERS | BUS | 2 | 5 | 5 | 10 | 5 | 14 | 6 | 10 | 12 | 12 | 12 | 12 |  | 50 Ohms | TOP=L2:L3=L2/L4:L6=L5/L7:BOTTOM=L7 |
| FLA_WPN | OTHERS | BUS | 3 | 5 | 5 | 10 | 5 | 14 | 6 | 10 | 12 | 12 | 12 | 12 |  | 50 Ohms | TOP=L2:L3=L2/L4:L6=L5/L7:BOTTOM=L7 |
| FLA_WPN | OTHERS | BUS | 4 | 5 | 5 | 10 | 5 | 14 | 6 | 10 | 12 | 12 | 12 | 12 |  | 50 Ohms | TOP=L2:L3=L2/L4:L6=L5/L7:BOTTOM=L7 |
| FLA_WPN | OTHERS | BUS | 5 | 5 | 5 | 10 | 5 | 14 | 6 | 10 | 12 | 12 | 12 | 12 |  | 50 Ohms | TOP=L2:L3=L2/L4:L6=L5/L7:BOTTOM=L7 |
| FLA_WPN | OTHERS | BUS | 6 | 5 | 5 | 10 | 5 | 14 | 6 | 10 | 12 | 12 | 12 | 12 |  | 50 Ohms | TOP=L2:L3=L2/L4:L6=L5/L7:BOTTOM=L7 |
| FLA_WPN | OTHERS | BUS | 7 | 5 | 5 | 10 | 5 | 14 | 6 | 10 | 12 | 12 | 12 | 12 |  | 50 Ohms | TOP=L2:L3=L2/L4:L6=L5/L7:BOTTOM=L7 |
| FLA_WPN | OTHERS | BUS | 8 | 4.75 | 5 | 10 | 5 | 14 | 6 | 9.5 | 12 | 12 | 12 | 12 |  | 50 Ohms | TOP=L2:L3=L2/L4:L6=L5/L7:BOTTOM=L7 |
| FLA1_WPN | OTHERS | BUS | 1 | 4.75 | 5 | 10 | 5 | 14 | 6 | 9.5 | 12 | 12 | 12 | 12 |  | 50 Ohms | TOP=L2:L3=L2/L4:L6=L5/L7:BOTTOM=L7 |
| FLA1_WPN | OTHERS | BUS | 2 | 5 | 5 | 10 | 5 | 14 | 6 | 10 | 12 | 12 | 12 | 12 |  | 50 Ohms | TOP=L2:L3=L2/L4:L6=L5/L7:BOTTOM=L7 |
| FLA1_WPN | OTHERS | BUS | 3 | 5 | 5 | 10 | 5 | 14 | 6 | 10 | 12 | 12 | 12 | 12 |  | 50 Ohms | TOP=L2:L3=L2/L4:L6=L5/L7:BOTTOM=L7 |
| FLA1_WPN | OTHERS | BUS | 4 | 5 | 5 | 10 | 5 | 14 | 6 | 10 | 12 | 12 | 12 | 12 |  | 50 Ohms | TOP=L2:L3=L2/L4:L6=L5/L7:BOTTOM=L7 |
| FLA1_WPN | OTHERS | BUS | 5 | 5 | 5 | 10 | 5 | 14 | 6 | 10 | 12 | 12 | 12 | 12 |  | 50 Ohms | TOP=L2:L3=L2/L4:L6=L5/L7:BOTTOM=L7 |
| FLA1_WPN | OTHERS | BUS | 6 | 5 | 5 | 10 | 5 | 14 | 6 | 10 | 12 | 12 | 12 | 12 |  | 50 Ohms | TOP=L2:L3=L2/L4:L6=L5/L7:BOTTOM=L7 |
| FLA1_WPN | OTHERS | BUS | 7 | 5 | 5 | 10 | 5 | 14 | 6 | 10 | 12 | 12 | 12 | 12 |  | 50 Ohms | TOP=L2:L3=L2/L4:L6=L5/L7:BOTTOM=L7 |
| FLA1_WPN | OTHERS | BUS | 8 | 4.75 | 5 | 10 | 5 | 14 | 6 | 9.5 | 12 | 12 | 12 | 12 |  | 50 Ohms | TOP=L2:L3=L2/L4:L6=L5/L7:BOTTOM=L7 |
| FLA1_WPN_R | OTHERS | BUS | 1 | 4.75 | 5 | 10 | 5 | 14 | 6 | 9.5 | 12 | 12 | 12 | 12 |  | 50 Ohms | TOP=L2:L3=L2/L4:L6=L5/L7:BOTTOM=L7 |
| FLA1_WPN_R | OTHERS | BUS | 2 | 5 | 5 | 10 | 5 | 14 | 6 | 10 | 12 | 12 | 12 | 12 |  | 50 Ohms | TOP=L2:L3=L2/L4:L6=L5/L7:BOTTOM=L7 |
| FLA1_WPN_R | OTHERS | BUS | 3 | 5 | 5 | 10 | 5 | 14 | 6 | 10 | 12 | 12 | 12 | 12 |  | 50 Ohms | TOP=L2:L3=L2/L4:L6=L5/L7:BOTTOM=L7 |
| FLA1_WPN_R | OTHERS | BUS | 4 | 5 | 5 | 10 | 5 | 14 | 6 | 10 | 12 | 12 | 12 | 12 |  | 50 Ohms | TOP=L2:L3=L2/L4:L6=L5/L7:BOTTOM=L7 |
| FLA1_WPN_R | OTHERS | BUS | 5 | 5 | 5 | 10 | 5 | 14 | 6 | 10 | 12 | 12 | 12 | 12 |  | 50 Ohms | TOP=L2:L3=L2/L4:L6=L5/L7:BOTTOM=L7 |
| FLA1_WPN_R | OTHERS | BUS | 6 | 5 | 5 | 10 | 5 | 14 | 6 | 10 | 12 | 12 | 12 | 12 |  | 50 Ohms | TOP=L2:L3=L2/L4:L6=L5/L7:BOTTOM=L7 |
| FLA1_WPN_R | OTHERS | BUS | 7 | 5 | 5 | 10 | 5 | 14 | 6 | 10 | 12 | 12 | 12 | 12 |  | 50 Ohms | TOP=L2:L3=L2/L4:L6=L5/L7:BOTTOM=L7 |
| FLA1_WPN_R | OTHERS | BUS | 8 | 4.75 | 5 | 10 | 5 | 14 | 6 | 9.5 | 12 | 12 | 12 | 12 |  | 50 Ohms | TOP=L2:L3=L2/L4:L6=L5/L7:BOTTOM=L7 |
| FM_BMC_RESET#_BTN | OTHERS | BUS | 1 | 4.75 | 5 | 10 | 5 | 14 | 6 | 9.5 | 12 | 12 | 12 | 12 |  | 50 Ohms | TOP=L2:L3=L2/L4:L6=L5/L7:BOTTOM=L7 |
| FM_BMC_RESET#_BTN | OTHERS | BUS | 2 | 5 | 5 | 10 | 5 | 14 | 6 | 10 | 12 | 12 | 12 | 12 |  | 50 Ohms | TOP=L2:L3=L2/L4:L6=L5/L7:BOTTOM=L7 |
| FM_BMC_RESET#_BTN | OTHERS | BUS | 3 | 5 | 5 | 10 | 5 | 14 | 6 | 10 | 12 | 12 | 12 | 12 |  | 50 Ohms | TOP=L2:L3=L2/L4:L6=L5/L7:BOTTOM=L7 |
| FM_BMC_RESET#_BTN | OTHERS | BUS | 4 | 5 | 5 | 10 | 5 | 14 | 6 | 10 | 12 | 12 | 12 | 12 |  | 50 Ohms | TOP=L2:L3=L2/L4:L6=L5/L7:BOTTOM=L7 |
| FM_BMC_RESET#_BTN | OTHERS | BUS | 5 | 5 | 5 | 10 | 5 | 14 | 6 | 10 | 12 | 12 | 12 | 12 |  | 50 Ohms | TOP=L2:L3=L2/L4:L6=L5/L7:BOTTOM=L7 |
| FM_BMC_RESET#_BTN | OTHERS | BUS | 6 | 5 | 5 | 10 | 5 | 14 | 6 | 10 | 12 | 12 | 12 | 12 |  | 50 Ohms | TOP=L2:L3=L2/L4:L6=L5/L7:BOTTOM=L7 |
| FM_BMC_RESET#_BTN | OTHERS | BUS | 7 | 5 | 5 | 10 | 5 | 14 | 6 | 10 | 12 | 12 | 12 | 12 |  | 50 Ohms | TOP=L2:L3=L2/L4:L6=L5/L7:BOTTOM=L7 |
| FM_BMC_RESET#_BTN | OTHERS | BUS | 8 | 4.75 | 5 | 10 | 5 | 14 | 6 | 9.5 | 12 | 12 | 12 | 12 |  | 50 Ohms | TOP=L2:L3=L2/L4:L6=L5/L7:BOTTOM=L7 |
| FM_BMC_RESET#_BTN_D | OTHERS | BUS | 1 | 4.75 | 5 | 10 | 5 | 14 | 6 | 9.5 | 12 | 12 | 12 | 12 |  | 50 Ohms | TOP=L2:L3=L2/L4:L6=L5/L7:BOTTOM=L7 |
| FM_BMC_RESET#_BTN_D | OTHERS | BUS | 2 | 5 | 5 | 10 | 5 | 14 | 6 | 10 | 12 | 12 | 12 | 12 |  | 50 Ohms | TOP=L2:L3=L2/L4:L6=L5/L7:BOTTOM=L7 |
| FM_BMC_RESET#_BTN_D | OTHERS | BUS | 3 | 5 | 5 | 10 | 5 | 14 | 6 | 10 | 12 | 12 | 12 | 12 |  | 50 Ohms | TOP=L2:L3=L2/L4:L6=L5/L7:BOTTOM=L7 |
| FM_BMC_RESET#_BTN_D | OTHERS | BUS | 4 | 5 | 5 | 10 | 5 | 14 | 6 | 10 | 12 | 12 | 12 | 12 |  | 50 Ohms | TOP=L2:L3=L2/L4:L6=L5/L7:BOTTOM=L7 |
| FM_BMC_RESET#_BTN_D | OTHERS | BUS | 5 | 5 | 5 | 10 | 5 | 14 | 6 | 10 | 12 | 12 | 12 | 12 |  | 50 Ohms | TOP=L2:L3=L2/L4:L6=L5/L7:BOTTOM=L7 |
| FM_BMC_RESET#_BTN_D | OTHERS | BUS | 6 | 5 | 5 | 10 | 5 | 14 | 6 | 10 | 12 | 12 | 12 | 12 |  | 50 Ohms | TOP=L2:L3=L2/L4:L6=L5/L7:BOTTOM=L7 |
| FM_BMC_RESET#_BTN_D | OTHERS | BUS | 7 | 5 | 5 | 10 | 5 | 14 | 6 | 10 | 12 | 12 | 12 | 12 |  | 50 Ohms | TOP=L2:L3=L2/L4:L6=L5/L7:BOTTOM=L7 |
| FM_BMC_RESET#_BTN_D | OTHERS | BUS | 8 | 4.75 | 5 | 10 | 5 | 14 | 6 | 9.5 | 12 | 12 | 12 | 12 |  | 50 Ohms | TOP=L2:L3=L2/L4:L6=L5/L7:BOTTOM=L7 |
| FM_BMC_RESET_N | OTHERS | BUS | 1 | 4.75 | 5 | 10 | 5 | 14 | 6 | 9.5 | 12 | 12 | 12 | 12 |  | 50 Ohms | TOP=L2:L3=L2/L4:L6=L5/L7:BOTTOM=L7 |
| FM_BMC_RESET_N | OTHERS | BUS | 2 | 5 | 5 | 10 | 5 | 14 | 6 | 10 | 12 | 12 | 12 | 12 |  | 50 Ohms | TOP=L2:L3=L2/L4:L6=L5/L7:BOTTOM=L7 |
| FM_BMC_RESET_N | OTHERS | BUS | 3 | 5 | 5 | 10 | 5 | 14 | 6 | 10 | 12 | 12 | 12 | 12 |  | 50 Ohms | TOP=L2:L3=L2/L4:L6=L5/L7:BOTTOM=L7 |
| FM_BMC_RESET_N | OTHERS | BUS | 4 | 5 | 5 | 10 | 5 | 14 | 6 | 10 | 12 | 12 | 12 | 12 |  | 50 Ohms | TOP=L2:L3=L2/L4:L6=L5/L7:BOTTOM=L7 |
| FM_BMC_RESET_N | OTHERS | BUS | 5 | 5 | 5 | 10 | 5 | 14 | 6 | 10 | 12 | 12 | 12 | 12 |  | 50 Ohms | TOP=L2:L3=L2/L4:L6=L5/L7:BOTTOM=L7 |
| FM_BMC_RESET_N | OTHERS | BUS | 6 | 5 | 5 | 10 | 5 | 14 | 6 | 10 | 12 | 12 | 12 | 12 |  | 50 Ohms | TOP=L2:L3=L2/L4:L6=L5/L7:BOTTOM=L7 |
| FM_BMC_RESET_N | OTHERS | BUS | 7 | 5 | 5 | 10 | 5 | 14 | 6 | 10 | 12 | 12 | 12 | 12 |  | 50 Ohms | TOP=L2:L3=L2/L4:L6=L5/L7:BOTTOM=L7 |
| FM_BMC_RESET_N | OTHERS | BUS | 8 | 4.75 | 5 | 10 | 5 | 14 | 6 | 9.5 | 12 | 12 | 12 | 12 |  | 50 Ohms | TOP=L2:L3=L2/L4:L6=L5/L7:BOTTOM=L7 |
| FM_BMC_RESET_Q36 | OTHERS | BUS | 1 | 4.75 | 5 | 10 | 5 | 14 | 6 | 9.5 | 12 | 12 | 12 | 12 |  | 50 Ohms | TOP=L2:L3=L2/L4:L6=L5/L7:BOTTOM=L7 |
| FM_BMC_RESET_Q36 | OTHERS | BUS | 2 | 5 | 5 | 10 | 5 | 14 | 6 | 10 | 12 | 12 | 12 | 12 |  | 50 Ohms | TOP=L2:L3=L2/L4:L6=L5/L7:BOTTOM=L7 |
| FM_BMC_RESET_Q36 | OTHERS | BUS | 3 | 5 | 5 | 10 | 5 | 14 | 6 | 10 | 12 | 12 | 12 | 12 |  | 50 Ohms | TOP=L2:L3=L2/L4:L6=L5/L7:BOTTOM=L7 |
| FM_BMC_RESET_Q36 | OTHERS | BUS | 4 | 5 | 5 | 10 | 5 | 14 | 6 | 10 | 12 | 12 | 12 | 12 |  | 50 Ohms | TOP=L2:L3=L2/L4:L6=L5/L7:BOTTOM=L7 |
| FM_BMC_RESET_Q36 | OTHERS | BUS | 5 | 5 | 5 | 10 | 5 | 14 | 6 | 10 | 12 | 12 | 12 | 12 |  | 50 Ohms | TOP=L2:L3=L2/L4:L6=L5/L7:BOTTOM=L7 |
| FM_BMC_RESET_Q36 | OTHERS | BUS | 6 | 5 | 5 | 10 | 5 | 14 | 6 | 10 | 12 | 12 | 12 | 12 |  | 50 Ohms | TOP=L2:L3=L2/L4:L6=L5/L7:BOTTOM=L7 |
| FM_BMC_RESET_Q36 | OTHERS | BUS | 7 | 5 | 5 | 10 | 5 | 14 | 6 | 10 | 12 | 12 | 12 | 12 |  | 50 Ohms | TOP=L2:L3=L2/L4:L6=L5/L7:BOTTOM=L7 |
| FM_BMC_RESET_Q36 | OTHERS | BUS | 8 | 4.75 | 5 | 10 | 5 | 14 | 6 | 9.5 | 12 | 12 | 12 | 12 |  | 50 Ohms | TOP=L2:L3=L2/L4:L6=L5/L7:BOTTOM=L7 |
| FM_BMC_RESET_Q36_R | OTHERS | BUS | 1 | 4.75 | 5 | 10 | 5 | 14 | 6 | 9.5 | 12 | 12 | 12 | 12 |  | 50 Ohms | TOP=L2:L3=L2/L4:L6=L5/L7:BOTTOM=L7 |
| FM_BMC_RESET_Q36_R | OTHERS | BUS | 2 | 5 | 5 | 10 | 5 | 14 | 6 | 10 | 12 | 12 | 12 | 12 |  | 50 Ohms | TOP=L2:L3=L2/L4:L6=L5/L7:BOTTOM=L7 |
| FM_BMC_RESET_Q36_R | OTHERS | BUS | 3 | 5 | 5 | 10 | 5 | 14 | 6 | 10 | 12 | 12 | 12 | 12 |  | 50 Ohms | TOP=L2:L3=L2/L4:L6=L5/L7:BOTTOM=L7 |
| FM_BMC_RESET_Q36_R | OTHERS | BUS | 4 | 5 | 5 | 10 | 5 | 14 | 6 | 10 | 12 | 12 | 12 | 12 |  | 50 Ohms | TOP=L2:L3=L2/L4:L6=L5/L7:BOTTOM=L7 |
| FM_BMC_RESET_Q36_R | OTHERS | BUS | 5 | 5 | 5 | 10 | 5 | 14 | 6 | 10 | 12 | 12 | 12 | 12 |  | 50 Ohms | TOP=L2:L3=L2/L4:L6=L5/L7:BOTTOM=L7 |
| FM_BMC_RESET_Q36_R | OTHERS | BUS | 6 | 5 | 5 | 10 | 5 | 14 | 6 | 10 | 12 | 12 | 12 | 12 |  | 50 Ohms | TOP=L2:L3=L2/L4:L6=L5/L7:BOTTOM=L7 |
| FM_BMC_RESET_Q36_R | OTHERS | BUS | 7 | 5 | 5 | 10 | 5 | 14 | 6 | 10 | 12 | 12 | 12 | 12 |  | 50 Ohms | TOP=L2:L3=L2/L4:L6=L5/L7:BOTTOM=L7 |
| FM_BMC_RESET_Q36_R | OTHERS | BUS | 8 | 4.75 | 5 | 10 | 5 | 14 | 6 | 9.5 | 12 | 12 | 12 | 12 |  | 50 Ohms | TOP=L2:L3=L2/L4:L6=L5/L7:BOTTOM=L7 |
| FM_OSC_50M_EN | OTHERS | BUS | 1 | 4.75 | 5 | 10 | 5 | 14 | 6 | 9.5 | 12 | 12 | 12 | 12 |  | 50 Ohms | TOP=L2:L3=L2/L4:L6=L5/L7:BOTTOM=L7 |
| FM_OSC_50M_EN | OTHERS | BUS | 2 | 5 | 5 | 10 | 5 | 14 | 6 | 10 | 12 | 12 | 12 | 12 |  | 50 Ohms | TOP=L2:L3=L2/L4:L6=L5/L7:BOTTOM=L7 |
| FM_OSC_50M_EN | OTHERS | BUS | 3 | 5 | 5 | 10 | 5 | 14 | 6 | 10 | 12 | 12 | 12 | 12 |  | 50 Ohms | TOP=L2:L3=L2/L4:L6=L5/L7:BOTTOM=L7 |
| FM_OSC_50M_EN | OTHERS | BUS | 4 | 5 | 5 | 10 | 5 | 14 | 6 | 10 | 12 | 12 | 12 | 12 |  | 50 Ohms | TOP=L2:L3=L2/L4:L6=L5/L7:BOTTOM=L7 |
| FM_OSC_50M_EN | OTHERS | BUS | 5 | 5 | 5 | 10 | 5 | 14 | 6 | 10 | 12 | 12 | 12 | 12 |  | 50 Ohms | TOP=L2:L3=L2/L4:L6=L5/L7:BOTTOM=L7 |
| FM_OSC_50M_EN | OTHERS | BUS | 6 | 5 | 5 | 10 | 5 | 14 | 6 | 10 | 12 | 12 | 12 | 12 |  | 50 Ohms | TOP=L2:L3=L2/L4:L6=L5/L7:BOTTOM=L7 |
| FM_OSC_50M_EN | OTHERS | BUS | 7 | 5 | 5 | 10 | 5 | 14 | 6 | 10 | 12 | 12 | 12 | 12 |  | 50 Ohms | TOP=L2:L3=L2/L4:L6=L5/L7:BOTTOM=L7 |
| FM_OSC_50M_EN | OTHERS | BUS | 8 | 4.75 | 5 | 10 | 5 | 14 | 6 | 9.5 | 12 | 12 | 12 | 12 |  | 50 Ohms | TOP=L2:L3=L2/L4:L6=L5/L7:BOTTOM=L7 |
| FM_PCH_LAN1_DISABLE_N | OTHERS | BUS | 1 | 4.75 | 5 | 10 | 5 | 14 | 6 | 9.5 | 12 | 12 | 12 | 12 |  | 50 Ohms | TOP=L2:L3=L2/L4:L6=L5/L7:BOTTOM=L7 |
| FM_PCH_LAN1_DISABLE_N | OTHERS | BUS | 2 | 5 | 5 | 10 | 5 | 14 | 6 | 10 | 12 | 12 | 12 | 12 |  | 50 Ohms | TOP=L2:L3=L2/L4:L6=L5/L7:BOTTOM=L7 |
| FM_PCH_LAN1_DISABLE_N | OTHERS | BUS | 3 | 5 | 5 | 10 | 5 | 14 | 6 | 10 | 12 | 12 | 12 | 12 |  | 50 Ohms | TOP=L2:L3=L2/L4:L6=L5/L7:BOTTOM=L7 |
| FM_PCH_LAN1_DISABLE_N | OTHERS | BUS | 4 | 5 | 5 | 10 | 5 | 14 | 6 | 10 | 12 | 12 | 12 | 12 |  | 50 Ohms | TOP=L2:L3=L2/L4:L6=L5/L7:BOTTOM=L7 |
| FM_PCH_LAN1_DISABLE_N | OTHERS | BUS | 5 | 5 | 5 | 10 | 5 | 14 | 6 | 10 | 12 | 12 | 12 | 12 |  | 50 Ohms | TOP=L2:L3=L2/L4:L6=L5/L7:BOTTOM=L7 |
| FM_PCH_LAN1_DISABLE_N | OTHERS | BUS | 6 | 5 | 5 | 10 | 5 | 14 | 6 | 10 | 12 | 12 | 12 | 12 |  | 50 Ohms | TOP=L2:L3=L2/L4:L6=L5/L7:BOTTOM=L7 |
| FM_PCH_LAN1_DISABLE_N | OTHERS | BUS | 7 | 5 | 5 | 10 | 5 | 14 | 6 | 10 | 12 | 12 | 12 | 12 |  | 50 Ohms | TOP=L2:L3=L2/L4:L6=L5/L7:BOTTOM=L7 |
| FM_PCH_LAN1_DISABLE_N | OTHERS | BUS | 8 | 4.75 | 5 | 10 | 5 | 14 | 6 | 9.5 | 12 | 12 | 12 | 12 |  | 50 Ohms | TOP=L2:L3=L2/L4:L6=L5/L7:BOTTOM=L7 |
| FM_PCH_LAN1_DISABLE_N_R | OTHERS | BUS | 1 | 4.75 | 5 | 10 | 5 | 14 | 6 | 9.5 | 12 | 12 | 12 | 12 |  | 50 Ohms | TOP=L2:L3=L2/L4:L6=L5/L7:BOTTOM=L7 |
| FM_PCH_LAN1_DISABLE_N_R | OTHERS | BUS | 2 | 5 | 5 | 10 | 5 | 14 | 6 | 10 | 12 | 12 | 12 | 12 |  | 50 Ohms | TOP=L2:L3=L2/L4:L6=L5/L7:BOTTOM=L7 |
| FM_PCH_LAN1_DISABLE_N_R | OTHERS | BUS | 3 | 5 | 5 | 10 | 5 | 14 | 6 | 10 | 12 | 12 | 12 | 12 |  | 50 Ohms | TOP=L2:L3=L2/L4:L6=L5/L7:BOTTOM=L7 |
| FM_PCH_LAN1_DISABLE_N_R | OTHERS | BUS | 4 | 5 | 5 | 10 | 5 | 14 | 6 | 10 | 12 | 12 | 12 | 12 |  | 50 Ohms | TOP=L2:L3=L2/L4:L6=L5/L7:BOTTOM=L7 |
| FM_PCH_LAN1_DISABLE_N_R | OTHERS | BUS | 5 | 5 | 5 | 10 | 5 | 14 | 6 | 10 | 12 | 12 | 12 | 12 |  | 50 Ohms | TOP=L2:L3=L2/L4:L6=L5/L7:BOTTOM=L7 |
| FM_PCH_LAN1_DISABLE_N_R | OTHERS | BUS | 6 | 5 | 5 | 10 | 5 | 14 | 6 | 10 | 12 | 12 | 12 | 12 |  | 50 Ohms | TOP=L2:L3=L2/L4:L6=L5/L7:BOTTOM=L7 |
| FM_PCH_LAN1_DISABLE_N_R | OTHERS | BUS | 7 | 5 | 5 | 10 | 5 | 14 | 6 | 10 | 12 | 12 | 12 | 12 |  | 50 Ohms | TOP=L2:L3=L2/L4:L6=L5/L7:BOTTOM=L7 |
| FM_PCH_LAN1_DISABLE_N_R | OTHERS | BUS | 8 | 4.75 | 5 | 10 | 5 | 14 | 6 | 9.5 | 12 | 12 | 12 | 12 |  | 50 Ohms | TOP=L2:L3=L2/L4:L6=L5/L7:BOTTOM=L7 |
| FM_TPM_PRES_N | OTHERS | BUS | 1 | 4.75 | 5 | 10 | 5 | 14 | 6 | 9.5 | 12 | 12 | 12 | 12 |  | 50 Ohms | TOP=L2:L3=L2/L4:L6=L5/L7:BOTTOM=L7 |
| FM_TPM_PRES_N | OTHERS | BUS | 2 | 5 | 5 | 10 | 5 | 14 | 6 | 10 | 12 | 12 | 12 | 12 |  | 50 Ohms | TOP=L2:L3=L2/L4:L6=L5/L7:BOTTOM=L7 |
| FM_TPM_PRES_N | OTHERS | BUS | 3 | 5 | 5 | 10 | 5 | 14 | 6 | 10 | 12 | 12 | 12 | 12 |  | 50 Ohms | TOP=L2:L3=L2/L4:L6=L5/L7:BOTTOM=L7 |
| FM_TPM_PRES_N | OTHERS | BUS | 4 | 5 | 5 | 10 | 5 | 14 | 6 | 10 | 12 | 12 | 12 | 12 |  | 50 Ohms | TOP=L2:L3=L2/L4:L6=L5/L7:BOTTOM=L7 |
| FM_TPM_PRES_N | OTHERS | BUS | 5 | 5 | 5 | 10 | 5 | 14 | 6 | 10 | 12 | 12 | 12 | 12 |  | 50 Ohms | TOP=L2:L3=L2/L4:L6=L5/L7:BOTTOM=L7 |
| FM_TPM_PRES_N | OTHERS | BUS | 6 | 5 | 5 | 10 | 5 | 14 | 6 | 10 | 12 | 12 | 12 | 12 |  | 50 Ohms | TOP=L2:L3=L2/L4:L6=L5/L7:BOTTOM=L7 |
| FM_TPM_PRES_N | OTHERS | BUS | 7 | 5 | 5 | 10 | 5 | 14 | 6 | 10 | 12 | 12 | 12 | 12 |  | 50 Ohms | TOP=L2:L3=L2/L4:L6=L5/L7:BOTTOM=L7 |
| FM_TPM_PRES_N | OTHERS | BUS | 8 | 4.75 | 5 | 10 | 5 | 14 | 6 | 9.5 | 12 | 12 | 12 | 12 |  | 50 Ohms | TOP=L2:L3=L2/L4:L6=L5/L7:BOTTOM=L7 |
| FM_TPM_PRES_N_R | OTHERS | BUS | 1 | 4.75 | 5 | 10 | 5 | 14 | 6 | 9.5 | 12 | 12 | 12 | 12 |  | 50 Ohms | TOP=L2:L3=L2/L4:L6=L5/L7:BOTTOM=L7 |
| FM_TPM_PRES_N_R | OTHERS | BUS | 2 | 5 | 5 | 10 | 5 | 14 | 6 | 10 | 12 | 12 | 12 | 12 |  | 50 Ohms | TOP=L2:L3=L2/L4:L6=L5/L7:BOTTOM=L7 |
| FM_TPM_PRES_N_R | OTHERS | BUS | 3 | 5 | 5 | 10 | 5 | 14 | 6 | 10 | 12 | 12 | 12 | 12 |  | 50 Ohms | TOP=L2:L3=L2/L4:L6=L5/L7:BOTTOM=L7 |
| FM_TPM_PRES_N_R | OTHERS | BUS | 4 | 5 | 5 | 10 | 5 | 14 | 6 | 10 | 12 | 12 | 12 | 12 |  | 50 Ohms | TOP=L2:L3=L2/L4:L6=L5/L7:BOTTOM=L7 |
| FM_TPM_PRES_N_R | OTHERS | BUS | 5 | 5 | 5 | 10 | 5 | 14 | 6 | 10 | 12 | 12 | 12 | 12 |  | 50 Ohms | TOP=L2:L3=L2/L4:L6=L5/L7:BOTTOM=L7 |
| FM_TPM_PRES_N_R | OTHERS | BUS | 6 | 5 | 5 | 10 | 5 | 14 | 6 | 10 | 12 | 12 | 12 | 12 |  | 50 Ohms | TOP=L2:L3=L2/L4:L6=L5/L7:BOTTOM=L7 |
| FM_TPM_PRES_N_R | OTHERS | BUS | 7 | 5 | 5 | 10 | 5 | 14 | 6 | 10 | 12 | 12 | 12 | 12 |  | 50 Ohms | TOP=L2:L3=L2/L4:L6=L5/L7:BOTTOM=L7 |
| FM_TPM_PRES_N_R | OTHERS | BUS | 8 | 4.75 | 5 | 10 | 5 | 14 | 6 | 9.5 | 12 | 12 | 12 | 12 |  | 50 Ohms | TOP=L2:L3=L2/L4:L6=L5/L7:BOTTOM=L7 |
| FM_TPM_PRES_RST | OTHERS | BUS | 1 | 4.75 | 5 | 10 | 5 | 14 | 6 | 9.5 | 12 | 12 | 12 | 12 |  | 50 Ohms | TOP=L2:L3=L2/L4:L6=L5/L7:BOTTOM=L7 |
| FM_TPM_PRES_RST | OTHERS | BUS | 2 | 5 | 5 | 10 | 5 | 14 | 6 | 10 | 12 | 12 | 12 | 12 |  | 50 Ohms | TOP=L2:L3=L2/L4:L6=L5/L7:BOTTOM=L7 |
| FM_TPM_PRES_RST | OTHERS | BUS | 3 | 5 | 5 | 10 | 5 | 14 | 6 | 10 | 12 | 12 | 12 | 12 |  | 50 Ohms | TOP=L2:L3=L2/L4:L6=L5/L7:BOTTOM=L7 |
| FM_TPM_PRES_RST | OTHERS | BUS | 4 | 5 | 5 | 10 | 5 | 14 | 6 | 10 | 12 | 12 | 12 | 12 |  | 50 Ohms | TOP=L2:L3=L2/L4:L6=L5/L7:BOTTOM=L7 |
| FM_TPM_PRES_RST | OTHERS | BUS | 5 | 5 | 5 | 10 | 5 | 14 | 6 | 10 | 12 | 12 | 12 | 12 |  | 50 Ohms | TOP=L2:L3=L2/L4:L6=L5/L7:BOTTOM=L7 |
| FM_TPM_PRES_RST | OTHERS | BUS | 6 | 5 | 5 | 10 | 5 | 14 | 6 | 10 | 12 | 12 | 12 | 12 |  | 50 Ohms | TOP=L2:L3=L2/L4:L6=L5/L7:BOTTOM=L7 |
| FM_TPM_PRES_RST | OTHERS | BUS | 7 | 5 | 5 | 10 | 5 | 14 | 6 | 10 | 12 | 12 | 12 | 12 |  | 50 Ohms | TOP=L2:L3=L2/L4:L6=L5/L7:BOTTOM=L7 |
| FM_TPM_PRES_RST | OTHERS | BUS | 8 | 4.75 | 5 | 10 | 5 | 14 | 6 | 9.5 | 12 | 12 | 12 | 12 |  | 50 Ohms | TOP=L2:L3=L2/L4:L6=L5/L7:BOTTOM=L7 |
| FM_TPM_PRES_RST_N | OTHERS | BUS | 1 | 4.75 | 5 | 10 | 5 | 14 | 6 | 9.5 | 12 | 12 | 12 | 12 |  | 50 Ohms | TOP=L2:L3=L2/L4:L6=L5/L7:BOTTOM=L7 |
| FM_TPM_PRES_RST_N | OTHERS | BUS | 2 | 5 | 5 | 10 | 5 | 14 | 6 | 10 | 12 | 12 | 12 | 12 |  | 50 Ohms | TOP=L2:L3=L2/L4:L6=L5/L7:BOTTOM=L7 |
| FM_TPM_PRES_RST_N | OTHERS | BUS | 3 | 5 | 5 | 10 | 5 | 14 | 6 | 10 | 12 | 12 | 12 | 12 |  | 50 Ohms | TOP=L2:L3=L2/L4:L6=L5/L7:BOTTOM=L7 |
| FM_TPM_PRES_RST_N | OTHERS | BUS | 4 | 5 | 5 | 10 | 5 | 14 | 6 | 10 | 12 | 12 | 12 | 12 |  | 50 Ohms | TOP=L2:L3=L2/L4:L6=L5/L7:BOTTOM=L7 |
| FM_TPM_PRES_RST_N | OTHERS | BUS | 5 | 5 | 5 | 10 | 5 | 14 | 6 | 10 | 12 | 12 | 12 | 12 |  | 50 Ohms | TOP=L2:L3=L2/L4:L6=L5/L7:BOTTOM=L7 |
| FM_TPM_PRES_RST_N | OTHERS | BUS | 6 | 5 | 5 | 10 | 5 | 14 | 6 | 10 | 12 | 12 | 12 | 12 |  | 50 Ohms | TOP=L2:L3=L2/L4:L6=L5/L7:BOTTOM=L7 |
| FM_TPM_PRES_RST_N | OTHERS | BUS | 7 | 5 | 5 | 10 | 5 | 14 | 6 | 10 | 12 | 12 | 12 | 12 |  | 50 Ohms | TOP=L2:L3=L2/L4:L6=L5/L7:BOTTOM=L7 |
| FM_TPM_PRES_RST_N | OTHERS | BUS | 8 | 4.75 | 5 | 10 | 5 | 14 | 6 | 9.5 | 12 | 12 | 12 | 12 |  | 50 Ohms | TOP=L2:L3=L2/L4:L6=L5/L7:BOTTOM=L7 |
| FM_TPM_PRES_RST_N_C | OTHERS | BUS | 1 | 4.75 | 5 | 10 | 5 | 14 | 6 | 9.5 | 12 | 12 | 12 | 12 |  | 50 Ohms | TOP=L2:L3=L2/L4:L6=L5/L7:BOTTOM=L7 |
| FM_TPM_PRES_RST_N_C | OTHERS | BUS | 2 | 5 | 5 | 10 | 5 | 14 | 6 | 10 | 12 | 12 | 12 | 12 |  | 50 Ohms | TOP=L2:L3=L2/L4:L6=L5/L7:BOTTOM=L7 |
| FM_TPM_PRES_RST_N_C | OTHERS | BUS | 3 | 5 | 5 | 10 | 5 | 14 | 6 | 10 | 12 | 12 | 12 | 12 |  | 50 Ohms | TOP=L2:L3=L2/L4:L6=L5/L7:BOTTOM=L7 |
| FM_TPM_PRES_RST_N_C | OTHERS | BUS | 4 | 5 | 5 | 10 | 5 | 14 | 6 | 10 | 12 | 12 | 12 | 12 |  | 50 Ohms | TOP=L2:L3=L2/L4:L6=L5/L7:BOTTOM=L7 |
| FM_TPM_PRES_RST_N_C | OTHERS | BUS | 5 | 5 | 5 | 10 | 5 | 14 | 6 | 10 | 12 | 12 | 12 | 12 |  | 50 Ohms | TOP=L2:L3=L2/L4:L6=L5/L7:BOTTOM=L7 |
| FM_TPM_PRES_RST_N_C | OTHERS | BUS | 6 | 5 | 5 | 10 | 5 | 14 | 6 | 10 | 12 | 12 | 12 | 12 |  | 50 Ohms | TOP=L2:L3=L2/L4:L6=L5/L7:BOTTOM=L7 |
| FM_TPM_PRES_RST_N_C | OTHERS | BUS | 7 | 5 | 5 | 10 | 5 | 14 | 6 | 10 | 12 | 12 | 12 | 12 |  | 50 Ohms | TOP=L2:L3=L2/L4:L6=L5/L7:BOTTOM=L7 |
| FM_TPM_PRES_RST_N_C | OTHERS | BUS | 8 | 4.75 | 5 | 10 | 5 | 14 | 6 | 9.5 | 12 | 12 | 12 | 12 |  | 50 Ohms | TOP=L2:L3=L2/L4:L6=L5/L7:BOTTOM=L7 |
| FM_TPM_PRES_RST_N_R | OTHERS | BUS | 1 | 4.75 | 5 | 10 | 5 | 14 | 6 | 9.5 | 12 | 12 | 12 | 12 |  | 50 Ohms | TOP=L2:L3=L2/L4:L6=L5/L7:BOTTOM=L7 |
| FM_TPM_PRES_RST_N_R | OTHERS | BUS | 2 | 5 | 5 | 10 | 5 | 14 | 6 | 10 | 12 | 12 | 12 | 12 |  | 50 Ohms | TOP=L2:L3=L2/L4:L6=L5/L7:BOTTOM=L7 |
| FM_TPM_PRES_RST_N_R | OTHERS | BUS | 3 | 5 | 5 | 10 | 5 | 14 | 6 | 10 | 12 | 12 | 12 | 12 |  | 50 Ohms | TOP=L2:L3=L2/L4:L6=L5/L7:BOTTOM=L7 |
| FM_TPM_PRES_RST_N_R | OTHERS | BUS | 4 | 5 | 5 | 10 | 5 | 14 | 6 | 10 | 12 | 12 | 12 | 12 |  | 50 Ohms | TOP=L2:L3=L2/L4:L6=L5/L7:BOTTOM=L7 |
| FM_TPM_PRES_RST_N_R | OTHERS | BUS | 5 | 5 | 5 | 10 | 5 | 14 | 6 | 10 | 12 | 12 | 12 | 12 |  | 50 Ohms | TOP=L2:L3=L2/L4:L6=L5/L7:BOTTOM=L7 |
| FM_TPM_PRES_RST_N_R | OTHERS | BUS | 6 | 5 | 5 | 10 | 5 | 14 | 6 | 10 | 12 | 12 | 12 | 12 |  | 50 Ohms | TOP=L2:L3=L2/L4:L6=L5/L7:BOTTOM=L7 |
| FM_TPM_PRES_RST_N_R | OTHERS | BUS | 7 | 5 | 5 | 10 | 5 | 14 | 6 | 10 | 12 | 12 | 12 | 12 |  | 50 Ohms | TOP=L2:L3=L2/L4:L6=L5/L7:BOTTOM=L7 |
| FM_TPM_PRES_RST_N_R | OTHERS | BUS | 8 | 4.75 | 5 | 10 | 5 | 14 | 6 | 9.5 | 12 | 12 | 12 | 12 |  | 50 Ohms | TOP=L2:L3=L2/L4:L6=L5/L7:BOTTOM=L7 |
| GPIO107_R | OTHERS | BUS | 1 | 4.75 | 5 | 10 | 5 | 14 | 6 | 9.5 | 12 | 12 | 12 | 12 |  | 50 Ohms | TOP=L2:L3=L2/L4:L6=L5/L7:BOTTOM=L7 |
| GPIO107_R | OTHERS | BUS | 2 | 5 | 5 | 10 | 5 | 14 | 6 | 10 | 12 | 12 | 12 | 12 |  | 50 Ohms | TOP=L2:L3=L2/L4:L6=L5/L7:BOTTOM=L7 |
| GPIO107_R | OTHERS | BUS | 3 | 5 | 5 | 10 | 5 | 14 | 6 | 10 | 12 | 12 | 12 | 12 |  | 50 Ohms | TOP=L2:L3=L2/L4:L6=L5/L7:BOTTOM=L7 |
| GPIO107_R | OTHERS | BUS | 4 | 5 | 5 | 10 | 5 | 14 | 6 | 10 | 12 | 12 | 12 | 12 |  | 50 Ohms | TOP=L2:L3=L2/L4:L6=L5/L7:BOTTOM=L7 |
| GPIO107_R | OTHERS | BUS | 5 | 5 | 5 | 10 | 5 | 14 | 6 | 10 | 12 | 12 | 12 | 12 |  | 50 Ohms | TOP=L2:L3=L2/L4:L6=L5/L7:BOTTOM=L7 |
| GPIO107_R | OTHERS | BUS | 6 | 5 | 5 | 10 | 5 | 14 | 6 | 10 | 12 | 12 | 12 | 12 |  | 50 Ohms | TOP=L2:L3=L2/L4:L6=L5/L7:BOTTOM=L7 |
| GPIO107_R | OTHERS | BUS | 7 | 5 | 5 | 10 | 5 | 14 | 6 | 10 | 12 | 12 | 12 | 12 |  | 50 Ohms | TOP=L2:L3=L2/L4:L6=L5/L7:BOTTOM=L7 |
| GPIO107_R | OTHERS | BUS | 8 | 4.75 | 5 | 10 | 5 | 14 | 6 | 9.5 | 12 | 12 | 12 | 12 |  | 50 Ohms | TOP=L2:L3=L2/L4:L6=L5/L7:BOTTOM=L7 |
| GPIO108_R | OTHERS | BUS | 1 | 4.75 | 5 | 10 | 5 | 14 | 6 | 9.5 | 12 | 12 | 12 | 12 |  | 50 Ohms | TOP=L2:L3=L2/L4:L6=L5/L7:BOTTOM=L7 |
| GPIO108_R | OTHERS | BUS | 2 | 5 | 5 | 10 | 5 | 14 | 6 | 10 | 12 | 12 | 12 | 12 |  | 50 Ohms | TOP=L2:L3=L2/L4:L6=L5/L7:BOTTOM=L7 |
| GPIO108_R | OTHERS | BUS | 3 | 5 | 5 | 10 | 5 | 14 | 6 | 10 | 12 | 12 | 12 | 12 |  | 50 Ohms | TOP=L2:L3=L2/L4:L6=L5/L7:BOTTOM=L7 |
| GPIO108_R | OTHERS | BUS | 4 | 5 | 5 | 10 | 5 | 14 | 6 | 10 | 12 | 12 | 12 | 12 |  | 50 Ohms | TOP=L2:L3=L2/L4:L6=L5/L7:BOTTOM=L7 |
| GPIO108_R | OTHERS | BUS | 5 | 5 | 5 | 10 | 5 | 14 | 6 | 10 | 12 | 12 | 12 | 12 |  | 50 Ohms | TOP=L2:L3=L2/L4:L6=L5/L7:BOTTOM=L7 |
| GPIO108_R | OTHERS | BUS | 6 | 5 | 5 | 10 | 5 | 14 | 6 | 10 | 12 | 12 | 12 | 12 |  | 50 Ohms | TOP=L2:L3=L2/L4:L6=L5/L7:BOTTOM=L7 |
| GPIO108_R | OTHERS | BUS | 7 | 5 | 5 | 10 | 5 | 14 | 6 | 10 | 12 | 12 | 12 | 12 |  | 50 Ohms | TOP=L2:L3=L2/L4:L6=L5/L7:BOTTOM=L7 |
| GPIO108_R | OTHERS | BUS | 8 | 4.75 | 5 | 10 | 5 | 14 | 6 | 9.5 | 12 | 12 | 12 | 12 |  | 50 Ohms | TOP=L2:L3=L2/L4:L6=L5/L7:BOTTOM=L7 |
| GPIO109_R | OTHERS | BUS | 1 | 4.75 | 5 | 10 | 5 | 14 | 6 | 9.5 | 12 | 12 | 12 | 12 |  | 50 Ohms | TOP=L2:L3=L2/L4:L6=L5/L7:BOTTOM=L7 |
| GPIO109_R | OTHERS | BUS | 2 | 5 | 5 | 10 | 5 | 14 | 6 | 10 | 12 | 12 | 12 | 12 |  | 50 Ohms | TOP=L2:L3=L2/L4:L6=L5/L7:BOTTOM=L7 |
| GPIO109_R | OTHERS | BUS | 3 | 5 | 5 | 10 | 5 | 14 | 6 | 10 | 12 | 12 | 12 | 12 |  | 50 Ohms | TOP=L2:L3=L2/L4:L6=L5/L7:BOTTOM=L7 |
| GPIO109_R | OTHERS | BUS | 4 | 5 | 5 | 10 | 5 | 14 | 6 | 10 | 12 | 12 | 12 | 12 |  | 50 Ohms | TOP=L2:L3=L2/L4:L6=L5/L7:BOTTOM=L7 |
| GPIO109_R | OTHERS | BUS | 5 | 5 | 5 | 10 | 5 | 14 | 6 | 10 | 12 | 12 | 12 | 12 |  | 50 Ohms | TOP=L2:L3=L2/L4:L6=L5/L7:BOTTOM=L7 |
| GPIO109_R | OTHERS | BUS | 6 | 5 | 5 | 10 | 5 | 14 | 6 | 10 | 12 | 12 | 12 | 12 |  | 50 Ohms | TOP=L2:L3=L2/L4:L6=L5/L7:BOTTOM=L7 |
| GPIO109_R | OTHERS | BUS | 7 | 5 | 5 | 10 | 5 | 14 | 6 | 10 | 12 | 12 | 12 | 12 |  | 50 Ohms | TOP=L2:L3=L2/L4:L6=L5/L7:BOTTOM=L7 |
| GPIO109_R | OTHERS | BUS | 8 | 4.75 | 5 | 10 | 5 | 14 | 6 | 9.5 | 12 | 12 | 12 | 12 |  | 50 Ohms | TOP=L2:L3=L2/L4:L6=L5/L7:BOTTOM=L7 |
| GPIOB1 | OTHERS | BUS | 1 | 4.75 | 5 | 10 | 5 | 14 | 6 | 9.5 | 12 | 12 | 12 | 12 |  | 50 Ohms | TOP=L2:L3=L2/L4:L6=L5/L7:BOTTOM=L7 |
| GPIOB1 | OTHERS | BUS | 2 | 5 | 5 | 10 | 5 | 14 | 6 | 10 | 12 | 12 | 12 | 12 |  | 50 Ohms | TOP=L2:L3=L2/L4:L6=L5/L7:BOTTOM=L7 |
| GPIOB1 | OTHERS | BUS | 3 | 5 | 5 | 10 | 5 | 14 | 6 | 10 | 12 | 12 | 12 | 12 |  | 50 Ohms | TOP=L2:L3=L2/L4:L6=L5/L7:BOTTOM=L7 |
| GPIOB1 | OTHERS | BUS | 4 | 5 | 5 | 10 | 5 | 14 | 6 | 10 | 12 | 12 | 12 | 12 |  | 50 Ohms | TOP=L2:L3=L2/L4:L6=L5/L7:BOTTOM=L7 |
| GPIOB1 | OTHERS | BUS | 5 | 5 | 5 | 10 | 5 | 14 | 6 | 10 | 12 | 12 | 12 | 12 |  | 50 Ohms | TOP=L2:L3=L2/L4:L6=L5/L7:BOTTOM=L7 |
| GPIOB1 | OTHERS | BUS | 6 | 5 | 5 | 10 | 5 | 14 | 6 | 10 | 12 | 12 | 12 | 12 |  | 50 Ohms | TOP=L2:L3=L2/L4:L6=L5/L7:BOTTOM=L7 |
| GPIOB1 | OTHERS | BUS | 7 | 5 | 5 | 10 | 5 | 14 | 6 | 10 | 12 | 12 | 12 | 12 |  | 50 Ohms | TOP=L2:L3=L2/L4:L6=L5/L7:BOTTOM=L7 |
| GPIOB1 | OTHERS | BUS | 8 | 4.75 | 5 | 10 | 5 | 14 | 6 | 9.5 | 12 | 12 | 12 | 12 |  | 50 Ohms | TOP=L2:L3=L2/L4:L6=L5/L7:BOTTOM=L7 |
| GPIOH0 | OTHERS | BUS | 1 | 4.75 | 5 | 10 | 5 | 14 | 6 | 9.5 | 12 | 12 | 12 | 12 |  | 50 Ohms | TOP=L2:L3=L2/L4:L6=L5/L7:BOTTOM=L7 |
| GPIOH0 | OTHERS | BUS | 2 | 5 | 5 | 10 | 5 | 14 | 6 | 10 | 12 | 12 | 12 | 12 |  | 50 Ohms | TOP=L2:L3=L2/L4:L6=L5/L7:BOTTOM=L7 |
| GPIOH0 | OTHERS | BUS | 3 | 5 | 5 | 10 | 5 | 14 | 6 | 10 | 12 | 12 | 12 | 12 |  | 50 Ohms | TOP=L2:L3=L2/L4:L6=L5/L7:BOTTOM=L7 |
| GPIOH0 | OTHERS | BUS | 4 | 5 | 5 | 10 | 5 | 14 | 6 | 10 | 12 | 12 | 12 | 12 |  | 50 Ohms | TOP=L2:L3=L2/L4:L6=L5/L7:BOTTOM=L7 |
| GPIOH0 | OTHERS | BUS | 5 | 5 | 5 | 10 | 5 | 14 | 6 | 10 | 12 | 12 | 12 | 12 |  | 50 Ohms | TOP=L2:L3=L2/L4:L6=L5/L7:BOTTOM=L7 |
| GPIOH0 | OTHERS | BUS | 6 | 5 | 5 | 10 | 5 | 14 | 6 | 10 | 12 | 12 | 12 | 12 |  | 50 Ohms | TOP=L2:L3=L2/L4:L6=L5/L7:BOTTOM=L7 |
| GPIOH0 | OTHERS | BUS | 7 | 5 | 5 | 10 | 5 | 14 | 6 | 10 | 12 | 12 | 12 | 12 |  | 50 Ohms | TOP=L2:L3=L2/L4:L6=L5/L7:BOTTOM=L7 |
| GPIOH0 | OTHERS | BUS | 8 | 4.75 | 5 | 10 | 5 | 14 | 6 | 9.5 | 12 | 12 | 12 | 12 |  | 50 Ohms | TOP=L2:L3=L2/L4:L6=L5/L7:BOTTOM=L7 |
| GPIOH2 | OTHERS | BUS | 1 | 4.75 | 5 | 10 | 5 | 14 | 6 | 9.5 | 12 | 12 | 12 | 12 |  | 50 Ohms | TOP=L2:L3=L2/L4:L6=L5/L7:BOTTOM=L7 |
| GPIOH2 | OTHERS | BUS | 2 | 5 | 5 | 10 | 5 | 14 | 6 | 10 | 12 | 12 | 12 | 12 |  | 50 Ohms | TOP=L2:L3=L2/L4:L6=L5/L7:BOTTOM=L7 |
| GPIOH2 | OTHERS | BUS | 3 | 5 | 5 | 10 | 5 | 14 | 6 | 10 | 12 | 12 | 12 | 12 |  | 50 Ohms | TOP=L2:L3=L2/L4:L6=L5/L7:BOTTOM=L7 |
| GPIOH2 | OTHERS | BUS | 4 | 5 | 5 | 10 | 5 | 14 | 6 | 10 | 12 | 12 | 12 | 12 |  | 50 Ohms | TOP=L2:L3=L2/L4:L6=L5/L7:BOTTOM=L7 |
| GPIOH2 | OTHERS | BUS | 5 | 5 | 5 | 10 | 5 | 14 | 6 | 10 | 12 | 12 | 12 | 12 |  | 50 Ohms | TOP=L2:L3=L2/L4:L6=L5/L7:BOTTOM=L7 |
| GPIOH2 | OTHERS | BUS | 6 | 5 | 5 | 10 | 5 | 14 | 6 | 10 | 12 | 12 | 12 | 12 |  | 50 Ohms | TOP=L2:L3=L2/L4:L6=L5/L7:BOTTOM=L7 |
| GPIOH2 | OTHERS | BUS | 7 | 5 | 5 | 10 | 5 | 14 | 6 | 10 | 12 | 12 | 12 | 12 |  | 50 Ohms | TOP=L2:L3=L2/L4:L6=L5/L7:BOTTOM=L7 |
| GPIOH2 | OTHERS | BUS | 8 | 4.75 | 5 | 10 | 5 | 14 | 6 | 9.5 | 12 | 12 | 12 | 12 |  | 50 Ohms | TOP=L2:L3=L2/L4:L6=L5/L7:BOTTOM=L7 |
| GPIOH2_R | OTHERS | BUS | 1 | 4.75 | 5 | 10 | 5 | 14 | 6 | 9.5 | 12 | 12 | 12 | 12 |  | 50 Ohms | TOP=L2:L3=L2/L4:L6=L5/L7:BOTTOM=L7 |
| GPIOH2_R | OTHERS | BUS | 2 | 5 | 5 | 10 | 5 | 14 | 6 | 10 | 12 | 12 | 12 | 12 |  | 50 Ohms | TOP=L2:L3=L2/L4:L6=L5/L7:BOTTOM=L7 |
| GPIOH2_R | OTHERS | BUS | 3 | 5 | 5 | 10 | 5 | 14 | 6 | 10 | 12 | 12 | 12 | 12 |  | 50 Ohms | TOP=L2:L3=L2/L4:L6=L5/L7:BOTTOM=L7 |
| GPIOH2_R | OTHERS | BUS | 4 | 5 | 5 | 10 | 5 | 14 | 6 | 10 | 12 | 12 | 12 | 12 |  | 50 Ohms | TOP=L2:L3=L2/L4:L6=L5/L7:BOTTOM=L7 |
| GPIOH2_R | OTHERS | BUS | 5 | 5 | 5 | 10 | 5 | 14 | 6 | 10 | 12 | 12 | 12 | 12 |  | 50 Ohms | TOP=L2:L3=L2/L4:L6=L5/L7:BOTTOM=L7 |
| GPIOH2_R | OTHERS | BUS | 6 | 5 | 5 | 10 | 5 | 14 | 6 | 10 | 12 | 12 | 12 | 12 |  | 50 Ohms | TOP=L2:L3=L2/L4:L6=L5/L7:BOTTOM=L7 |
| GPIOH2_R | OTHERS | BUS | 7 | 5 | 5 | 10 | 5 | 14 | 6 | 10 | 12 | 12 | 12 | 12 |  | 50 Ohms | TOP=L2:L3=L2/L4:L6=L5/L7:BOTTOM=L7 |
| GPIOH2_R | OTHERS | BUS | 8 | 4.75 | 5 | 10 | 5 | 14 | 6 | 9.5 | 12 | 12 | 12 | 12 |  | 50 Ohms | TOP=L2:L3=L2/L4:L6=L5/L7:BOTTOM=L7 |
| GPIOM0_I210_PERST_N | OTHERS | BUS | 1 | 4.75 | 5 | 10 | 5 | 14 | 6 | 9.5 | 12 | 12 | 12 | 12 |  | 50 Ohms | TOP=L2:L3=L2/L4:L6=L5/L7:BOTTOM=L7 |
| GPIOM0_I210_PERST_N | OTHERS | BUS | 2 | 5 | 5 | 10 | 5 | 14 | 6 | 10 | 12 | 12 | 12 | 12 |  | 50 Ohms | TOP=L2:L3=L2/L4:L6=L5/L7:BOTTOM=L7 |
| GPIOM0_I210_PERST_N | OTHERS | BUS | 3 | 5 | 5 | 10 | 5 | 14 | 6 | 10 | 12 | 12 | 12 | 12 |  | 50 Ohms | TOP=L2:L3=L2/L4:L6=L5/L7:BOTTOM=L7 |
| GPIOM0_I210_PERST_N | OTHERS | BUS | 4 | 5 | 5 | 10 | 5 | 14 | 6 | 10 | 12 | 12 | 12 | 12 |  | 50 Ohms | TOP=L2:L3=L2/L4:L6=L5/L7:BOTTOM=L7 |
| GPIOM0_I210_PERST_N | OTHERS | BUS | 5 | 5 | 5 | 10 | 5 | 14 | 6 | 10 | 12 | 12 | 12 | 12 |  | 50 Ohms | TOP=L2:L3=L2/L4:L6=L5/L7:BOTTOM=L7 |
| GPIOM0_I210_PERST_N | OTHERS | BUS | 6 | 5 | 5 | 10 | 5 | 14 | 6 | 10 | 12 | 12 | 12 | 12 |  | 50 Ohms | TOP=L2:L3=L2/L4:L6=L5/L7:BOTTOM=L7 |
| GPIOM0_I210_PERST_N | OTHERS | BUS | 7 | 5 | 5 | 10 | 5 | 14 | 6 | 10 | 12 | 12 | 12 | 12 |  | 50 Ohms | TOP=L2:L3=L2/L4:L6=L5/L7:BOTTOM=L7 |
| GPIOM0_I210_PERST_N | OTHERS | BUS | 8 | 4.75 | 5 | 10 | 5 | 14 | 6 | 9.5 | 12 | 12 | 12 | 12 |  | 50 Ohms | TOP=L2:L3=L2/L4:L6=L5/L7:BOTTOM=L7 |
| GPIOR1_R | OTHERS | BUS | 1 | 4.75 | 5 | 10 | 5 | 14 | 6 | 9.5 | 12 | 12 | 12 | 12 |  | 50 Ohms | TOP=L2:L3=L2/L4:L6=L5/L7:BOTTOM=L7 |
| GPIOR1_R | OTHERS | BUS | 2 | 5 | 5 | 10 | 5 | 14 | 6 | 10 | 12 | 12 | 12 | 12 |  | 50 Ohms | TOP=L2:L3=L2/L4:L6=L5/L7:BOTTOM=L7 |
| GPIOR1_R | OTHERS | BUS | 3 | 5 | 5 | 10 | 5 | 14 | 6 | 10 | 12 | 12 | 12 | 12 |  | 50 Ohms | TOP=L2:L3=L2/L4:L6=L5/L7:BOTTOM=L7 |
| GPIOR1_R | OTHERS | BUS | 4 | 5 | 5 | 10 | 5 | 14 | 6 | 10 | 12 | 12 | 12 | 12 |  | 50 Ohms | TOP=L2:L3=L2/L4:L6=L5/L7:BOTTOM=L7 |
| GPIOR1_R | OTHERS | BUS | 5 | 5 | 5 | 10 | 5 | 14 | 6 | 10 | 12 | 12 | 12 | 12 |  | 50 Ohms | TOP=L2:L3=L2/L4:L6=L5/L7:BOTTOM=L7 |
| GPIOR1_R | OTHERS | BUS | 6 | 5 | 5 | 10 | 5 | 14 | 6 | 10 | 12 | 12 | 12 | 12 |  | 50 Ohms | TOP=L2:L3=L2/L4:L6=L5/L7:BOTTOM=L7 |
| GPIOR1_R | OTHERS | BUS | 7 | 5 | 5 | 10 | 5 | 14 | 6 | 10 | 12 | 12 | 12 | 12 |  | 50 Ohms | TOP=L2:L3=L2/L4:L6=L5/L7:BOTTOM=L7 |
| GPIOR1_R | OTHERS | BUS | 8 | 4.75 | 5 | 10 | 5 | 14 | 6 | 9.5 | 12 | 12 | 12 | 12 |  | 50 Ohms | TOP=L2:L3=L2/L4:L6=L5/L7:BOTTOM=L7 |
| GPIOR2_R | OTHERS | BUS | 1 | 4.75 | 5 | 10 | 5 | 14 | 6 | 9.5 | 12 | 12 | 12 | 12 |  | 50 Ohms | TOP=L2:L3=L2/L4:L6=L5/L7:BOTTOM=L7 |
| GPIOR2_R | OTHERS | BUS | 2 | 5 | 5 | 10 | 5 | 14 | 6 | 10 | 12 | 12 | 12 | 12 |  | 50 Ohms | TOP=L2:L3=L2/L4:L6=L5/L7:BOTTOM=L7 |
| GPIOR2_R | OTHERS | BUS | 3 | 5 | 5 | 10 | 5 | 14 | 6 | 10 | 12 | 12 | 12 | 12 |  | 50 Ohms | TOP=L2:L3=L2/L4:L6=L5/L7:BOTTOM=L7 |
| GPIOR2_R | OTHERS | BUS | 4 | 5 | 5 | 10 | 5 | 14 | 6 | 10 | 12 | 12 | 12 | 12 |  | 50 Ohms | TOP=L2:L3=L2/L4:L6=L5/L7:BOTTOM=L7 |
| GPIOR2_R | OTHERS | BUS | 5 | 5 | 5 | 10 | 5 | 14 | 6 | 10 | 12 | 12 | 12 | 12 |  | 50 Ohms | TOP=L2:L3=L2/L4:L6=L5/L7:BOTTOM=L7 |
| GPIOR2_R | OTHERS | BUS | 6 | 5 | 5 | 10 | 5 | 14 | 6 | 10 | 12 | 12 | 12 | 12 |  | 50 Ohms | TOP=L2:L3=L2/L4:L6=L5/L7:BOTTOM=L7 |
| GPIOR2_R | OTHERS | BUS | 7 | 5 | 5 | 10 | 5 | 14 | 6 | 10 | 12 | 12 | 12 | 12 |  | 50 Ohms | TOP=L2:L3=L2/L4:L6=L5/L7:BOTTOM=L7 |
| GPIOR2_R | OTHERS | BUS | 8 | 4.75 | 5 | 10 | 5 | 14 | 6 | 9.5 | 12 | 12 | 12 | 12 |  | 50 Ohms | TOP=L2:L3=L2/L4:L6=L5/L7:BOTTOM=L7 |
| GPIOR3_R | OTHERS | BUS | 1 | 4.75 | 5 | 10 | 5 | 14 | 6 | 9.5 | 12 | 12 | 12 | 12 |  | 50 Ohms | TOP=L2:L3=L2/L4:L6=L5/L7:BOTTOM=L7 |
| GPIOR3_R | OTHERS | BUS | 2 | 5 | 5 | 10 | 5 | 14 | 6 | 10 | 12 | 12 | 12 | 12 |  | 50 Ohms | TOP=L2:L3=L2/L4:L6=L5/L7:BOTTOM=L7 |
| GPIOR3_R | OTHERS | BUS | 3 | 5 | 5 | 10 | 5 | 14 | 6 | 10 | 12 | 12 | 12 | 12 |  | 50 Ohms | TOP=L2:L3=L2/L4:L6=L5/L7:BOTTOM=L7 |
| GPIOR3_R | OTHERS | BUS | 4 | 5 | 5 | 10 | 5 | 14 | 6 | 10 | 12 | 12 | 12 | 12 |  | 50 Ohms | TOP=L2:L3=L2/L4:L6=L5/L7:BOTTOM=L7 |
| GPIOR3_R | OTHERS | BUS | 5 | 5 | 5 | 10 | 5 | 14 | 6 | 10 | 12 | 12 | 12 | 12 |  | 50 Ohms | TOP=L2:L3=L2/L4:L6=L5/L7:BOTTOM=L7 |
| GPIOR3_R | OTHERS | BUS | 6 | 5 | 5 | 10 | 5 | 14 | 6 | 10 | 12 | 12 | 12 | 12 |  | 50 Ohms | TOP=L2:L3=L2/L4:L6=L5/L7:BOTTOM=L7 |
| GPIOR3_R | OTHERS | BUS | 7 | 5 | 5 | 10 | 5 | 14 | 6 | 10 | 12 | 12 | 12 | 12 |  | 50 Ohms | TOP=L2:L3=L2/L4:L6=L5/L7:BOTTOM=L7 |
| GPIOR3_R | OTHERS | BUS | 8 | 4.75 | 5 | 10 | 5 | 14 | 6 | 9.5 | 12 | 12 | 12 | 12 |  | 50 Ohms | TOP=L2:L3=L2/L4:L6=L5/L7:BOTTOM=L7 |
| GPIOR4_BMC_INT_N_R | OTHERS | BUS | 1 | 4.75 | 5 | 10 | 5 | 14 | 6 | 9.5 | 12 | 12 | 12 | 12 |  | 50 Ohms | TOP=L2:L3=L2/L4:L6=L5/L7:BOTTOM=L7 |
| GPIOR4_BMC_INT_N_R | OTHERS | BUS | 2 | 5 | 5 | 10 | 5 | 14 | 6 | 10 | 12 | 12 | 12 | 12 |  | 50 Ohms | TOP=L2:L3=L2/L4:L6=L5/L7:BOTTOM=L7 |
| GPIOR4_BMC_INT_N_R | OTHERS | BUS | 3 | 5 | 5 | 10 | 5 | 14 | 6 | 10 | 12 | 12 | 12 | 12 |  | 50 Ohms | TOP=L2:L3=L2/L4:L6=L5/L7:BOTTOM=L7 |
| GPIOR4_BMC_INT_N_R | OTHERS | BUS | 4 | 5 | 5 | 10 | 5 | 14 | 6 | 10 | 12 | 12 | 12 | 12 |  | 50 Ohms | TOP=L2:L3=L2/L4:L6=L5/L7:BOTTOM=L7 |
| GPIOR4_BMC_INT_N_R | OTHERS | BUS | 5 | 5 | 5 | 10 | 5 | 14 | 6 | 10 | 12 | 12 | 12 | 12 |  | 50 Ohms | TOP=L2:L3=L2/L4:L6=L5/L7:BOTTOM=L7 |
| GPIOR4_BMC_INT_N_R | OTHERS | BUS | 6 | 5 | 5 | 10 | 5 | 14 | 6 | 10 | 12 | 12 | 12 | 12 |  | 50 Ohms | TOP=L2:L3=L2/L4:L6=L5/L7:BOTTOM=L7 |
| GPIOR4_BMC_INT_N_R | OTHERS | BUS | 7 | 5 | 5 | 10 | 5 | 14 | 6 | 10 | 12 | 12 | 12 | 12 |  | 50 Ohms | TOP=L2:L3=L2/L4:L6=L5/L7:BOTTOM=L7 |
| GPIOR4_BMC_INT_N_R | OTHERS | BUS | 8 | 4.75 | 5 | 10 | 5 | 14 | 6 | 9.5 | 12 | 12 | 12 | 12 |  | 50 Ohms | TOP=L2:L3=L2/L4:L6=L5/L7:BOTTOM=L7 |
| GPIOR5_R | OTHERS | BUS | 1 | 4.75 | 5 | 10 | 5 | 14 | 6 | 9.5 | 12 | 12 | 12 | 12 |  | 50 Ohms | TOP=L2:L3=L2/L4:L6=L5/L7:BOTTOM=L7 |
| GPIOR5_R | OTHERS | BUS | 2 | 5 | 5 | 10 | 5 | 14 | 6 | 10 | 12 | 12 | 12 | 12 |  | 50 Ohms | TOP=L2:L3=L2/L4:L6=L5/L7:BOTTOM=L7 |
| GPIOR5_R | OTHERS | BUS | 3 | 5 | 5 | 10 | 5 | 14 | 6 | 10 | 12 | 12 | 12 | 12 |  | 50 Ohms | TOP=L2:L3=L2/L4:L6=L5/L7:BOTTOM=L7 |
| GPIOR5_R | OTHERS | BUS | 4 | 5 | 5 | 10 | 5 | 14 | 6 | 10 | 12 | 12 | 12 | 12 |  | 50 Ohms | TOP=L2:L3=L2/L4:L6=L5/L7:BOTTOM=L7 |
| GPIOR5_R | OTHERS | BUS | 5 | 5 | 5 | 10 | 5 | 14 | 6 | 10 | 12 | 12 | 12 | 12 |  | 50 Ohms | TOP=L2:L3=L2/L4:L6=L5/L7:BOTTOM=L7 |
| GPIOR5_R | OTHERS | BUS | 6 | 5 | 5 | 10 | 5 | 14 | 6 | 10 | 12 | 12 | 12 | 12 |  | 50 Ohms | TOP=L2:L3=L2/L4:L6=L5/L7:BOTTOM=L7 |
| GPIOR5_R | OTHERS | BUS | 7 | 5 | 5 | 10 | 5 | 14 | 6 | 10 | 12 | 12 | 12 | 12 |  | 50 Ohms | TOP=L2:L3=L2/L4:L6=L5/L7:BOTTOM=L7 |
| GPIOR5_R | OTHERS | BUS | 8 | 4.75 | 5 | 10 | 5 | 14 | 6 | 9.5 | 12 | 12 | 12 | 12 |  | 50 Ohms | TOP=L2:L3=L2/L4:L6=L5/L7:BOTTOM=L7 |
| GPIOS5_R | OTHERS | BUS | 1 | 4.75 | 5 | 10 | 5 | 14 | 6 | 9.5 | 12 | 12 | 12 | 12 |  | 50 Ohms | TOP=L2:L3=L2/L4:L6=L5/L7:BOTTOM=L7 |
| GPIOS5_R | OTHERS | BUS | 2 | 5 | 5 | 10 | 5 | 14 | 6 | 10 | 12 | 12 | 12 | 12 |  | 50 Ohms | TOP=L2:L3=L2/L4:L6=L5/L7:BOTTOM=L7 |
| GPIOS5_R | OTHERS | BUS | 3 | 5 | 5 | 10 | 5 | 14 | 6 | 10 | 12 | 12 | 12 | 12 |  | 50 Ohms | TOP=L2:L3=L2/L4:L6=L5/L7:BOTTOM=L7 |
| GPIOS5_R | OTHERS | BUS | 4 | 5 | 5 | 10 | 5 | 14 | 6 | 10 | 12 | 12 | 12 | 12 |  | 50 Ohms | TOP=L2:L3=L2/L4:L6=L5/L7:BOTTOM=L7 |
| GPIOS5_R | OTHERS | BUS | 5 | 5 | 5 | 10 | 5 | 14 | 6 | 10 | 12 | 12 | 12 | 12 |  | 50 Ohms | TOP=L2:L3=L2/L4:L6=L5/L7:BOTTOM=L7 |
| GPIOS5_R | OTHERS | BUS | 6 | 5 | 5 | 10 | 5 | 14 | 6 | 10 | 12 | 12 | 12 | 12 |  | 50 Ohms | TOP=L2:L3=L2/L4:L6=L5/L7:BOTTOM=L7 |
| GPIOS5_R | OTHERS | BUS | 7 | 5 | 5 | 10 | 5 | 14 | 6 | 10 | 12 | 12 | 12 | 12 |  | 50 Ohms | TOP=L2:L3=L2/L4:L6=L5/L7:BOTTOM=L7 |
| GPIOS5_R | OTHERS | BUS | 8 | 4.75 | 5 | 10 | 5 | 14 | 6 | 9.5 | 12 | 12 | 12 | 12 |  | 50 Ohms | TOP=L2:L3=L2/L4:L6=L5/L7:BOTTOM=L7 |
| HB_A_IN | OTHERS | BUS | 1 | 4.75 | 5 | 10 | 5 | 14 | 6 | 9.5 | 12 | 12 | 12 | 12 |  | 50 Ohms | TOP=L2:L3=L2/L4:L6=L5/L7:BOTTOM=L7 |
| HB_A_IN | OTHERS | BUS | 2 | 5 | 5 | 10 | 5 | 14 | 6 | 10 | 12 | 12 | 12 | 12 |  | 50 Ohms | TOP=L2:L3=L2/L4:L6=L5/L7:BOTTOM=L7 |
| HB_A_IN | OTHERS | BUS | 3 | 5 | 5 | 10 | 5 | 14 | 6 | 10 | 12 | 12 | 12 | 12 |  | 50 Ohms | TOP=L2:L3=L2/L4:L6=L5/L7:BOTTOM=L7 |
| HB_A_IN | OTHERS | BUS | 4 | 5 | 5 | 10 | 5 | 14 | 6 | 10 | 12 | 12 | 12 | 12 |  | 50 Ohms | TOP=L2:L3=L2/L4:L6=L5/L7:BOTTOM=L7 |
| HB_A_IN | OTHERS | BUS | 5 | 5 | 5 | 10 | 5 | 14 | 6 | 10 | 12 | 12 | 12 | 12 |  | 50 Ohms | TOP=L2:L3=L2/L4:L6=L5/L7:BOTTOM=L7 |
| HB_A_IN | OTHERS | BUS | 6 | 5 | 5 | 10 | 5 | 14 | 6 | 10 | 12 | 12 | 12 | 12 |  | 50 Ohms | TOP=L2:L3=L2/L4:L6=L5/L7:BOTTOM=L7 |
| HB_A_IN | OTHERS | BUS | 7 | 5 | 5 | 10 | 5 | 14 | 6 | 10 | 12 | 12 | 12 | 12 |  | 50 Ohms | TOP=L2:L3=L2/L4:L6=L5/L7:BOTTOM=L7 |
| HB_A_IN | OTHERS | BUS | 8 | 4.75 | 5 | 10 | 5 | 14 | 6 | 9.5 | 12 | 12 | 12 | 12 |  | 50 Ohms | TOP=L2:L3=L2/L4:L6=L5/L7:BOTTOM=L7 |
| HB_A_OUT | OTHERS | BUS | 1 | 4.75 | 5 | 10 | 5 | 14 | 6 | 9.5 | 12 | 12 | 12 | 12 |  | 50 Ohms | TOP=L2:L3=L2/L4:L6=L5/L7:BOTTOM=L7 |
| HB_A_OUT | OTHERS | BUS | 2 | 5 | 5 | 10 | 5 | 14 | 6 | 10 | 12 | 12 | 12 | 12 |  | 50 Ohms | TOP=L2:L3=L2/L4:L6=L5/L7:BOTTOM=L7 |
| HB_A_OUT | OTHERS | BUS | 3 | 5 | 5 | 10 | 5 | 14 | 6 | 10 | 12 | 12 | 12 | 12 |  | 50 Ohms | TOP=L2:L3=L2/L4:L6=L5/L7:BOTTOM=L7 |
| HB_A_OUT | OTHERS | BUS | 4 | 5 | 5 | 10 | 5 | 14 | 6 | 10 | 12 | 12 | 12 | 12 |  | 50 Ohms | TOP=L2:L3=L2/L4:L6=L5/L7:BOTTOM=L7 |
| HB_A_OUT | OTHERS | BUS | 5 | 5 | 5 | 10 | 5 | 14 | 6 | 10 | 12 | 12 | 12 | 12 |  | 50 Ohms | TOP=L2:L3=L2/L4:L6=L5/L7:BOTTOM=L7 |
| HB_A_OUT | OTHERS | BUS | 6 | 5 | 5 | 10 | 5 | 14 | 6 | 10 | 12 | 12 | 12 | 12 |  | 50 Ohms | TOP=L2:L3=L2/L4:L6=L5/L7:BOTTOM=L7 |
| HB_A_OUT | OTHERS | BUS | 7 | 5 | 5 | 10 | 5 | 14 | 6 | 10 | 12 | 12 | 12 | 12 |  | 50 Ohms | TOP=L2:L3=L2/L4:L6=L5/L7:BOTTOM=L7 |
| HB_A_OUT | OTHERS | BUS | 8 | 4.75 | 5 | 10 | 5 | 14 | 6 | 9.5 | 12 | 12 | 12 | 12 |  | 50 Ohms | TOP=L2:L3=L2/L4:L6=L5/L7:BOTTOM=L7 |
| HB_OUT | OTHERS | BUS | 1 | 4.75 | 5 | 10 | 5 | 14 | 6 | 9.5 | 12 | 12 | 12 | 12 |  | 50 Ohms | TOP=L2:L3=L2/L4:L6=L5/L7:BOTTOM=L7 |
| HB_OUT | OTHERS | BUS | 2 | 5 | 5 | 10 | 5 | 14 | 6 | 10 | 12 | 12 | 12 | 12 |  | 50 Ohms | TOP=L2:L3=L2/L4:L6=L5/L7:BOTTOM=L7 |
| HB_OUT | OTHERS | BUS | 3 | 5 | 5 | 10 | 5 | 14 | 6 | 10 | 12 | 12 | 12 | 12 |  | 50 Ohms | TOP=L2:L3=L2/L4:L6=L5/L7:BOTTOM=L7 |
| HB_OUT | OTHERS | BUS | 4 | 5 | 5 | 10 | 5 | 14 | 6 | 10 | 12 | 12 | 12 | 12 |  | 50 Ohms | TOP=L2:L3=L2/L4:L6=L5/L7:BOTTOM=L7 |
| HB_OUT | OTHERS | BUS | 5 | 5 | 5 | 10 | 5 | 14 | 6 | 10 | 12 | 12 | 12 | 12 |  | 50 Ohms | TOP=L2:L3=L2/L4:L6=L5/L7:BOTTOM=L7 |
| HB_OUT | OTHERS | BUS | 6 | 5 | 5 | 10 | 5 | 14 | 6 | 10 | 12 | 12 | 12 | 12 |  | 50 Ohms | TOP=L2:L3=L2/L4:L6=L5/L7:BOTTOM=L7 |
| HB_OUT | OTHERS | BUS | 7 | 5 | 5 | 10 | 5 | 14 | 6 | 10 | 12 | 12 | 12 | 12 |  | 50 Ohms | TOP=L2:L3=L2/L4:L6=L5/L7:BOTTOM=L7 |
| HB_OUT | OTHERS | BUS | 8 | 4.75 | 5 | 10 | 5 | 14 | 6 | 9.5 | 12 | 12 | 12 | 12 |  | 50 Ohms | TOP=L2:L3=L2/L4:L6=L5/L7:BOTTOM=L7 |
| HB_OUT_BMC | OTHERS | BUS | 1 | 4.75 | 5 | 10 | 5 | 14 | 6 | 9.5 | 12 | 12 | 12 | 12 |  | 50 Ohms | TOP=L2:L3=L2/L4:L6=L5/L7:BOTTOM=L7 |
| HB_OUT_BMC | OTHERS | BUS | 2 | 5 | 5 | 10 | 5 | 14 | 6 | 10 | 12 | 12 | 12 | 12 |  | 50 Ohms | TOP=L2:L3=L2/L4:L6=L5/L7:BOTTOM=L7 |
| HB_OUT_BMC | OTHERS | BUS | 3 | 5 | 5 | 10 | 5 | 14 | 6 | 10 | 12 | 12 | 12 | 12 |  | 50 Ohms | TOP=L2:L3=L2/L4:L6=L5/L7:BOTTOM=L7 |
| HB_OUT_BMC | OTHERS | BUS | 4 | 5 | 5 | 10 | 5 | 14 | 6 | 10 | 12 | 12 | 12 | 12 |  | 50 Ohms | TOP=L2:L3=L2/L4:L6=L5/L7:BOTTOM=L7 |
| HB_OUT_BMC | OTHERS | BUS | 5 | 5 | 5 | 10 | 5 | 14 | 6 | 10 | 12 | 12 | 12 | 12 |  | 50 Ohms | TOP=L2:L3=L2/L4:L6=L5/L7:BOTTOM=L7 |
| HB_OUT_BMC | OTHERS | BUS | 6 | 5 | 5 | 10 | 5 | 14 | 6 | 10 | 12 | 12 | 12 | 12 |  | 50 Ohms | TOP=L2:L3=L2/L4:L6=L5/L7:BOTTOM=L7 |
| HB_OUT_BMC | OTHERS | BUS | 7 | 5 | 5 | 10 | 5 | 14 | 6 | 10 | 12 | 12 | 12 | 12 |  | 50 Ohms | TOP=L2:L3=L2/L4:L6=L5/L7:BOTTOM=L7 |
| HB_OUT_BMC | OTHERS | BUS | 8 | 4.75 | 5 | 10 | 5 | 14 | 6 | 9.5 | 12 | 12 | 12 | 12 |  | 50 Ohms | TOP=L2:L3=L2/L4:L6=L5/L7:BOTTOM=L7 |
| HB_OUT_R | OTHERS | BUS | 1 | 4.75 | 5 | 10 | 5 | 14 | 6 | 9.5 | 12 | 12 | 12 | 12 |  | 50 Ohms | TOP=L2:L3=L2/L4:L6=L5/L7:BOTTOM=L7 |
| HB_OUT_R | OTHERS | BUS | 2 | 5 | 5 | 10 | 5 | 14 | 6 | 10 | 12 | 12 | 12 | 12 |  | 50 Ohms | TOP=L2:L3=L2/L4:L6=L5/L7:BOTTOM=L7 |
| HB_OUT_R | OTHERS | BUS | 3 | 5 | 5 | 10 | 5 | 14 | 6 | 10 | 12 | 12 | 12 | 12 |  | 50 Ohms | TOP=L2:L3=L2/L4:L6=L5/L7:BOTTOM=L7 |
| HB_OUT_R | OTHERS | BUS | 4 | 5 | 5 | 10 | 5 | 14 | 6 | 10 | 12 | 12 | 12 | 12 |  | 50 Ohms | TOP=L2:L3=L2/L4:L6=L5/L7:BOTTOM=L7 |
| HB_OUT_R | OTHERS | BUS | 5 | 5 | 5 | 10 | 5 | 14 | 6 | 10 | 12 | 12 | 12 | 12 |  | 50 Ohms | TOP=L2:L3=L2/L4:L6=L5/L7:BOTTOM=L7 |
| HB_OUT_R | OTHERS | BUS | 6 | 5 | 5 | 10 | 5 | 14 | 6 | 10 | 12 | 12 | 12 | 12 |  | 50 Ohms | TOP=L2:L3=L2/L4:L6=L5/L7:BOTTOM=L7 |
| HB_OUT_R | OTHERS | BUS | 7 | 5 | 5 | 10 | 5 | 14 | 6 | 10 | 12 | 12 | 12 | 12 |  | 50 Ohms | TOP=L2:L3=L2/L4:L6=L5/L7:BOTTOM=L7 |
| HB_OUT_R | OTHERS | BUS | 8 | 4.75 | 5 | 10 | 5 | 14 | 6 | 9.5 | 12 | 12 | 12 | 12 |  | 50 Ohms | TOP=L2:L3=L2/L4:L6=L5/L7:BOTTOM=L7 |
| HIGH_HEX_0 | OTHERS | BUS | 1 | 4.75 | 5 | 10 | 5 | 14 | 6 | 9.5 | 12 | 12 | 12 | 12 |  | 50 Ohms | TOP=L2:L3=L2/L4:L6=L5/L7:BOTTOM=L7 |
| HIGH_HEX_0 | OTHERS | BUS | 2 | 5 | 5 | 10 | 5 | 14 | 6 | 10 | 12 | 12 | 12 | 12 |  | 50 Ohms | TOP=L2:L3=L2/L4:L6=L5/L7:BOTTOM=L7 |
| HIGH_HEX_0 | OTHERS | BUS | 3 | 5 | 5 | 10 | 5 | 14 | 6 | 10 | 12 | 12 | 12 | 12 |  | 50 Ohms | TOP=L2:L3=L2/L4:L6=L5/L7:BOTTOM=L7 |
| HIGH_HEX_0 | OTHERS | BUS | 4 | 5 | 5 | 10 | 5 | 14 | 6 | 10 | 12 | 12 | 12 | 12 |  | 50 Ohms | TOP=L2:L3=L2/L4:L6=L5/L7:BOTTOM=L7 |
| HIGH_HEX_0 | OTHERS | BUS | 5 | 5 | 5 | 10 | 5 | 14 | 6 | 10 | 12 | 12 | 12 | 12 |  | 50 Ohms | TOP=L2:L3=L2/L4:L6=L5/L7:BOTTOM=L7 |
| HIGH_HEX_0 | OTHERS | BUS | 6 | 5 | 5 | 10 | 5 | 14 | 6 | 10 | 12 | 12 | 12 | 12 |  | 50 Ohms | TOP=L2:L3=L2/L4:L6=L5/L7:BOTTOM=L7 |
| HIGH_HEX_0 | OTHERS | BUS | 7 | 5 | 5 | 10 | 5 | 14 | 6 | 10 | 12 | 12 | 12 | 12 |  | 50 Ohms | TOP=L2:L3=L2/L4:L6=L5/L7:BOTTOM=L7 |
| HIGH_HEX_0 | OTHERS | BUS | 8 | 4.75 | 5 | 10 | 5 | 14 | 6 | 9.5 | 12 | 12 | 12 | 12 |  | 50 Ohms | TOP=L2:L3=L2/L4:L6=L5/L7:BOTTOM=L7 |
| HIGH_HEX_1 | OTHERS | BUS | 1 | 4.75 | 5 | 10 | 5 | 14 | 6 | 9.5 | 12 | 12 | 12 | 12 |  | 50 Ohms | TOP=L2:L3=L2/L4:L6=L5/L7:BOTTOM=L7 |
| HIGH_HEX_1 | OTHERS | BUS | 2 | 5 | 5 | 10 | 5 | 14 | 6 | 10 | 12 | 12 | 12 | 12 |  | 50 Ohms | TOP=L2:L3=L2/L4:L6=L5/L7:BOTTOM=L7 |
| HIGH_HEX_1 | OTHERS | BUS | 3 | 5 | 5 | 10 | 5 | 14 | 6 | 10 | 12 | 12 | 12 | 12 |  | 50 Ohms | TOP=L2:L3=L2/L4:L6=L5/L7:BOTTOM=L7 |
| HIGH_HEX_1 | OTHERS | BUS | 4 | 5 | 5 | 10 | 5 | 14 | 6 | 10 | 12 | 12 | 12 | 12 |  | 50 Ohms | TOP=L2:L3=L2/L4:L6=L5/L7:BOTTOM=L7 |
| HIGH_HEX_1 | OTHERS | BUS | 5 | 5 | 5 | 10 | 5 | 14 | 6 | 10 | 12 | 12 | 12 | 12 |  | 50 Ohms | TOP=L2:L3=L2/L4:L6=L5/L7:BOTTOM=L7 |
| HIGH_HEX_1 | OTHERS | BUS | 6 | 5 | 5 | 10 | 5 | 14 | 6 | 10 | 12 | 12 | 12 | 12 |  | 50 Ohms | TOP=L2:L3=L2/L4:L6=L5/L7:BOTTOM=L7 |
| HIGH_HEX_1 | OTHERS | BUS | 7 | 5 | 5 | 10 | 5 | 14 | 6 | 10 | 12 | 12 | 12 | 12 |  | 50 Ohms | TOP=L2:L3=L2/L4:L6=L5/L7:BOTTOM=L7 |
| HIGH_HEX_1 | OTHERS | BUS | 8 | 4.75 | 5 | 10 | 5 | 14 | 6 | 9.5 | 12 | 12 | 12 | 12 |  | 50 Ohms | TOP=L2:L3=L2/L4:L6=L5/L7:BOTTOM=L7 |
| HIGH_HEX_2 | OTHERS | BUS | 1 | 4.75 | 5 | 10 | 5 | 14 | 6 | 9.5 | 12 | 12 | 12 | 12 |  | 50 Ohms | TOP=L2:L3=L2/L4:L6=L5/L7:BOTTOM=L7 |
| HIGH_HEX_2 | OTHERS | BUS | 2 | 5 | 5 | 10 | 5 | 14 | 6 | 10 | 12 | 12 | 12 | 12 |  | 50 Ohms | TOP=L2:L3=L2/L4:L6=L5/L7:BOTTOM=L7 |
| HIGH_HEX_2 | OTHERS | BUS | 3 | 5 | 5 | 10 | 5 | 14 | 6 | 10 | 12 | 12 | 12 | 12 |  | 50 Ohms | TOP=L2:L3=L2/L4:L6=L5/L7:BOTTOM=L7 |
| HIGH_HEX_2 | OTHERS | BUS | 4 | 5 | 5 | 10 | 5 | 14 | 6 | 10 | 12 | 12 | 12 | 12 |  | 50 Ohms | TOP=L2:L3=L2/L4:L6=L5/L7:BOTTOM=L7 |
| HIGH_HEX_2 | OTHERS | BUS | 5 | 5 | 5 | 10 | 5 | 14 | 6 | 10 | 12 | 12 | 12 | 12 |  | 50 Ohms | TOP=L2:L3=L2/L4:L6=L5/L7:BOTTOM=L7 |
| HIGH_HEX_2 | OTHERS | BUS | 6 | 5 | 5 | 10 | 5 | 14 | 6 | 10 | 12 | 12 | 12 | 12 |  | 50 Ohms | TOP=L2:L3=L2/L4:L6=L5/L7:BOTTOM=L7 |
| HIGH_HEX_2 | OTHERS | BUS | 7 | 5 | 5 | 10 | 5 | 14 | 6 | 10 | 12 | 12 | 12 | 12 |  | 50 Ohms | TOP=L2:L3=L2/L4:L6=L5/L7:BOTTOM=L7 |
| HIGH_HEX_2 | OTHERS | BUS | 8 | 4.75 | 5 | 10 | 5 | 14 | 6 | 9.5 | 12 | 12 | 12 | 12 |  | 50 Ohms | TOP=L2:L3=L2/L4:L6=L5/L7:BOTTOM=L7 |
| HIGH_HEX_3 | OTHERS | BUS | 1 | 4.75 | 5 | 10 | 5 | 14 | 6 | 9.5 | 12 | 12 | 12 | 12 |  | 50 Ohms | TOP=L2:L3=L2/L4:L6=L5/L7:BOTTOM=L7 |
| HIGH_HEX_3 | OTHERS | BUS | 2 | 5 | 5 | 10 | 5 | 14 | 6 | 10 | 12 | 12 | 12 | 12 |  | 50 Ohms | TOP=L2:L3=L2/L4:L6=L5/L7:BOTTOM=L7 |
| HIGH_HEX_3 | OTHERS | BUS | 3 | 5 | 5 | 10 | 5 | 14 | 6 | 10 | 12 | 12 | 12 | 12 |  | 50 Ohms | TOP=L2:L3=L2/L4:L6=L5/L7:BOTTOM=L7 |
| HIGH_HEX_3 | OTHERS | BUS | 4 | 5 | 5 | 10 | 5 | 14 | 6 | 10 | 12 | 12 | 12 | 12 |  | 50 Ohms | TOP=L2:L3=L2/L4:L6=L5/L7:BOTTOM=L7 |
| HIGH_HEX_3 | OTHERS | BUS | 5 | 5 | 5 | 10 | 5 | 14 | 6 | 10 | 12 | 12 | 12 | 12 |  | 50 Ohms | TOP=L2:L3=L2/L4:L6=L5/L7:BOTTOM=L7 |
| HIGH_HEX_3 | OTHERS | BUS | 6 | 5 | 5 | 10 | 5 | 14 | 6 | 10 | 12 | 12 | 12 | 12 |  | 50 Ohms | TOP=L2:L3=L2/L4:L6=L5/L7:BOTTOM=L7 |
| HIGH_HEX_3 | OTHERS | BUS | 7 | 5 | 5 | 10 | 5 | 14 | 6 | 10 | 12 | 12 | 12 | 12 |  | 50 Ohms | TOP=L2:L3=L2/L4:L6=L5/L7:BOTTOM=L7 |
| HIGH_HEX_3 | OTHERS | BUS | 8 | 4.75 | 5 | 10 | 5 | 14 | 6 | 9.5 | 12 | 12 | 12 | 12 |  | 50 Ohms | TOP=L2:L3=L2/L4:L6=L5/L7:BOTTOM=L7 |
| HOST_I2C_RESET_N | OTHERS | BUS | 1 | 4.75 | 5 | 10 | 5 | 14 | 6 | 9.5 | 12 | 12 | 12 | 12 |  | 50 Ohms | TOP=L2:L3=L2/L4:L6=L5/L7:BOTTOM=L7 |
| HOST_I2C_RESET_N | OTHERS | BUS | 2 | 5 | 5 | 10 | 5 | 14 | 6 | 10 | 12 | 12 | 12 | 12 |  | 50 Ohms | TOP=L2:L3=L2/L4:L6=L5/L7:BOTTOM=L7 |
| HOST_I2C_RESET_N | OTHERS | BUS | 3 | 5 | 5 | 10 | 5 | 14 | 6 | 10 | 12 | 12 | 12 | 12 |  | 50 Ohms | TOP=L2:L3=L2/L4:L6=L5/L7:BOTTOM=L7 |
| HOST_I2C_RESET_N | OTHERS | BUS | 4 | 5 | 5 | 10 | 5 | 14 | 6 | 10 | 12 | 12 | 12 | 12 |  | 50 Ohms | TOP=L2:L3=L2/L4:L6=L5/L7:BOTTOM=L7 |
| HOST_I2C_RESET_N | OTHERS | BUS | 5 | 5 | 5 | 10 | 5 | 14 | 6 | 10 | 12 | 12 | 12 | 12 |  | 50 Ohms | TOP=L2:L3=L2/L4:L6=L5/L7:BOTTOM=L7 |
| HOST_I2C_RESET_N | OTHERS | BUS | 6 | 5 | 5 | 10 | 5 | 14 | 6 | 10 | 12 | 12 | 12 | 12 |  | 50 Ohms | TOP=L2:L3=L2/L4:L6=L5/L7:BOTTOM=L7 |
| HOST_I2C_RESET_N | OTHERS | BUS | 7 | 5 | 5 | 10 | 5 | 14 | 6 | 10 | 12 | 12 | 12 | 12 |  | 50 Ohms | TOP=L2:L3=L2/L4:L6=L5/L7:BOTTOM=L7 |
| HOST_I2C_RESET_N | OTHERS | BUS | 8 | 4.75 | 5 | 10 | 5 | 14 | 6 | 9.5 | 12 | 12 | 12 | 12 |  | 50 Ohms | TOP=L2:L3=L2/L4:L6=L5/L7:BOTTOM=L7 |
| HOST_I2C_RESET_N_D | OTHERS | BUS | 1 | 4.75 | 5 | 10 | 5 | 14 | 6 | 9.5 | 12 | 12 | 12 | 12 |  | 50 Ohms | TOP=L2:L3=L2/L4:L6=L5/L7:BOTTOM=L7 |
| HOST_I2C_RESET_N_D | OTHERS | BUS | 2 | 5 | 5 | 10 | 5 | 14 | 6 | 10 | 12 | 12 | 12 | 12 |  | 50 Ohms | TOP=L2:L3=L2/L4:L6=L5/L7:BOTTOM=L7 |
| HOST_I2C_RESET_N_D | OTHERS | BUS | 3 | 5 | 5 | 10 | 5 | 14 | 6 | 10 | 12 | 12 | 12 | 12 |  | 50 Ohms | TOP=L2:L3=L2/L4:L6=L5/L7:BOTTOM=L7 |
| HOST_I2C_RESET_N_D | OTHERS | BUS | 4 | 5 | 5 | 10 | 5 | 14 | 6 | 10 | 12 | 12 | 12 | 12 |  | 50 Ohms | TOP=L2:L3=L2/L4:L6=L5/L7:BOTTOM=L7 |
| HOST_I2C_RESET_N_D | OTHERS | BUS | 5 | 5 | 5 | 10 | 5 | 14 | 6 | 10 | 12 | 12 | 12 | 12 |  | 50 Ohms | TOP=L2:L3=L2/L4:L6=L5/L7:BOTTOM=L7 |
| HOST_I2C_RESET_N_D | OTHERS | BUS | 6 | 5 | 5 | 10 | 5 | 14 | 6 | 10 | 12 | 12 | 12 | 12 |  | 50 Ohms | TOP=L2:L3=L2/L4:L6=L5/L7:BOTTOM=L7 |
| HOST_I2C_RESET_N_D | OTHERS | BUS | 7 | 5 | 5 | 10 | 5 | 14 | 6 | 10 | 12 | 12 | 12 | 12 |  | 50 Ohms | TOP=L2:L3=L2/L4:L6=L5/L7:BOTTOM=L7 |
| HOST_I2C_RESET_N_D | OTHERS | BUS | 8 | 4.75 | 5 | 10 | 5 | 14 | 6 | 9.5 | 12 | 12 | 12 | 12 |  | 50 Ohms | TOP=L2:L3=L2/L4:L6=L5/L7:BOTTOM=L7 |
| HOST1_RST_N | OTHERS | BUS | 1 | 4.75 | 5 | 10 | 5 | 14 | 6 | 9.5 | 12 | 12 | 12 | 12 |  | 50 Ohms | TOP=L2:L3=L2/L4:L6=L5/L7:BOTTOM=L7 |
| HOST1_RST_N | OTHERS | BUS | 2 | 5 | 5 | 10 | 5 | 14 | 6 | 10 | 12 | 12 | 12 | 12 |  | 50 Ohms | TOP=L2:L3=L2/L4:L6=L5/L7:BOTTOM=L7 |
| HOST1_RST_N | OTHERS | BUS | 3 | 5 | 5 | 10 | 5 | 14 | 6 | 10 | 12 | 12 | 12 | 12 |  | 50 Ohms | TOP=L2:L3=L2/L4:L6=L5/L7:BOTTOM=L7 |
| HOST1_RST_N | OTHERS | BUS | 4 | 5 | 5 | 10 | 5 | 14 | 6 | 10 | 12 | 12 | 12 | 12 |  | 50 Ohms | TOP=L2:L3=L2/L4:L6=L5/L7:BOTTOM=L7 |
| HOST1_RST_N | OTHERS | BUS | 5 | 5 | 5 | 10 | 5 | 14 | 6 | 10 | 12 | 12 | 12 | 12 |  | 50 Ohms | TOP=L2:L3=L2/L4:L6=L5/L7:BOTTOM=L7 |
| HOST1_RST_N | OTHERS | BUS | 6 | 5 | 5 | 10 | 5 | 14 | 6 | 10 | 12 | 12 | 12 | 12 |  | 50 Ohms | TOP=L2:L3=L2/L4:L6=L5/L7:BOTTOM=L7 |
| HOST1_RST_N | OTHERS | BUS | 7 | 5 | 5 | 10 | 5 | 14 | 6 | 10 | 12 | 12 | 12 | 12 |  | 50 Ohms | TOP=L2:L3=L2/L4:L6=L5/L7:BOTTOM=L7 |
| HOST1_RST_N | OTHERS | BUS | 8 | 4.75 | 5 | 10 | 5 | 14 | 6 | 9.5 | 12 | 12 | 12 | 12 |  | 50 Ohms | TOP=L2:L3=L2/L4:L6=L5/L7:BOTTOM=L7 |
| HOST1_RST_N_C | OTHERS | BUS | 1 | 4.75 | 5 | 10 | 5 | 14 | 6 | 9.5 | 12 | 12 | 12 | 12 |  | 50 Ohms | TOP=L2:L3=L2/L4:L6=L5/L7:BOTTOM=L7 |
| HOST1_RST_N_C | OTHERS | BUS | 2 | 5 | 5 | 10 | 5 | 14 | 6 | 10 | 12 | 12 | 12 | 12 |  | 50 Ohms | TOP=L2:L3=L2/L4:L6=L5/L7:BOTTOM=L7 |
| HOST1_RST_N_C | OTHERS | BUS | 3 | 5 | 5 | 10 | 5 | 14 | 6 | 10 | 12 | 12 | 12 | 12 |  | 50 Ohms | TOP=L2:L3=L2/L4:L6=L5/L7:BOTTOM=L7 |
| HOST1_RST_N_C | OTHERS | BUS | 4 | 5 | 5 | 10 | 5 | 14 | 6 | 10 | 12 | 12 | 12 | 12 |  | 50 Ohms | TOP=L2:L3=L2/L4:L6=L5/L7:BOTTOM=L7 |
| HOST1_RST_N_C | OTHERS | BUS | 5 | 5 | 5 | 10 | 5 | 14 | 6 | 10 | 12 | 12 | 12 | 12 |  | 50 Ohms | TOP=L2:L3=L2/L4:L6=L5/L7:BOTTOM=L7 |
| HOST1_RST_N_C | OTHERS | BUS | 6 | 5 | 5 | 10 | 5 | 14 | 6 | 10 | 12 | 12 | 12 | 12 |  | 50 Ohms | TOP=L2:L3=L2/L4:L6=L5/L7:BOTTOM=L7 |
| HOST1_RST_N_C | OTHERS | BUS | 7 | 5 | 5 | 10 | 5 | 14 | 6 | 10 | 12 | 12 | 12 | 12 |  | 50 Ohms | TOP=L2:L3=L2/L4:L6=L5/L7:BOTTOM=L7 |
| HOST1_RST_N_C | OTHERS | BUS | 8 | 4.75 | 5 | 10 | 5 | 14 | 6 | 9.5 | 12 | 12 | 12 | 12 |  | 50 Ohms | TOP=L2:L3=L2/L4:L6=L5/L7:BOTTOM=L7 |
| HOST1_RST_N_LS | OTHERS | BUS | 1 | 4.75 | 5 | 10 | 5 | 14 | 6 | 9.5 | 12 | 12 | 12 | 12 |  | 50 Ohms | TOP=L2:L3=L2/L4:L6=L5/L7:BOTTOM=L7 |
| HOST1_RST_N_LS | OTHERS | BUS | 2 | 5 | 5 | 10 | 5 | 14 | 6 | 10 | 12 | 12 | 12 | 12 |  | 50 Ohms | TOP=L2:L3=L2/L4:L6=L5/L7:BOTTOM=L7 |
| HOST1_RST_N_LS | OTHERS | BUS | 3 | 5 | 5 | 10 | 5 | 14 | 6 | 10 | 12 | 12 | 12 | 12 |  | 50 Ohms | TOP=L2:L3=L2/L4:L6=L5/L7:BOTTOM=L7 |
| HOST1_RST_N_LS | OTHERS | BUS | 4 | 5 | 5 | 10 | 5 | 14 | 6 | 10 | 12 | 12 | 12 | 12 |  | 50 Ohms | TOP=L2:L3=L2/L4:L6=L5/L7:BOTTOM=L7 |
| HOST1_RST_N_LS | OTHERS | BUS | 5 | 5 | 5 | 10 | 5 | 14 | 6 | 10 | 12 | 12 | 12 | 12 |  | 50 Ohms | TOP=L2:L3=L2/L4:L6=L5/L7:BOTTOM=L7 |
| HOST1_RST_N_LS | OTHERS | BUS | 6 | 5 | 5 | 10 | 5 | 14 | 6 | 10 | 12 | 12 | 12 | 12 |  | 50 Ohms | TOP=L2:L3=L2/L4:L6=L5/L7:BOTTOM=L7 |
| HOST1_RST_N_LS | OTHERS | BUS | 7 | 5 | 5 | 10 | 5 | 14 | 6 | 10 | 12 | 12 | 12 | 12 |  | 50 Ohms | TOP=L2:L3=L2/L4:L6=L5/L7:BOTTOM=L7 |
| HOST1_RST_N_LS | OTHERS | BUS | 8 | 4.75 | 5 | 10 | 5 | 14 | 6 | 9.5 | 12 | 12 | 12 | 12 |  | 50 Ohms | TOP=L2:L3=L2/L4:L6=L5/L7:BOTTOM=L7 |
| HOST1_RST_N_R | OTHERS | BUS | 1 | 4.75 | 5 | 10 | 5 | 14 | 6 | 9.5 | 12 | 12 | 12 | 12 |  | 50 Ohms | TOP=L2:L3=L2/L4:L6=L5/L7:BOTTOM=L7 |
| HOST1_RST_N_R | OTHERS | BUS | 2 | 5 | 5 | 10 | 5 | 14 | 6 | 10 | 12 | 12 | 12 | 12 |  | 50 Ohms | TOP=L2:L3=L2/L4:L6=L5/L7:BOTTOM=L7 |
| HOST1_RST_N_R | OTHERS | BUS | 3 | 5 | 5 | 10 | 5 | 14 | 6 | 10 | 12 | 12 | 12 | 12 |  | 50 Ohms | TOP=L2:L3=L2/L4:L6=L5/L7:BOTTOM=L7 |
| HOST1_RST_N_R | OTHERS | BUS | 4 | 5 | 5 | 10 | 5 | 14 | 6 | 10 | 12 | 12 | 12 | 12 |  | 50 Ohms | TOP=L2:L3=L2/L4:L6=L5/L7:BOTTOM=L7 |
| HOST1_RST_N_R | OTHERS | BUS | 5 | 5 | 5 | 10 | 5 | 14 | 6 | 10 | 12 | 12 | 12 | 12 |  | 50 Ohms | TOP=L2:L3=L2/L4:L6=L5/L7:BOTTOM=L7 |
| HOST1_RST_N_R | OTHERS | BUS | 6 | 5 | 5 | 10 | 5 | 14 | 6 | 10 | 12 | 12 | 12 | 12 |  | 50 Ohms | TOP=L2:L3=L2/L4:L6=L5/L7:BOTTOM=L7 |
| HOST1_RST_N_R | OTHERS | BUS | 7 | 5 | 5 | 10 | 5 | 14 | 6 | 10 | 12 | 12 | 12 | 12 |  | 50 Ohms | TOP=L2:L3=L2/L4:L6=L5/L7:BOTTOM=L7 |
| HOST1_RST_N_R | OTHERS | BUS | 8 | 4.75 | 5 | 10 | 5 | 14 | 6 | 9.5 | 12 | 12 | 12 | 12 |  | 50 Ohms | TOP=L2:L3=L2/L4:L6=L5/L7:BOTTOM=L7 |
| HOST2_RST_N | OTHERS | BUS | 1 | 4.75 | 5 | 10 | 5 | 14 | 6 | 9.5 | 12 | 12 | 12 | 12 |  | 50 Ohms | TOP=L2:L3=L2/L4:L6=L5/L7:BOTTOM=L7 |
| HOST2_RST_N | OTHERS | BUS | 2 | 5 | 5 | 10 | 5 | 14 | 6 | 10 | 12 | 12 | 12 | 12 |  | 50 Ohms | TOP=L2:L3=L2/L4:L6=L5/L7:BOTTOM=L7 |
| HOST2_RST_N | OTHERS | BUS | 3 | 5 | 5 | 10 | 5 | 14 | 6 | 10 | 12 | 12 | 12 | 12 |  | 50 Ohms | TOP=L2:L3=L2/L4:L6=L5/L7:BOTTOM=L7 |
| HOST2_RST_N | OTHERS | BUS | 4 | 5 | 5 | 10 | 5 | 14 | 6 | 10 | 12 | 12 | 12 | 12 |  | 50 Ohms | TOP=L2:L3=L2/L4:L6=L5/L7:BOTTOM=L7 |
| HOST2_RST_N | OTHERS | BUS | 5 | 5 | 5 | 10 | 5 | 14 | 6 | 10 | 12 | 12 | 12 | 12 |  | 50 Ohms | TOP=L2:L3=L2/L4:L6=L5/L7:BOTTOM=L7 |
| HOST2_RST_N | OTHERS | BUS | 6 | 5 | 5 | 10 | 5 | 14 | 6 | 10 | 12 | 12 | 12 | 12 |  | 50 Ohms | TOP=L2:L3=L2/L4:L6=L5/L7:BOTTOM=L7 |
| HOST2_RST_N | OTHERS | BUS | 7 | 5 | 5 | 10 | 5 | 14 | 6 | 10 | 12 | 12 | 12 | 12 |  | 50 Ohms | TOP=L2:L3=L2/L4:L6=L5/L7:BOTTOM=L7 |
| HOST2_RST_N | OTHERS | BUS | 8 | 4.75 | 5 | 10 | 5 | 14 | 6 | 9.5 | 12 | 12 | 12 | 12 |  | 50 Ohms | TOP=L2:L3=L2/L4:L6=L5/L7:BOTTOM=L7 |
| HOST2_RST_N_C | OTHERS | BUS | 1 | 4.75 | 5 | 10 | 5 | 14 | 6 | 9.5 | 12 | 12 | 12 | 12 |  | 50 Ohms | TOP=L2:L3=L2/L4:L6=L5/L7:BOTTOM=L7 |
| HOST2_RST_N_C | OTHERS | BUS | 2 | 5 | 5 | 10 | 5 | 14 | 6 | 10 | 12 | 12 | 12 | 12 |  | 50 Ohms | TOP=L2:L3=L2/L4:L6=L5/L7:BOTTOM=L7 |
| HOST2_RST_N_C | OTHERS | BUS | 3 | 5 | 5 | 10 | 5 | 14 | 6 | 10 | 12 | 12 | 12 | 12 |  | 50 Ohms | TOP=L2:L3=L2/L4:L6=L5/L7:BOTTOM=L7 |
| HOST2_RST_N_C | OTHERS | BUS | 4 | 5 | 5 | 10 | 5 | 14 | 6 | 10 | 12 | 12 | 12 | 12 |  | 50 Ohms | TOP=L2:L3=L2/L4:L6=L5/L7:BOTTOM=L7 |
| HOST2_RST_N_C | OTHERS | BUS | 5 | 5 | 5 | 10 | 5 | 14 | 6 | 10 | 12 | 12 | 12 | 12 |  | 50 Ohms | TOP=L2:L3=L2/L4:L6=L5/L7:BOTTOM=L7 |
| HOST2_RST_N_C | OTHERS | BUS | 6 | 5 | 5 | 10 | 5 | 14 | 6 | 10 | 12 | 12 | 12 | 12 |  | 50 Ohms | TOP=L2:L3=L2/L4:L6=L5/L7:BOTTOM=L7 |
| HOST2_RST_N_C | OTHERS | BUS | 7 | 5 | 5 | 10 | 5 | 14 | 6 | 10 | 12 | 12 | 12 | 12 |  | 50 Ohms | TOP=L2:L3=L2/L4:L6=L5/L7:BOTTOM=L7 |
| HOST2_RST_N_C | OTHERS | BUS | 8 | 4.75 | 5 | 10 | 5 | 14 | 6 | 9.5 | 12 | 12 | 12 | 12 |  | 50 Ohms | TOP=L2:L3=L2/L4:L6=L5/L7:BOTTOM=L7 |
| HOST2_RST_N_LS | OTHERS | BUS | 1 | 4.75 | 5 | 10 | 5 | 14 | 6 | 9.5 | 12 | 12 | 12 | 12 |  | 50 Ohms | TOP=L2:L3=L2/L4:L6=L5/L7:BOTTOM=L7 |
| HOST2_RST_N_LS | OTHERS | BUS | 2 | 5 | 5 | 10 | 5 | 14 | 6 | 10 | 12 | 12 | 12 | 12 |  | 50 Ohms | TOP=L2:L3=L2/L4:L6=L5/L7:BOTTOM=L7 |
| HOST2_RST_N_LS | OTHERS | BUS | 3 | 5 | 5 | 10 | 5 | 14 | 6 | 10 | 12 | 12 | 12 | 12 |  | 50 Ohms | TOP=L2:L3=L2/L4:L6=L5/L7:BOTTOM=L7 |
| HOST2_RST_N_LS | OTHERS | BUS | 4 | 5 | 5 | 10 | 5 | 14 | 6 | 10 | 12 | 12 | 12 | 12 |  | 50 Ohms | TOP=L2:L3=L2/L4:L6=L5/L7:BOTTOM=L7 |
| HOST2_RST_N_LS | OTHERS | BUS | 5 | 5 | 5 | 10 | 5 | 14 | 6 | 10 | 12 | 12 | 12 | 12 |  | 50 Ohms | TOP=L2:L3=L2/L4:L6=L5/L7:BOTTOM=L7 |
| HOST2_RST_N_LS | OTHERS | BUS | 6 | 5 | 5 | 10 | 5 | 14 | 6 | 10 | 12 | 12 | 12 | 12 |  | 50 Ohms | TOP=L2:L3=L2/L4:L6=L5/L7:BOTTOM=L7 |
| HOST2_RST_N_LS | OTHERS | BUS | 7 | 5 | 5 | 10 | 5 | 14 | 6 | 10 | 12 | 12 | 12 | 12 |  | 50 Ohms | TOP=L2:L3=L2/L4:L6=L5/L7:BOTTOM=L7 |
| HOST2_RST_N_LS | OTHERS | BUS | 8 | 4.75 | 5 | 10 | 5 | 14 | 6 | 9.5 | 12 | 12 | 12 | 12 |  | 50 Ohms | TOP=L2:L3=L2/L4:L6=L5/L7:BOTTOM=L7 |
| HOST3_RST_N | OTHERS | BUS | 1 | 4.75 | 5 | 10 | 5 | 14 | 6 | 9.5 | 12 | 12 | 12 | 12 |  | 50 Ohms | TOP=L2:L3=L2/L4:L6=L5/L7:BOTTOM=L7 |
| HOST3_RST_N | OTHERS | BUS | 2 | 5 | 5 | 10 | 5 | 14 | 6 | 10 | 12 | 12 | 12 | 12 |  | 50 Ohms | TOP=L2:L3=L2/L4:L6=L5/L7:BOTTOM=L7 |
| HOST3_RST_N | OTHERS | BUS | 3 | 5 | 5 | 10 | 5 | 14 | 6 | 10 | 12 | 12 | 12 | 12 |  | 50 Ohms | TOP=L2:L3=L2/L4:L6=L5/L7:BOTTOM=L7 |
| HOST3_RST_N | OTHERS | BUS | 4 | 5 | 5 | 10 | 5 | 14 | 6 | 10 | 12 | 12 | 12 | 12 |  | 50 Ohms | TOP=L2:L3=L2/L4:L6=L5/L7:BOTTOM=L7 |
| HOST3_RST_N | OTHERS | BUS | 5 | 5 | 5 | 10 | 5 | 14 | 6 | 10 | 12 | 12 | 12 | 12 |  | 50 Ohms | TOP=L2:L3=L2/L4:L6=L5/L7:BOTTOM=L7 |
| HOST3_RST_N | OTHERS | BUS | 6 | 5 | 5 | 10 | 5 | 14 | 6 | 10 | 12 | 12 | 12 | 12 |  | 50 Ohms | TOP=L2:L3=L2/L4:L6=L5/L7:BOTTOM=L7 |
| HOST3_RST_N | OTHERS | BUS | 7 | 5 | 5 | 10 | 5 | 14 | 6 | 10 | 12 | 12 | 12 | 12 |  | 50 Ohms | TOP=L2:L3=L2/L4:L6=L5/L7:BOTTOM=L7 |
| HOST3_RST_N | OTHERS | BUS | 8 | 4.75 | 5 | 10 | 5 | 14 | 6 | 9.5 | 12 | 12 | 12 | 12 |  | 50 Ohms | TOP=L2:L3=L2/L4:L6=L5/L7:BOTTOM=L7 |
| HOST3_RST_N_C | OTHERS | BUS | 1 | 4.75 | 5 | 10 | 5 | 14 | 6 | 9.5 | 12 | 12 | 12 | 12 |  | 50 Ohms | TOP=L2:L3=L2/L4:L6=L5/L7:BOTTOM=L7 |
| HOST3_RST_N_C | OTHERS | BUS | 2 | 5 | 5 | 10 | 5 | 14 | 6 | 10 | 12 | 12 | 12 | 12 |  | 50 Ohms | TOP=L2:L3=L2/L4:L6=L5/L7:BOTTOM=L7 |
| HOST3_RST_N_C | OTHERS | BUS | 3 | 5 | 5 | 10 | 5 | 14 | 6 | 10 | 12 | 12 | 12 | 12 |  | 50 Ohms | TOP=L2:L3=L2/L4:L6=L5/L7:BOTTOM=L7 |
| HOST3_RST_N_C | OTHERS | BUS | 4 | 5 | 5 | 10 | 5 | 14 | 6 | 10 | 12 | 12 | 12 | 12 |  | 50 Ohms | TOP=L2:L3=L2/L4:L6=L5/L7:BOTTOM=L7 |
| HOST3_RST_N_C | OTHERS | BUS | 5 | 5 | 5 | 10 | 5 | 14 | 6 | 10 | 12 | 12 | 12 | 12 |  | 50 Ohms | TOP=L2:L3=L2/L4:L6=L5/L7:BOTTOM=L7 |
| HOST3_RST_N_C | OTHERS | BUS | 6 | 5 | 5 | 10 | 5 | 14 | 6 | 10 | 12 | 12 | 12 | 12 |  | 50 Ohms | TOP=L2:L3=L2/L4:L6=L5/L7:BOTTOM=L7 |
| HOST3_RST_N_C | OTHERS | BUS | 7 | 5 | 5 | 10 | 5 | 14 | 6 | 10 | 12 | 12 | 12 | 12 |  | 50 Ohms | TOP=L2:L3=L2/L4:L6=L5/L7:BOTTOM=L7 |
| HOST3_RST_N_C | OTHERS | BUS | 8 | 4.75 | 5 | 10 | 5 | 14 | 6 | 9.5 | 12 | 12 | 12 | 12 |  | 50 Ohms | TOP=L2:L3=L2/L4:L6=L5/L7:BOTTOM=L7 |
| HOST3_RST_N_LS | OTHERS | BUS | 1 | 4.75 | 5 | 10 | 5 | 14 | 6 | 9.5 | 12 | 12 | 12 | 12 |  | 50 Ohms | TOP=L2:L3=L2/L4:L6=L5/L7:BOTTOM=L7 |
| HOST3_RST_N_LS | OTHERS | BUS | 2 | 5 | 5 | 10 | 5 | 14 | 6 | 10 | 12 | 12 | 12 | 12 |  | 50 Ohms | TOP=L2:L3=L2/L4:L6=L5/L7:BOTTOM=L7 |
| HOST3_RST_N_LS | OTHERS | BUS | 3 | 5 | 5 | 10 | 5 | 14 | 6 | 10 | 12 | 12 | 12 | 12 |  | 50 Ohms | TOP=L2:L3=L2/L4:L6=L5/L7:BOTTOM=L7 |
| HOST3_RST_N_LS | OTHERS | BUS | 4 | 5 | 5 | 10 | 5 | 14 | 6 | 10 | 12 | 12 | 12 | 12 |  | 50 Ohms | TOP=L2:L3=L2/L4:L6=L5/L7:BOTTOM=L7 |
| HOST3_RST_N_LS | OTHERS | BUS | 5 | 5 | 5 | 10 | 5 | 14 | 6 | 10 | 12 | 12 | 12 | 12 |  | 50 Ohms | TOP=L2:L3=L2/L4:L6=L5/L7:BOTTOM=L7 |
| HOST3_RST_N_LS | OTHERS | BUS | 6 | 5 | 5 | 10 | 5 | 14 | 6 | 10 | 12 | 12 | 12 | 12 |  | 50 Ohms | TOP=L2:L3=L2/L4:L6=L5/L7:BOTTOM=L7 |
| HOST3_RST_N_LS | OTHERS | BUS | 7 | 5 | 5 | 10 | 5 | 14 | 6 | 10 | 12 | 12 | 12 | 12 |  | 50 Ohms | TOP=L2:L3=L2/L4:L6=L5/L7:BOTTOM=L7 |
| HOST3_RST_N_LS | OTHERS | BUS | 8 | 4.75 | 5 | 10 | 5 | 14 | 6 | 9.5 | 12 | 12 | 12 | 12 |  | 50 Ohms | TOP=L2:L3=L2/L4:L6=L5/L7:BOTTOM=L7 |
| HOST4_RST_N | OTHERS | BUS | 1 | 4.75 | 5 | 10 | 5 | 14 | 6 | 9.5 | 12 | 12 | 12 | 12 |  | 50 Ohms | TOP=L2:L3=L2/L4:L6=L5/L7:BOTTOM=L7 |
| HOST4_RST_N | OTHERS | BUS | 2 | 5 | 5 | 10 | 5 | 14 | 6 | 10 | 12 | 12 | 12 | 12 |  | 50 Ohms | TOP=L2:L3=L2/L4:L6=L5/L7:BOTTOM=L7 |
| HOST4_RST_N | OTHERS | BUS | 3 | 5 | 5 | 10 | 5 | 14 | 6 | 10 | 12 | 12 | 12 | 12 |  | 50 Ohms | TOP=L2:L3=L2/L4:L6=L5/L7:BOTTOM=L7 |
| HOST4_RST_N | OTHERS | BUS | 4 | 5 | 5 | 10 | 5 | 14 | 6 | 10 | 12 | 12 | 12 | 12 |  | 50 Ohms | TOP=L2:L3=L2/L4:L6=L5/L7:BOTTOM=L7 |
| HOST4_RST_N | OTHERS | BUS | 5 | 5 | 5 | 10 | 5 | 14 | 6 | 10 | 12 | 12 | 12 | 12 |  | 50 Ohms | TOP=L2:L3=L2/L4:L6=L5/L7:BOTTOM=L7 |
| HOST4_RST_N | OTHERS | BUS | 6 | 5 | 5 | 10 | 5 | 14 | 6 | 10 | 12 | 12 | 12 | 12 |  | 50 Ohms | TOP=L2:L3=L2/L4:L6=L5/L7:BOTTOM=L7 |
| HOST4_RST_N | OTHERS | BUS | 7 | 5 | 5 | 10 | 5 | 14 | 6 | 10 | 12 | 12 | 12 | 12 |  | 50 Ohms | TOP=L2:L3=L2/L4:L6=L5/L7:BOTTOM=L7 |
| HOST4_RST_N | OTHERS | BUS | 8 | 4.75 | 5 | 10 | 5 | 14 | 6 | 9.5 | 12 | 12 | 12 | 12 |  | 50 Ohms | TOP=L2:L3=L2/L4:L6=L5/L7:BOTTOM=L7 |
| HOST4_RST_N_C | OTHERS | BUS | 1 | 4.75 | 5 | 10 | 5 | 14 | 6 | 9.5 | 12 | 12 | 12 | 12 |  | 50 Ohms | TOP=L2:L3=L2/L4:L6=L5/L7:BOTTOM=L7 |
| HOST4_RST_N_C | OTHERS | BUS | 2 | 5 | 5 | 10 | 5 | 14 | 6 | 10 | 12 | 12 | 12 | 12 |  | 50 Ohms | TOP=L2:L3=L2/L4:L6=L5/L7:BOTTOM=L7 |
| HOST4_RST_N_C | OTHERS | BUS | 3 | 5 | 5 | 10 | 5 | 14 | 6 | 10 | 12 | 12 | 12 | 12 |  | 50 Ohms | TOP=L2:L3=L2/L4:L6=L5/L7:BOTTOM=L7 |
| HOST4_RST_N_C | OTHERS | BUS | 4 | 5 | 5 | 10 | 5 | 14 | 6 | 10 | 12 | 12 | 12 | 12 |  | 50 Ohms | TOP=L2:L3=L2/L4:L6=L5/L7:BOTTOM=L7 |
| HOST4_RST_N_C | OTHERS | BUS | 5 | 5 | 5 | 10 | 5 | 14 | 6 | 10 | 12 | 12 | 12 | 12 |  | 50 Ohms | TOP=L2:L3=L2/L4:L6=L5/L7:BOTTOM=L7 |
| HOST4_RST_N_C | OTHERS | BUS | 6 | 5 | 5 | 10 | 5 | 14 | 6 | 10 | 12 | 12 | 12 | 12 |  | 50 Ohms | TOP=L2:L3=L2/L4:L6=L5/L7:BOTTOM=L7 |
| HOST4_RST_N_C | OTHERS | BUS | 7 | 5 | 5 | 10 | 5 | 14 | 6 | 10 | 12 | 12 | 12 | 12 |  | 50 Ohms | TOP=L2:L3=L2/L4:L6=L5/L7:BOTTOM=L7 |
| HOST4_RST_N_C | OTHERS | BUS | 8 | 4.75 | 5 | 10 | 5 | 14 | 6 | 9.5 | 12 | 12 | 12 | 12 |  | 50 Ohms | TOP=L2:L3=L2/L4:L6=L5/L7:BOTTOM=L7 |
| HOST4_RST_N_LS | OTHERS | BUS | 1 | 4.75 | 5 | 10 | 5 | 14 | 6 | 9.5 | 12 | 12 | 12 | 12 |  | 50 Ohms | TOP=L2:L3=L2/L4:L6=L5/L7:BOTTOM=L7 |
| HOST4_RST_N_LS | OTHERS | BUS | 2 | 5 | 5 | 10 | 5 | 14 | 6 | 10 | 12 | 12 | 12 | 12 |  | 50 Ohms | TOP=L2:L3=L2/L4:L6=L5/L7:BOTTOM=L7 |
| HOST4_RST_N_LS | OTHERS | BUS | 3 | 5 | 5 | 10 | 5 | 14 | 6 | 10 | 12 | 12 | 12 | 12 |  | 50 Ohms | TOP=L2:L3=L2/L4:L6=L5/L7:BOTTOM=L7 |
| HOST4_RST_N_LS | OTHERS | BUS | 4 | 5 | 5 | 10 | 5 | 14 | 6 | 10 | 12 | 12 | 12 | 12 |  | 50 Ohms | TOP=L2:L3=L2/L4:L6=L5/L7:BOTTOM=L7 |
| HOST4_RST_N_LS | OTHERS | BUS | 5 | 5 | 5 | 10 | 5 | 14 | 6 | 10 | 12 | 12 | 12 | 12 |  | 50 Ohms | TOP=L2:L3=L2/L4:L6=L5/L7:BOTTOM=L7 |
| HOST4_RST_N_LS | OTHERS | BUS | 6 | 5 | 5 | 10 | 5 | 14 | 6 | 10 | 12 | 12 | 12 | 12 |  | 50 Ohms | TOP=L2:L3=L2/L4:L6=L5/L7:BOTTOM=L7 |
| HOST4_RST_N_LS | OTHERS | BUS | 7 | 5 | 5 | 10 | 5 | 14 | 6 | 10 | 12 | 12 | 12 | 12 |  | 50 Ohms | TOP=L2:L3=L2/L4:L6=L5/L7:BOTTOM=L7 |
| HOST4_RST_N_LS | OTHERS | BUS | 8 | 4.75 | 5 | 10 | 5 | 14 | 6 | 9.5 | 12 | 12 | 12 | 12 |  | 50 Ohms | TOP=L2:L3=L2/L4:L6=L5/L7:BOTTOM=L7 |
| HOST5_RST_N | OTHERS | BUS | 1 | 4.75 | 5 | 10 | 5 | 14 | 6 | 9.5 | 12 | 12 | 12 | 12 |  | 50 Ohms | TOP=L2:L3=L2/L4:L6=L5/L7:BOTTOM=L7 |
| HOST5_RST_N | OTHERS | BUS | 2 | 5 | 5 | 10 | 5 | 14 | 6 | 10 | 12 | 12 | 12 | 12 |  | 50 Ohms | TOP=L2:L3=L2/L4:L6=L5/L7:BOTTOM=L7 |
| HOST5_RST_N | OTHERS | BUS | 3 | 5 | 5 | 10 | 5 | 14 | 6 | 10 | 12 | 12 | 12 | 12 |  | 50 Ohms | TOP=L2:L3=L2/L4:L6=L5/L7:BOTTOM=L7 |
| HOST5_RST_N | OTHERS | BUS | 4 | 5 | 5 | 10 | 5 | 14 | 6 | 10 | 12 | 12 | 12 | 12 |  | 50 Ohms | TOP=L2:L3=L2/L4:L6=L5/L7:BOTTOM=L7 |
| HOST5_RST_N | OTHERS | BUS | 5 | 5 | 5 | 10 | 5 | 14 | 6 | 10 | 12 | 12 | 12 | 12 |  | 50 Ohms | TOP=L2:L3=L2/L4:L6=L5/L7:BOTTOM=L7 |
| HOST5_RST_N | OTHERS | BUS | 6 | 5 | 5 | 10 | 5 | 14 | 6 | 10 | 12 | 12 | 12 | 12 |  | 50 Ohms | TOP=L2:L3=L2/L4:L6=L5/L7:BOTTOM=L7 |
| HOST5_RST_N | OTHERS | BUS | 7 | 5 | 5 | 10 | 5 | 14 | 6 | 10 | 12 | 12 | 12 | 12 |  | 50 Ohms | TOP=L2:L3=L2/L4:L6=L5/L7:BOTTOM=L7 |
| HOST5_RST_N | OTHERS | BUS | 8 | 4.75 | 5 | 10 | 5 | 14 | 6 | 9.5 | 12 | 12 | 12 | 12 |  | 50 Ohms | TOP=L2:L3=L2/L4:L6=L5/L7:BOTTOM=L7 |
| HOST5_RST_N_C | OTHERS | BUS | 1 | 4.75 | 5 | 10 | 5 | 14 | 6 | 9.5 | 12 | 12 | 12 | 12 |  | 50 Ohms | TOP=L2:L3=L2/L4:L6=L5/L7:BOTTOM=L7 |
| HOST5_RST_N_C | OTHERS | BUS | 2 | 5 | 5 | 10 | 5 | 14 | 6 | 10 | 12 | 12 | 12 | 12 |  | 50 Ohms | TOP=L2:L3=L2/L4:L6=L5/L7:BOTTOM=L7 |
| HOST5_RST_N_C | OTHERS | BUS | 3 | 5 | 5 | 10 | 5 | 14 | 6 | 10 | 12 | 12 | 12 | 12 |  | 50 Ohms | TOP=L2:L3=L2/L4:L6=L5/L7:BOTTOM=L7 |
| HOST5_RST_N_C | OTHERS | BUS | 4 | 5 | 5 | 10 | 5 | 14 | 6 | 10 | 12 | 12 | 12 | 12 |  | 50 Ohms | TOP=L2:L3=L2/L4:L6=L5/L7:BOTTOM=L7 |
| HOST5_RST_N_C | OTHERS | BUS | 5 | 5 | 5 | 10 | 5 | 14 | 6 | 10 | 12 | 12 | 12 | 12 |  | 50 Ohms | TOP=L2:L3=L2/L4:L6=L5/L7:BOTTOM=L7 |
| HOST5_RST_N_C | OTHERS | BUS | 6 | 5 | 5 | 10 | 5 | 14 | 6 | 10 | 12 | 12 | 12 | 12 |  | 50 Ohms | TOP=L2:L3=L2/L4:L6=L5/L7:BOTTOM=L7 |
| HOST5_RST_N_C | OTHERS | BUS | 7 | 5 | 5 | 10 | 5 | 14 | 6 | 10 | 12 | 12 | 12 | 12 |  | 50 Ohms | TOP=L2:L3=L2/L4:L6=L5/L7:BOTTOM=L7 |
| HOST5_RST_N_C | OTHERS | BUS | 8 | 4.75 | 5 | 10 | 5 | 14 | 6 | 9.5 | 12 | 12 | 12 | 12 |  | 50 Ohms | TOP=L2:L3=L2/L4:L6=L5/L7:BOTTOM=L7 |
| HOST5_RST_N_LS | OTHERS | BUS | 1 | 4.75 | 5 | 10 | 5 | 14 | 6 | 9.5 | 12 | 12 | 12 | 12 |  | 50 Ohms | TOP=L2:L3=L2/L4:L6=L5/L7:BOTTOM=L7 |
| HOST5_RST_N_LS | OTHERS | BUS | 2 | 5 | 5 | 10 | 5 | 14 | 6 | 10 | 12 | 12 | 12 | 12 |  | 50 Ohms | TOP=L2:L3=L2/L4:L6=L5/L7:BOTTOM=L7 |
| HOST5_RST_N_LS | OTHERS | BUS | 3 | 5 | 5 | 10 | 5 | 14 | 6 | 10 | 12 | 12 | 12 | 12 |  | 50 Ohms | TOP=L2:L3=L2/L4:L6=L5/L7:BOTTOM=L7 |
| HOST5_RST_N_LS | OTHERS | BUS | 4 | 5 | 5 | 10 | 5 | 14 | 6 | 10 | 12 | 12 | 12 | 12 |  | 50 Ohms | TOP=L2:L3=L2/L4:L6=L5/L7:BOTTOM=L7 |
| HOST5_RST_N_LS | OTHERS | BUS | 5 | 5 | 5 | 10 | 5 | 14 | 6 | 10 | 12 | 12 | 12 | 12 |  | 50 Ohms | TOP=L2:L3=L2/L4:L6=L5/L7:BOTTOM=L7 |
| HOST5_RST_N_LS | OTHERS | BUS | 6 | 5 | 5 | 10 | 5 | 14 | 6 | 10 | 12 | 12 | 12 | 12 |  | 50 Ohms | TOP=L2:L3=L2/L4:L6=L5/L7:BOTTOM=L7 |
| HOST5_RST_N_LS | OTHERS | BUS | 7 | 5 | 5 | 10 | 5 | 14 | 6 | 10 | 12 | 12 | 12 | 12 |  | 50 Ohms | TOP=L2:L3=L2/L4:L6=L5/L7:BOTTOM=L7 |
| HOST5_RST_N_LS | OTHERS | BUS | 8 | 4.75 | 5 | 10 | 5 | 14 | 6 | 9.5 | 12 | 12 | 12 | 12 |  | 50 Ohms | TOP=L2:L3=L2/L4:L6=L5/L7:BOTTOM=L7 |
| HOST6_RST_N | OTHERS | BUS | 1 | 4.75 | 5 | 10 | 5 | 14 | 6 | 9.5 | 12 | 12 | 12 | 12 |  | 50 Ohms | TOP=L2:L3=L2/L4:L6=L5/L7:BOTTOM=L7 |
| HOST6_RST_N | OTHERS | BUS | 2 | 5 | 5 | 10 | 5 | 14 | 6 | 10 | 12 | 12 | 12 | 12 |  | 50 Ohms | TOP=L2:L3=L2/L4:L6=L5/L7:BOTTOM=L7 |
| HOST6_RST_N | OTHERS | BUS | 3 | 5 | 5 | 10 | 5 | 14 | 6 | 10 | 12 | 12 | 12 | 12 |  | 50 Ohms | TOP=L2:L3=L2/L4:L6=L5/L7:BOTTOM=L7 |
| HOST6_RST_N | OTHERS | BUS | 4 | 5 | 5 | 10 | 5 | 14 | 6 | 10 | 12 | 12 | 12 | 12 |  | 50 Ohms | TOP=L2:L3=L2/L4:L6=L5/L7:BOTTOM=L7 |
| HOST6_RST_N | OTHERS | BUS | 5 | 5 | 5 | 10 | 5 | 14 | 6 | 10 | 12 | 12 | 12 | 12 |  | 50 Ohms | TOP=L2:L3=L2/L4:L6=L5/L7:BOTTOM=L7 |
| HOST6_RST_N | OTHERS | BUS | 6 | 5 | 5 | 10 | 5 | 14 | 6 | 10 | 12 | 12 | 12 | 12 |  | 50 Ohms | TOP=L2:L3=L2/L4:L6=L5/L7:BOTTOM=L7 |
| HOST6_RST_N | OTHERS | BUS | 7 | 5 | 5 | 10 | 5 | 14 | 6 | 10 | 12 | 12 | 12 | 12 |  | 50 Ohms | TOP=L2:L3=L2/L4:L6=L5/L7:BOTTOM=L7 |
| HOST6_RST_N | OTHERS | BUS | 8 | 4.75 | 5 | 10 | 5 | 14 | 6 | 9.5 | 12 | 12 | 12 | 12 |  | 50 Ohms | TOP=L2:L3=L2/L4:L6=L5/L7:BOTTOM=L7 |
| HOST6_RST_N_C | OTHERS | BUS | 1 | 4.75 | 5 | 10 | 5 | 14 | 6 | 9.5 | 12 | 12 | 12 | 12 |  | 50 Ohms | TOP=L2:L3=L2/L4:L6=L5/L7:BOTTOM=L7 |
| HOST6_RST_N_C | OTHERS | BUS | 2 | 5 | 5 | 10 | 5 | 14 | 6 | 10 | 12 | 12 | 12 | 12 |  | 50 Ohms | TOP=L2:L3=L2/L4:L6=L5/L7:BOTTOM=L7 |
| HOST6_RST_N_C | OTHERS | BUS | 3 | 5 | 5 | 10 | 5 | 14 | 6 | 10 | 12 | 12 | 12 | 12 |  | 50 Ohms | TOP=L2:L3=L2/L4:L6=L5/L7:BOTTOM=L7 |
| HOST6_RST_N_C | OTHERS | BUS | 4 | 5 | 5 | 10 | 5 | 14 | 6 | 10 | 12 | 12 | 12 | 12 |  | 50 Ohms | TOP=L2:L3=L2/L4:L6=L5/L7:BOTTOM=L7 |
| HOST6_RST_N_C | OTHERS | BUS | 5 | 5 | 5 | 10 | 5 | 14 | 6 | 10 | 12 | 12 | 12 | 12 |  | 50 Ohms | TOP=L2:L3=L2/L4:L6=L5/L7:BOTTOM=L7 |
| HOST6_RST_N_C | OTHERS | BUS | 6 | 5 | 5 | 10 | 5 | 14 | 6 | 10 | 12 | 12 | 12 | 12 |  | 50 Ohms | TOP=L2:L3=L2/L4:L6=L5/L7:BOTTOM=L7 |
| HOST6_RST_N_C | OTHERS | BUS | 7 | 5 | 5 | 10 | 5 | 14 | 6 | 10 | 12 | 12 | 12 | 12 |  | 50 Ohms | TOP=L2:L3=L2/L4:L6=L5/L7:BOTTOM=L7 |
| HOST6_RST_N_C | OTHERS | BUS | 8 | 4.75 | 5 | 10 | 5 | 14 | 6 | 9.5 | 12 | 12 | 12 | 12 |  | 50 Ohms | TOP=L2:L3=L2/L4:L6=L5/L7:BOTTOM=L7 |
| HOST6_RST_N_LS | OTHERS | BUS | 1 | 4.75 | 5 | 10 | 5 | 14 | 6 | 9.5 | 12 | 12 | 12 | 12 |  | 50 Ohms | TOP=L2:L3=L2/L4:L6=L5/L7:BOTTOM=L7 |
| HOST6_RST_N_LS | OTHERS | BUS | 2 | 5 | 5 | 10 | 5 | 14 | 6 | 10 | 12 | 12 | 12 | 12 |  | 50 Ohms | TOP=L2:L3=L2/L4:L6=L5/L7:BOTTOM=L7 |
| HOST6_RST_N_LS | OTHERS | BUS | 3 | 5 | 5 | 10 | 5 | 14 | 6 | 10 | 12 | 12 | 12 | 12 |  | 50 Ohms | TOP=L2:L3=L2/L4:L6=L5/L7:BOTTOM=L7 |
| HOST6_RST_N_LS | OTHERS | BUS | 4 | 5 | 5 | 10 | 5 | 14 | 6 | 10 | 12 | 12 | 12 | 12 |  | 50 Ohms | TOP=L2:L3=L2/L4:L6=L5/L7:BOTTOM=L7 |
| HOST6_RST_N_LS | OTHERS | BUS | 5 | 5 | 5 | 10 | 5 | 14 | 6 | 10 | 12 | 12 | 12 | 12 |  | 50 Ohms | TOP=L2:L3=L2/L4:L6=L5/L7:BOTTOM=L7 |
| HOST6_RST_N_LS | OTHERS | BUS | 6 | 5 | 5 | 10 | 5 | 14 | 6 | 10 | 12 | 12 | 12 | 12 |  | 50 Ohms | TOP=L2:L3=L2/L4:L6=L5/L7:BOTTOM=L7 |
| HOST6_RST_N_LS | OTHERS | BUS | 7 | 5 | 5 | 10 | 5 | 14 | 6 | 10 | 12 | 12 | 12 | 12 |  | 50 Ohms | TOP=L2:L3=L2/L4:L6=L5/L7:BOTTOM=L7 |
| HOST6_RST_N_LS | OTHERS | BUS | 8 | 4.75 | 5 | 10 | 5 | 14 | 6 | 9.5 | 12 | 12 | 12 | 12 |  | 50 Ohms | TOP=L2:L3=L2/L4:L6=L5/L7:BOTTOM=L7 |
| HOST7_RST_N | OTHERS | BUS | 1 | 4.75 | 5 | 10 | 5 | 14 | 6 | 9.5 | 12 | 12 | 12 | 12 |  | 50 Ohms | TOP=L2:L3=L2/L4:L6=L5/L7:BOTTOM=L7 |
| HOST7_RST_N | OTHERS | BUS | 2 | 5 | 5 | 10 | 5 | 14 | 6 | 10 | 12 | 12 | 12 | 12 |  | 50 Ohms | TOP=L2:L3=L2/L4:L6=L5/L7:BOTTOM=L7 |
| HOST7_RST_N | OTHERS | BUS | 3 | 5 | 5 | 10 | 5 | 14 | 6 | 10 | 12 | 12 | 12 | 12 |  | 50 Ohms | TOP=L2:L3=L2/L4:L6=L5/L7:BOTTOM=L7 |
| HOST7_RST_N | OTHERS | BUS | 4 | 5 | 5 | 10 | 5 | 14 | 6 | 10 | 12 | 12 | 12 | 12 |  | 50 Ohms | TOP=L2:L3=L2/L4:L6=L5/L7:BOTTOM=L7 |
| HOST7_RST_N | OTHERS | BUS | 5 | 5 | 5 | 10 | 5 | 14 | 6 | 10 | 12 | 12 | 12 | 12 |  | 50 Ohms | TOP=L2:L3=L2/L4:L6=L5/L7:BOTTOM=L7 |
| HOST7_RST_N | OTHERS | BUS | 6 | 5 | 5 | 10 | 5 | 14 | 6 | 10 | 12 | 12 | 12 | 12 |  | 50 Ohms | TOP=L2:L3=L2/L4:L6=L5/L7:BOTTOM=L7 |
| HOST7_RST_N | OTHERS | BUS | 7 | 5 | 5 | 10 | 5 | 14 | 6 | 10 | 12 | 12 | 12 | 12 |  | 50 Ohms | TOP=L2:L3=L2/L4:L6=L5/L7:BOTTOM=L7 |
| HOST7_RST_N | OTHERS | BUS | 8 | 4.75 | 5 | 10 | 5 | 14 | 6 | 9.5 | 12 | 12 | 12 | 12 |  | 50 Ohms | TOP=L2:L3=L2/L4:L6=L5/L7:BOTTOM=L7 |
| HOST7_RST_N_C | OTHERS | BUS | 1 | 4.75 | 5 | 10 | 5 | 14 | 6 | 9.5 | 12 | 12 | 12 | 12 |  | 50 Ohms | TOP=L2:L3=L2/L4:L6=L5/L7:BOTTOM=L7 |
| HOST7_RST_N_C | OTHERS | BUS | 2 | 5 | 5 | 10 | 5 | 14 | 6 | 10 | 12 | 12 | 12 | 12 |  | 50 Ohms | TOP=L2:L3=L2/L4:L6=L5/L7:BOTTOM=L7 |
| HOST7_RST_N_C | OTHERS | BUS | 3 | 5 | 5 | 10 | 5 | 14 | 6 | 10 | 12 | 12 | 12 | 12 |  | 50 Ohms | TOP=L2:L3=L2/L4:L6=L5/L7:BOTTOM=L7 |
| HOST7_RST_N_C | OTHERS | BUS | 4 | 5 | 5 | 10 | 5 | 14 | 6 | 10 | 12 | 12 | 12 | 12 |  | 50 Ohms | TOP=L2:L3=L2/L4:L6=L5/L7:BOTTOM=L7 |
| HOST7_RST_N_C | OTHERS | BUS | 5 | 5 | 5 | 10 | 5 | 14 | 6 | 10 | 12 | 12 | 12 | 12 |  | 50 Ohms | TOP=L2:L3=L2/L4:L6=L5/L7:BOTTOM=L7 |
| HOST7_RST_N_C | OTHERS | BUS | 6 | 5 | 5 | 10 | 5 | 14 | 6 | 10 | 12 | 12 | 12 | 12 |  | 50 Ohms | TOP=L2:L3=L2/L4:L6=L5/L7:BOTTOM=L7 |
| HOST7_RST_N_C | OTHERS | BUS | 7 | 5 | 5 | 10 | 5 | 14 | 6 | 10 | 12 | 12 | 12 | 12 |  | 50 Ohms | TOP=L2:L3=L2/L4:L6=L5/L7:BOTTOM=L7 |
| HOST7_RST_N_C | OTHERS | BUS | 8 | 4.75 | 5 | 10 | 5 | 14 | 6 | 9.5 | 12 | 12 | 12 | 12 |  | 50 Ohms | TOP=L2:L3=L2/L4:L6=L5/L7:BOTTOM=L7 |
| HOST7_RST_N_LS | OTHERS | BUS | 1 | 4.75 | 5 | 10 | 5 | 14 | 6 | 9.5 | 12 | 12 | 12 | 12 |  | 50 Ohms | TOP=L2:L3=L2/L4:L6=L5/L7:BOTTOM=L7 |
| HOST7_RST_N_LS | OTHERS | BUS | 2 | 5 | 5 | 10 | 5 | 14 | 6 | 10 | 12 | 12 | 12 | 12 |  | 50 Ohms | TOP=L2:L3=L2/L4:L6=L5/L7:BOTTOM=L7 |
| HOST7_RST_N_LS | OTHERS | BUS | 3 | 5 | 5 | 10 | 5 | 14 | 6 | 10 | 12 | 12 | 12 | 12 |  | 50 Ohms | TOP=L2:L3=L2/L4:L6=L5/L7:BOTTOM=L7 |
| HOST7_RST_N_LS | OTHERS | BUS | 4 | 5 | 5 | 10 | 5 | 14 | 6 | 10 | 12 | 12 | 12 | 12 |  | 50 Ohms | TOP=L2:L3=L2/L4:L6=L5/L7:BOTTOM=L7 |
| HOST7_RST_N_LS | OTHERS | BUS | 5 | 5 | 5 | 10 | 5 | 14 | 6 | 10 | 12 | 12 | 12 | 12 |  | 50 Ohms | TOP=L2:L3=L2/L4:L6=L5/L7:BOTTOM=L7 |
| HOST7_RST_N_LS | OTHERS | BUS | 6 | 5 | 5 | 10 | 5 | 14 | 6 | 10 | 12 | 12 | 12 | 12 |  | 50 Ohms | TOP=L2:L3=L2/L4:L6=L5/L7:BOTTOM=L7 |
| HOST7_RST_N_LS | OTHERS | BUS | 7 | 5 | 5 | 10 | 5 | 14 | 6 | 10 | 12 | 12 | 12 | 12 |  | 50 Ohms | TOP=L2:L3=L2/L4:L6=L5/L7:BOTTOM=L7 |
| HOST7_RST_N_LS | OTHERS | BUS | 8 | 4.75 | 5 | 10 | 5 | 14 | 6 | 9.5 | 12 | 12 | 12 | 12 |  | 50 Ohms | TOP=L2:L3=L2/L4:L6=L5/L7:BOTTOM=L7 |
| HOST8_RST_N | OTHERS | BUS | 1 | 4.75 | 5 | 10 | 5 | 14 | 6 | 9.5 | 12 | 12 | 12 | 12 |  | 50 Ohms | TOP=L2:L3=L2/L4:L6=L5/L7:BOTTOM=L7 |
| HOST8_RST_N | OTHERS | BUS | 2 | 5 | 5 | 10 | 5 | 14 | 6 | 10 | 12 | 12 | 12 | 12 |  | 50 Ohms | TOP=L2:L3=L2/L4:L6=L5/L7:BOTTOM=L7 |
| HOST8_RST_N | OTHERS | BUS | 3 | 5 | 5 | 10 | 5 | 14 | 6 | 10 | 12 | 12 | 12 | 12 |  | 50 Ohms | TOP=L2:L3=L2/L4:L6=L5/L7:BOTTOM=L7 |
| HOST8_RST_N | OTHERS | BUS | 4 | 5 | 5 | 10 | 5 | 14 | 6 | 10 | 12 | 12 | 12 | 12 |  | 50 Ohms | TOP=L2:L3=L2/L4:L6=L5/L7:BOTTOM=L7 |
| HOST8_RST_N | OTHERS | BUS | 5 | 5 | 5 | 10 | 5 | 14 | 6 | 10 | 12 | 12 | 12 | 12 |  | 50 Ohms | TOP=L2:L3=L2/L4:L6=L5/L7:BOTTOM=L7 |
| HOST8_RST_N | OTHERS | BUS | 6 | 5 | 5 | 10 | 5 | 14 | 6 | 10 | 12 | 12 | 12 | 12 |  | 50 Ohms | TOP=L2:L3=L2/L4:L6=L5/L7:BOTTOM=L7 |
| HOST8_RST_N | OTHERS | BUS | 7 | 5 | 5 | 10 | 5 | 14 | 6 | 10 | 12 | 12 | 12 | 12 |  | 50 Ohms | TOP=L2:L3=L2/L4:L6=L5/L7:BOTTOM=L7 |
| HOST8_RST_N | OTHERS | BUS | 8 | 4.75 | 5 | 10 | 5 | 14 | 6 | 9.5 | 12 | 12 | 12 | 12 |  | 50 Ohms | TOP=L2:L3=L2/L4:L6=L5/L7:BOTTOM=L7 |
| HOST8_RST_N_C | OTHERS | BUS | 1 | 4.75 | 5 | 10 | 5 | 14 | 6 | 9.5 | 12 | 12 | 12 | 12 |  | 50 Ohms | TOP=L2:L3=L2/L4:L6=L5/L7:BOTTOM=L7 |
| HOST8_RST_N_C | OTHERS | BUS | 2 | 5 | 5 | 10 | 5 | 14 | 6 | 10 | 12 | 12 | 12 | 12 |  | 50 Ohms | TOP=L2:L3=L2/L4:L6=L5/L7:BOTTOM=L7 |
| HOST8_RST_N_C | OTHERS | BUS | 3 | 5 | 5 | 10 | 5 | 14 | 6 | 10 | 12 | 12 | 12 | 12 |  | 50 Ohms | TOP=L2:L3=L2/L4:L6=L5/L7:BOTTOM=L7 |
| HOST8_RST_N_C | OTHERS | BUS | 4 | 5 | 5 | 10 | 5 | 14 | 6 | 10 | 12 | 12 | 12 | 12 |  | 50 Ohms | TOP=L2:L3=L2/L4:L6=L5/L7:BOTTOM=L7 |
| HOST8_RST_N_C | OTHERS | BUS | 5 | 5 | 5 | 10 | 5 | 14 | 6 | 10 | 12 | 12 | 12 | 12 |  | 50 Ohms | TOP=L2:L3=L2/L4:L6=L5/L7:BOTTOM=L7 |
| HOST8_RST_N_C | OTHERS | BUS | 6 | 5 | 5 | 10 | 5 | 14 | 6 | 10 | 12 | 12 | 12 | 12 |  | 50 Ohms | TOP=L2:L3=L2/L4:L6=L5/L7:BOTTOM=L7 |
| HOST8_RST_N_C | OTHERS | BUS | 7 | 5 | 5 | 10 | 5 | 14 | 6 | 10 | 12 | 12 | 12 | 12 |  | 50 Ohms | TOP=L2:L3=L2/L4:L6=L5/L7:BOTTOM=L7 |
| HOST8_RST_N_C | OTHERS | BUS | 8 | 4.75 | 5 | 10 | 5 | 14 | 6 | 9.5 | 12 | 12 | 12 | 12 |  | 50 Ohms | TOP=L2:L3=L2/L4:L6=L5/L7:BOTTOM=L7 |
| HOST8_RST_N_LS | OTHERS | BUS | 1 | 4.75 | 5 | 10 | 5 | 14 | 6 | 9.5 | 12 | 12 | 12 | 12 |  | 50 Ohms | TOP=L2:L3=L2/L4:L6=L5/L7:BOTTOM=L7 |
| HOST8_RST_N_LS | OTHERS | BUS | 2 | 5 | 5 | 10 | 5 | 14 | 6 | 10 | 12 | 12 | 12 | 12 |  | 50 Ohms | TOP=L2:L3=L2/L4:L6=L5/L7:BOTTOM=L7 |
| HOST8_RST_N_LS | OTHERS | BUS | 3 | 5 | 5 | 10 | 5 | 14 | 6 | 10 | 12 | 12 | 12 | 12 |  | 50 Ohms | TOP=L2:L3=L2/L4:L6=L5/L7:BOTTOM=L7 |
| HOST8_RST_N_LS | OTHERS | BUS | 4 | 5 | 5 | 10 | 5 | 14 | 6 | 10 | 12 | 12 | 12 | 12 |  | 50 Ohms | TOP=L2:L3=L2/L4:L6=L5/L7:BOTTOM=L7 |
| HOST8_RST_N_LS | OTHERS | BUS | 5 | 5 | 5 | 10 | 5 | 14 | 6 | 10 | 12 | 12 | 12 | 12 |  | 50 Ohms | TOP=L2:L3=L2/L4:L6=L5/L7:BOTTOM=L7 |
| HOST8_RST_N_LS | OTHERS | BUS | 6 | 5 | 5 | 10 | 5 | 14 | 6 | 10 | 12 | 12 | 12 | 12 |  | 50 Ohms | TOP=L2:L3=L2/L4:L6=L5/L7:BOTTOM=L7 |
| HOST8_RST_N_LS | OTHERS | BUS | 7 | 5 | 5 | 10 | 5 | 14 | 6 | 10 | 12 | 12 | 12 | 12 |  | 50 Ohms | TOP=L2:L3=L2/L4:L6=L5/L7:BOTTOM=L7 |
| HOST8_RST_N_LS | OTHERS | BUS | 8 | 4.75 | 5 | 10 | 5 | 14 | 6 | 9.5 | 12 | 12 | 12 | 12 |  | 50 Ohms | TOP=L2:L3=L2/L4:L6=L5/L7:BOTTOM=L7 |
| I210_CS_N_R | OTHERS | BUS | 1 | 4.75 | 5 | 10 | 5 | 14 | 6 | 9.5 | 12 | 12 | 12 | 12 |  | 50 Ohms | TOP=L2:L3=L2/L4:L6=L5/L7:BOTTOM=L7 |
| I210_CS_N_R | OTHERS | BUS | 2 | 5 | 5 | 10 | 5 | 14 | 6 | 10 | 12 | 12 | 12 | 12 |  | 50 Ohms | TOP=L2:L3=L2/L4:L6=L5/L7:BOTTOM=L7 |
| I210_CS_N_R | OTHERS | BUS | 3 | 5 | 5 | 10 | 5 | 14 | 6 | 10 | 12 | 12 | 12 | 12 |  | 50 Ohms | TOP=L2:L3=L2/L4:L6=L5/L7:BOTTOM=L7 |
| I210_CS_N_R | OTHERS | BUS | 4 | 5 | 5 | 10 | 5 | 14 | 6 | 10 | 12 | 12 | 12 | 12 |  | 50 Ohms | TOP=L2:L3=L2/L4:L6=L5/L7:BOTTOM=L7 |
| I210_CS_N_R | OTHERS | BUS | 5 | 5 | 5 | 10 | 5 | 14 | 6 | 10 | 12 | 12 | 12 | 12 |  | 50 Ohms | TOP=L2:L3=L2/L4:L6=L5/L7:BOTTOM=L7 |
| I210_CS_N_R | OTHERS | BUS | 6 | 5 | 5 | 10 | 5 | 14 | 6 | 10 | 12 | 12 | 12 | 12 |  | 50 Ohms | TOP=L2:L3=L2/L4:L6=L5/L7:BOTTOM=L7 |
| I210_CS_N_R | OTHERS | BUS | 7 | 5 | 5 | 10 | 5 | 14 | 6 | 10 | 12 | 12 | 12 | 12 |  | 50 Ohms | TOP=L2:L3=L2/L4:L6=L5/L7:BOTTOM=L7 |
| I210_CS_N_R | OTHERS | BUS | 8 | 4.75 | 5 | 10 | 5 | 14 | 6 | 9.5 | 12 | 12 | 12 | 12 |  | 50 Ohms | TOP=L2:L3=L2/L4:L6=L5/L7:BOTTOM=L7 |
| I210_PERST_N | OTHERS | BUS | 1 | 4.75 | 5 | 10 | 5 | 14 | 6 | 9.5 | 12 | 12 | 12 | 12 |  | 50 Ohms | TOP=L2:L3=L2/L4:L6=L5/L7:BOTTOM=L7 |
| I210_PERST_N | OTHERS | BUS | 2 | 5 | 5 | 10 | 5 | 14 | 6 | 10 | 12 | 12 | 12 | 12 |  | 50 Ohms | TOP=L2:L3=L2/L4:L6=L5/L7:BOTTOM=L7 |
| I210_PERST_N | OTHERS | BUS | 3 | 5 | 5 | 10 | 5 | 14 | 6 | 10 | 12 | 12 | 12 | 12 |  | 50 Ohms | TOP=L2:L3=L2/L4:L6=L5/L7:BOTTOM=L7 |
| I210_PERST_N | OTHERS | BUS | 4 | 5 | 5 | 10 | 5 | 14 | 6 | 10 | 12 | 12 | 12 | 12 |  | 50 Ohms | TOP=L2:L3=L2/L4:L6=L5/L7:BOTTOM=L7 |
| I210_PERST_N | OTHERS | BUS | 5 | 5 | 5 | 10 | 5 | 14 | 6 | 10 | 12 | 12 | 12 | 12 |  | 50 Ohms | TOP=L2:L3=L2/L4:L6=L5/L7:BOTTOM=L7 |
| I210_PERST_N | OTHERS | BUS | 6 | 5 | 5 | 10 | 5 | 14 | 6 | 10 | 12 | 12 | 12 | 12 |  | 50 Ohms | TOP=L2:L3=L2/L4:L6=L5/L7:BOTTOM=L7 |
| I210_PERST_N | OTHERS | BUS | 7 | 5 | 5 | 10 | 5 | 14 | 6 | 10 | 12 | 12 | 12 | 12 |  | 50 Ohms | TOP=L2:L3=L2/L4:L6=L5/L7:BOTTOM=L7 |
| I210_PERST_N | OTHERS | BUS | 8 | 4.75 | 5 | 10 | 5 | 14 | 6 | 9.5 | 12 | 12 | 12 | 12 |  | 50 Ohms | TOP=L2:L3=L2/L4:L6=L5/L7:BOTTOM=L7 |
| I210_SI_R | OTHERS | BUS | 1 | 4.75 | 5 | 10 | 5 | 14 | 6 | 9.5 | 12 | 12 | 12 | 12 |  | 50 Ohms | TOP=L2:L3=L2/L4:L6=L5/L7:BOTTOM=L7 |
| I210_SI_R | OTHERS | BUS | 2 | 5 | 5 | 10 | 5 | 14 | 6 | 10 | 12 | 12 | 12 | 12 |  | 50 Ohms | TOP=L2:L3=L2/L4:L6=L5/L7:BOTTOM=L7 |
| I210_SI_R | OTHERS | BUS | 3 | 5 | 5 | 10 | 5 | 14 | 6 | 10 | 12 | 12 | 12 | 12 |  | 50 Ohms | TOP=L2:L3=L2/L4:L6=L5/L7:BOTTOM=L7 |
| I210_SI_R | OTHERS | BUS | 4 | 5 | 5 | 10 | 5 | 14 | 6 | 10 | 12 | 12 | 12 | 12 |  | 50 Ohms | TOP=L2:L3=L2/L4:L6=L5/L7:BOTTOM=L7 |
| I210_SI_R | OTHERS | BUS | 5 | 5 | 5 | 10 | 5 | 14 | 6 | 10 | 12 | 12 | 12 | 12 |  | 50 Ohms | TOP=L2:L3=L2/L4:L6=L5/L7:BOTTOM=L7 |
| I210_SI_R | OTHERS | BUS | 6 | 5 | 5 | 10 | 5 | 14 | 6 | 10 | 12 | 12 | 12 | 12 |  | 50 Ohms | TOP=L2:L3=L2/L4:L6=L5/L7:BOTTOM=L7 |
| I210_SI_R | OTHERS | BUS | 7 | 5 | 5 | 10 | 5 | 14 | 6 | 10 | 12 | 12 | 12 | 12 |  | 50 Ohms | TOP=L2:L3=L2/L4:L6=L5/L7:BOTTOM=L7 |
| I210_SI_R | OTHERS | BUS | 8 | 4.75 | 5 | 10 | 5 | 14 | 6 | 9.5 | 12 | 12 | 12 | 12 |  | 50 Ohms | TOP=L2:L3=L2/L4:L6=L5/L7:BOTTOM=L7 |
| I210_SK_R | OTHERS | BUS | 1 | 4.75 | 5 | 10 | 5 | 14 | 6 | 9.5 | 12 | 12 | 12 | 12 |  | 50 Ohms | TOP=L2:L3=L2/L4:L6=L5/L7:BOTTOM=L7 |
| I210_SK_R | OTHERS | BUS | 2 | 5 | 5 | 10 | 5 | 14 | 6 | 10 | 12 | 12 | 12 | 12 |  | 50 Ohms | TOP=L2:L3=L2/L4:L6=L5/L7:BOTTOM=L7 |
| I210_SK_R | OTHERS | BUS | 3 | 5 | 5 | 10 | 5 | 14 | 6 | 10 | 12 | 12 | 12 | 12 |  | 50 Ohms | TOP=L2:L3=L2/L4:L6=L5/L7:BOTTOM=L7 |
| I210_SK_R | OTHERS | BUS | 4 | 5 | 5 | 10 | 5 | 14 | 6 | 10 | 12 | 12 | 12 | 12 |  | 50 Ohms | TOP=L2:L3=L2/L4:L6=L5/L7:BOTTOM=L7 |
| I210_SK_R | OTHERS | BUS | 5 | 5 | 5 | 10 | 5 | 14 | 6 | 10 | 12 | 12 | 12 | 12 |  | 50 Ohms | TOP=L2:L3=L2/L4:L6=L5/L7:BOTTOM=L7 |
| I210_SK_R | OTHERS | BUS | 6 | 5 | 5 | 10 | 5 | 14 | 6 | 10 | 12 | 12 | 12 | 12 |  | 50 Ohms | TOP=L2:L3=L2/L4:L6=L5/L7:BOTTOM=L7 |
| I210_SK_R | OTHERS | BUS | 7 | 5 | 5 | 10 | 5 | 14 | 6 | 10 | 12 | 12 | 12 | 12 |  | 50 Ohms | TOP=L2:L3=L2/L4:L6=L5/L7:BOTTOM=L7 |
| I210_SK_R | OTHERS | BUS | 8 | 4.75 | 5 | 10 | 5 | 14 | 6 | 9.5 | 12 | 12 | 12 | 12 |  | 50 Ohms | TOP=L2:L3=L2/L4:L6=L5/L7:BOTTOM=L7 |
| I210_SO_R | OTHERS | BUS | 1 | 4.75 | 5 | 10 | 5 | 14 | 6 | 9.5 | 12 | 12 | 12 | 12 |  | 50 Ohms | TOP=L2:L3=L2/L4:L6=L5/L7:BOTTOM=L7 |
| I210_SO_R | OTHERS | BUS | 2 | 5 | 5 | 10 | 5 | 14 | 6 | 10 | 12 | 12 | 12 | 12 |  | 50 Ohms | TOP=L2:L3=L2/L4:L6=L5/L7:BOTTOM=L7 |
| I210_SO_R | OTHERS | BUS | 3 | 5 | 5 | 10 | 5 | 14 | 6 | 10 | 12 | 12 | 12 | 12 |  | 50 Ohms | TOP=L2:L3=L2/L4:L6=L5/L7:BOTTOM=L7 |
| I210_SO_R | OTHERS | BUS | 4 | 5 | 5 | 10 | 5 | 14 | 6 | 10 | 12 | 12 | 12 | 12 |  | 50 Ohms | TOP=L2:L3=L2/L4:L6=L5/L7:BOTTOM=L7 |
| I210_SO_R | OTHERS | BUS | 5 | 5 | 5 | 10 | 5 | 14 | 6 | 10 | 12 | 12 | 12 | 12 |  | 50 Ohms | TOP=L2:L3=L2/L4:L6=L5/L7:BOTTOM=L7 |
| I210_SO_R | OTHERS | BUS | 6 | 5 | 5 | 10 | 5 | 14 | 6 | 10 | 12 | 12 | 12 | 12 |  | 50 Ohms | TOP=L2:L3=L2/L4:L6=L5/L7:BOTTOM=L7 |
| I210_SO_R | OTHERS | BUS | 7 | 5 | 5 | 10 | 5 | 14 | 6 | 10 | 12 | 12 | 12 | 12 |  | 50 Ohms | TOP=L2:L3=L2/L4:L6=L5/L7:BOTTOM=L7 |
| I210_SO_R | OTHERS | BUS | 8 | 4.75 | 5 | 10 | 5 | 14 | 6 | 9.5 | 12 | 12 | 12 | 12 |  | 50 Ohms | TOP=L2:L3=L2/L4:L6=L5/L7:BOTTOM=L7 |
| I2C_MUX_RESET_PEB | OTHERS | BUS | 1 | 4.75 | 5 | 10 | 5 | 14 | 6 | 9.5 | 12 | 12 | 12 | 12 |  | 50 Ohms | TOP=L2:L3=L2/L4:L6=L5/L7:BOTTOM=L7 |
| I2C_MUX_RESET_PEB | OTHERS | BUS | 2 | 5 | 5 | 10 | 5 | 14 | 6 | 10 | 12 | 12 | 12 | 12 |  | 50 Ohms | TOP=L2:L3=L2/L4:L6=L5/L7:BOTTOM=L7 |
| I2C_MUX_RESET_PEB | OTHERS | BUS | 3 | 5 | 5 | 10 | 5 | 14 | 6 | 10 | 12 | 12 | 12 | 12 |  | 50 Ohms | TOP=L2:L3=L2/L4:L6=L5/L7:BOTTOM=L7 |
| I2C_MUX_RESET_PEB | OTHERS | BUS | 4 | 5 | 5 | 10 | 5 | 14 | 6 | 10 | 12 | 12 | 12 | 12 |  | 50 Ohms | TOP=L2:L3=L2/L4:L6=L5/L7:BOTTOM=L7 |
| I2C_MUX_RESET_PEB | OTHERS | BUS | 5 | 5 | 5 | 10 | 5 | 14 | 6 | 10 | 12 | 12 | 12 | 12 |  | 50 Ohms | TOP=L2:L3=L2/L4:L6=L5/L7:BOTTOM=L7 |
| I2C_MUX_RESET_PEB | OTHERS | BUS | 6 | 5 | 5 | 10 | 5 | 14 | 6 | 10 | 12 | 12 | 12 | 12 |  | 50 Ohms | TOP=L2:L3=L2/L4:L6=L5/L7:BOTTOM=L7 |
| I2C_MUX_RESET_PEB | OTHERS | BUS | 7 | 5 | 5 | 10 | 5 | 14 | 6 | 10 | 12 | 12 | 12 | 12 |  | 50 Ohms | TOP=L2:L3=L2/L4:L6=L5/L7:BOTTOM=L7 |
| I2C_MUX_RESET_PEB | OTHERS | BUS | 8 | 4.75 | 5 | 10 | 5 | 14 | 6 | 9.5 | 12 | 12 | 12 | 12 |  | 50 Ohms | TOP=L2:L3=L2/L4:L6=L5/L7:BOTTOM=L7 |
| I2C_MUX_RESET_PEB_R | OTHERS | BUS | 1 | 4.75 | 5 | 10 | 5 | 14 | 6 | 9.5 | 12 | 12 | 12 | 12 |  | 50 Ohms | TOP=L2:L3=L2/L4:L6=L5/L7:BOTTOM=L7 |
| I2C_MUX_RESET_PEB_R | OTHERS | BUS | 2 | 5 | 5 | 10 | 5 | 14 | 6 | 10 | 12 | 12 | 12 | 12 |  | 50 Ohms | TOP=L2:L3=L2/L4:L6=L5/L7:BOTTOM=L7 |
| I2C_MUX_RESET_PEB_R | OTHERS | BUS | 3 | 5 | 5 | 10 | 5 | 14 | 6 | 10 | 12 | 12 | 12 | 12 |  | 50 Ohms | TOP=L2:L3=L2/L4:L6=L5/L7:BOTTOM=L7 |
| I2C_MUX_RESET_PEB_R | OTHERS | BUS | 4 | 5 | 5 | 10 | 5 | 14 | 6 | 10 | 12 | 12 | 12 | 12 |  | 50 Ohms | TOP=L2:L3=L2/L4:L6=L5/L7:BOTTOM=L7 |
| I2C_MUX_RESET_PEB_R | OTHERS | BUS | 5 | 5 | 5 | 10 | 5 | 14 | 6 | 10 | 12 | 12 | 12 | 12 |  | 50 Ohms | TOP=L2:L3=L2/L4:L6=L5/L7:BOTTOM=L7 |
| I2C_MUX_RESET_PEB_R | OTHERS | BUS | 6 | 5 | 5 | 10 | 5 | 14 | 6 | 10 | 12 | 12 | 12 | 12 |  | 50 Ohms | TOP=L2:L3=L2/L4:L6=L5/L7:BOTTOM=L7 |
| I2C_MUX_RESET_PEB_R | OTHERS | BUS | 7 | 5 | 5 | 10 | 5 | 14 | 6 | 10 | 12 | 12 | 12 | 12 |  | 50 Ohms | TOP=L2:L3=L2/L4:L6=L5/L7:BOTTOM=L7 |
| I2C_MUX_RESET_PEB_R | OTHERS | BUS | 8 | 4.75 | 5 | 10 | 5 | 14 | 6 | 9.5 | 12 | 12 | 12 | 12 |  | 50 Ohms | TOP=L2:L3=L2/L4:L6=L5/L7:BOTTOM=L7 |
| I2C1_LS_G1 | OTHERS | BUS | 1 | 4.75 | 5 | 10 | 5 | 14 | 6 | 9.5 | 12 | 12 | 12 | 12 |  | 50 Ohms | TOP=L2:L3=L2/L4:L6=L5/L7:BOTTOM=L7 |
| I2C1_LS_G1 | OTHERS | BUS | 2 | 5 | 5 | 10 | 5 | 14 | 6 | 10 | 12 | 12 | 12 | 12 |  | 50 Ohms | TOP=L2:L3=L2/L4:L6=L5/L7:BOTTOM=L7 |
| I2C1_LS_G1 | OTHERS | BUS | 3 | 5 | 5 | 10 | 5 | 14 | 6 | 10 | 12 | 12 | 12 | 12 |  | 50 Ohms | TOP=L2:L3=L2/L4:L6=L5/L7:BOTTOM=L7 |
| I2C1_LS_G1 | OTHERS | BUS | 4 | 5 | 5 | 10 | 5 | 14 | 6 | 10 | 12 | 12 | 12 | 12 |  | 50 Ohms | TOP=L2:L3=L2/L4:L6=L5/L7:BOTTOM=L7 |
| I2C1_LS_G1 | OTHERS | BUS | 5 | 5 | 5 | 10 | 5 | 14 | 6 | 10 | 12 | 12 | 12 | 12 |  | 50 Ohms | TOP=L2:L3=L2/L4:L6=L5/L7:BOTTOM=L7 |
| I2C1_LS_G1 | OTHERS | BUS | 6 | 5 | 5 | 10 | 5 | 14 | 6 | 10 | 12 | 12 | 12 | 12 |  | 50 Ohms | TOP=L2:L3=L2/L4:L6=L5/L7:BOTTOM=L7 |
| I2C1_LS_G1 | OTHERS | BUS | 7 | 5 | 5 | 10 | 5 | 14 | 6 | 10 | 12 | 12 | 12 | 12 |  | 50 Ohms | TOP=L2:L3=L2/L4:L6=L5/L7:BOTTOM=L7 |
| I2C1_LS_G1 | OTHERS | BUS | 8 | 4.75 | 5 | 10 | 5 | 14 | 6 | 9.5 | 12 | 12 | 12 | 12 |  | 50 Ohms | TOP=L2:L3=L2/L4:L6=L5/L7:BOTTOM=L7 |
| I2C1_LS_G2 | OTHERS | BUS | 1 | 4.75 | 5 | 10 | 5 | 14 | 6 | 9.5 | 12 | 12 | 12 | 12 |  | 50 Ohms | TOP=L2:L3=L2/L4:L6=L5/L7:BOTTOM=L7 |
| I2C1_LS_G2 | OTHERS | BUS | 2 | 5 | 5 | 10 | 5 | 14 | 6 | 10 | 12 | 12 | 12 | 12 |  | 50 Ohms | TOP=L2:L3=L2/L4:L6=L5/L7:BOTTOM=L7 |
| I2C1_LS_G2 | OTHERS | BUS | 3 | 5 | 5 | 10 | 5 | 14 | 6 | 10 | 12 | 12 | 12 | 12 |  | 50 Ohms | TOP=L2:L3=L2/L4:L6=L5/L7:BOTTOM=L7 |
| I2C1_LS_G2 | OTHERS | BUS | 4 | 5 | 5 | 10 | 5 | 14 | 6 | 10 | 12 | 12 | 12 | 12 |  | 50 Ohms | TOP=L2:L3=L2/L4:L6=L5/L7:BOTTOM=L7 |
| I2C1_LS_G2 | OTHERS | BUS | 5 | 5 | 5 | 10 | 5 | 14 | 6 | 10 | 12 | 12 | 12 | 12 |  | 50 Ohms | TOP=L2:L3=L2/L4:L6=L5/L7:BOTTOM=L7 |
| I2C1_LS_G2 | OTHERS | BUS | 6 | 5 | 5 | 10 | 5 | 14 | 6 | 10 | 12 | 12 | 12 | 12 |  | 50 Ohms | TOP=L2:L3=L2/L4:L6=L5/L7:BOTTOM=L7 |
| I2C1_LS_G2 | OTHERS | BUS | 7 | 5 | 5 | 10 | 5 | 14 | 6 | 10 | 12 | 12 | 12 | 12 |  | 50 Ohms | TOP=L2:L3=L2/L4:L6=L5/L7:BOTTOM=L7 |
| I2C1_LS_G2 | OTHERS | BUS | 8 | 4.75 | 5 | 10 | 5 | 14 | 6 | 9.5 | 12 | 12 | 12 | 12 |  | 50 Ohms | TOP=L2:L3=L2/L4:L6=L5/L7:BOTTOM=L7 |
| I2C10_BUF_READY | OTHERS | BUS | 1 | 4.75 | 5 | 10 | 5 | 14 | 6 | 9.5 | 12 | 12 | 12 | 12 |  | 50 Ohms | TOP=L2:L3=L2/L4:L6=L5/L7:BOTTOM=L7 |
| I2C10_BUF_READY | OTHERS | BUS | 2 | 5 | 5 | 10 | 5 | 14 | 6 | 10 | 12 | 12 | 12 | 12 |  | 50 Ohms | TOP=L2:L3=L2/L4:L6=L5/L7:BOTTOM=L7 |
| I2C10_BUF_READY | OTHERS | BUS | 3 | 5 | 5 | 10 | 5 | 14 | 6 | 10 | 12 | 12 | 12 | 12 |  | 50 Ohms | TOP=L2:L3=L2/L4:L6=L5/L7:BOTTOM=L7 |
| I2C10_BUF_READY | OTHERS | BUS | 4 | 5 | 5 | 10 | 5 | 14 | 6 | 10 | 12 | 12 | 12 | 12 |  | 50 Ohms | TOP=L2:L3=L2/L4:L6=L5/L7:BOTTOM=L7 |
| I2C10_BUF_READY | OTHERS | BUS | 5 | 5 | 5 | 10 | 5 | 14 | 6 | 10 | 12 | 12 | 12 | 12 |  | 50 Ohms | TOP=L2:L3=L2/L4:L6=L5/L7:BOTTOM=L7 |
| I2C10_BUF_READY | OTHERS | BUS | 6 | 5 | 5 | 10 | 5 | 14 | 6 | 10 | 12 | 12 | 12 | 12 |  | 50 Ohms | TOP=L2:L3=L2/L4:L6=L5/L7:BOTTOM=L7 |
| I2C10_BUF_READY | OTHERS | BUS | 7 | 5 | 5 | 10 | 5 | 14 | 6 | 10 | 12 | 12 | 12 | 12 |  | 50 Ohms | TOP=L2:L3=L2/L4:L6=L5/L7:BOTTOM=L7 |
| I2C10_BUF_READY | OTHERS | BUS | 8 | 4.75 | 5 | 10 | 5 | 14 | 6 | 9.5 | 12 | 12 | 12 | 12 |  | 50 Ohms | TOP=L2:L3=L2/L4:L6=L5/L7:BOTTOM=L7 |
| I2C10_BUFF_EN | OTHERS | BUS | 1 | 4.75 | 5 | 10 | 5 | 14 | 6 | 9.5 | 12 | 12 | 12 | 12 |  | 50 Ohms | TOP=L2:L3=L2/L4:L6=L5/L7:BOTTOM=L7 |
| I2C10_BUFF_EN | OTHERS | BUS | 2 | 5 | 5 | 10 | 5 | 14 | 6 | 10 | 12 | 12 | 12 | 12 |  | 50 Ohms | TOP=L2:L3=L2/L4:L6=L5/L7:BOTTOM=L7 |
| I2C10_BUFF_EN | OTHERS | BUS | 3 | 5 | 5 | 10 | 5 | 14 | 6 | 10 | 12 | 12 | 12 | 12 |  | 50 Ohms | TOP=L2:L3=L2/L4:L6=L5/L7:BOTTOM=L7 |
| I2C10_BUFF_EN | OTHERS | BUS | 4 | 5 | 5 | 10 | 5 | 14 | 6 | 10 | 12 | 12 | 12 | 12 |  | 50 Ohms | TOP=L2:L3=L2/L4:L6=L5/L7:BOTTOM=L7 |
| I2C10_BUFF_EN | OTHERS | BUS | 5 | 5 | 5 | 10 | 5 | 14 | 6 | 10 | 12 | 12 | 12 | 12 |  | 50 Ohms | TOP=L2:L3=L2/L4:L6=L5/L7:BOTTOM=L7 |
| I2C10_BUFF_EN | OTHERS | BUS | 6 | 5 | 5 | 10 | 5 | 14 | 6 | 10 | 12 | 12 | 12 | 12 |  | 50 Ohms | TOP=L2:L3=L2/L4:L6=L5/L7:BOTTOM=L7 |
| I2C10_BUFF_EN | OTHERS | BUS | 7 | 5 | 5 | 10 | 5 | 14 | 6 | 10 | 12 | 12 | 12 | 12 |  | 50 Ohms | TOP=L2:L3=L2/L4:L6=L5/L7:BOTTOM=L7 |
| I2C10_BUFF_EN | OTHERS | BUS | 8 | 4.75 | 5 | 10 | 5 | 14 | 6 | 9.5 | 12 | 12 | 12 | 12 |  | 50 Ohms | TOP=L2:L3=L2/L4:L6=L5/L7:BOTTOM=L7 |
| I2C2_LS_G1 | OTHERS | BUS | 1 | 4.75 | 5 | 10 | 5 | 14 | 6 | 9.5 | 12 | 12 | 12 | 12 |  | 50 Ohms | TOP=L2:L3=L2/L4:L6=L5/L7:BOTTOM=L7 |
| I2C2_LS_G1 | OTHERS | BUS | 2 | 5 | 5 | 10 | 5 | 14 | 6 | 10 | 12 | 12 | 12 | 12 |  | 50 Ohms | TOP=L2:L3=L2/L4:L6=L5/L7:BOTTOM=L7 |
| I2C2_LS_G1 | OTHERS | BUS | 3 | 5 | 5 | 10 | 5 | 14 | 6 | 10 | 12 | 12 | 12 | 12 |  | 50 Ohms | TOP=L2:L3=L2/L4:L6=L5/L7:BOTTOM=L7 |
| I2C2_LS_G1 | OTHERS | BUS | 4 | 5 | 5 | 10 | 5 | 14 | 6 | 10 | 12 | 12 | 12 | 12 |  | 50 Ohms | TOP=L2:L3=L2/L4:L6=L5/L7:BOTTOM=L7 |
| I2C2_LS_G1 | OTHERS | BUS | 5 | 5 | 5 | 10 | 5 | 14 | 6 | 10 | 12 | 12 | 12 | 12 |  | 50 Ohms | TOP=L2:L3=L2/L4:L6=L5/L7:BOTTOM=L7 |
| I2C2_LS_G1 | OTHERS | BUS | 6 | 5 | 5 | 10 | 5 | 14 | 6 | 10 | 12 | 12 | 12 | 12 |  | 50 Ohms | TOP=L2:L3=L2/L4:L6=L5/L7:BOTTOM=L7 |
| I2C2_LS_G1 | OTHERS | BUS | 7 | 5 | 5 | 10 | 5 | 14 | 6 | 10 | 12 | 12 | 12 | 12 |  | 50 Ohms | TOP=L2:L3=L2/L4:L6=L5/L7:BOTTOM=L7 |
| I2C2_LS_G1 | OTHERS | BUS | 8 | 4.75 | 5 | 10 | 5 | 14 | 6 | 9.5 | 12 | 12 | 12 | 12 |  | 50 Ohms | TOP=L2:L3=L2/L4:L6=L5/L7:BOTTOM=L7 |
| I2C2_LS_G2 | OTHERS | BUS | 1 | 4.75 | 5 | 10 | 5 | 14 | 6 | 9.5 | 12 | 12 | 12 | 12 |  | 50 Ohms | TOP=L2:L3=L2/L4:L6=L5/L7:BOTTOM=L7 |
| I2C2_LS_G2 | OTHERS | BUS | 2 | 5 | 5 | 10 | 5 | 14 | 6 | 10 | 12 | 12 | 12 | 12 |  | 50 Ohms | TOP=L2:L3=L2/L4:L6=L5/L7:BOTTOM=L7 |
| I2C2_LS_G2 | OTHERS | BUS | 3 | 5 | 5 | 10 | 5 | 14 | 6 | 10 | 12 | 12 | 12 | 12 |  | 50 Ohms | TOP=L2:L3=L2/L4:L6=L5/L7:BOTTOM=L7 |
| I2C2_LS_G2 | OTHERS | BUS | 4 | 5 | 5 | 10 | 5 | 14 | 6 | 10 | 12 | 12 | 12 | 12 |  | 50 Ohms | TOP=L2:L3=L2/L4:L6=L5/L7:BOTTOM=L7 |
| I2C2_LS_G2 | OTHERS | BUS | 5 | 5 | 5 | 10 | 5 | 14 | 6 | 10 | 12 | 12 | 12 | 12 |  | 50 Ohms | TOP=L2:L3=L2/L4:L6=L5/L7:BOTTOM=L7 |
| I2C2_LS_G2 | OTHERS | BUS | 6 | 5 | 5 | 10 | 5 | 14 | 6 | 10 | 12 | 12 | 12 | 12 |  | 50 Ohms | TOP=L2:L3=L2/L4:L6=L5/L7:BOTTOM=L7 |
| I2C2_LS_G2 | OTHERS | BUS | 7 | 5 | 5 | 10 | 5 | 14 | 6 | 10 | 12 | 12 | 12 | 12 |  | 50 Ohms | TOP=L2:L3=L2/L4:L6=L5/L7:BOTTOM=L7 |
| I2C2_LS_G2 | OTHERS | BUS | 8 | 4.75 | 5 | 10 | 5 | 14 | 6 | 9.5 | 12 | 12 | 12 | 12 |  | 50 Ohms | TOP=L2:L3=L2/L4:L6=L5/L7:BOTTOM=L7 |
| I2C3_LS_G1 | OTHERS | BUS | 1 | 4.75 | 5 | 10 | 5 | 14 | 6 | 9.5 | 12 | 12 | 12 | 12 |  | 50 Ohms | TOP=L2:L3=L2/L4:L6=L5/L7:BOTTOM=L7 |
| I2C3_LS_G1 | OTHERS | BUS | 2 | 5 | 5 | 10 | 5 | 14 | 6 | 10 | 12 | 12 | 12 | 12 |  | 50 Ohms | TOP=L2:L3=L2/L4:L6=L5/L7:BOTTOM=L7 |
| I2C3_LS_G1 | OTHERS | BUS | 3 | 5 | 5 | 10 | 5 | 14 | 6 | 10 | 12 | 12 | 12 | 12 |  | 50 Ohms | TOP=L2:L3=L2/L4:L6=L5/L7:BOTTOM=L7 |
| I2C3_LS_G1 | OTHERS | BUS | 4 | 5 | 5 | 10 | 5 | 14 | 6 | 10 | 12 | 12 | 12 | 12 |  | 50 Ohms | TOP=L2:L3=L2/L4:L6=L5/L7:BOTTOM=L7 |
| I2C3_LS_G1 | OTHERS | BUS | 5 | 5 | 5 | 10 | 5 | 14 | 6 | 10 | 12 | 12 | 12 | 12 |  | 50 Ohms | TOP=L2:L3=L2/L4:L6=L5/L7:BOTTOM=L7 |
| I2C3_LS_G1 | OTHERS | BUS | 6 | 5 | 5 | 10 | 5 | 14 | 6 | 10 | 12 | 12 | 12 | 12 |  | 50 Ohms | TOP=L2:L3=L2/L4:L6=L5/L7:BOTTOM=L7 |
| I2C3_LS_G1 | OTHERS | BUS | 7 | 5 | 5 | 10 | 5 | 14 | 6 | 10 | 12 | 12 | 12 | 12 |  | 50 Ohms | TOP=L2:L3=L2/L4:L6=L5/L7:BOTTOM=L7 |
| I2C3_LS_G1 | OTHERS | BUS | 8 | 4.75 | 5 | 10 | 5 | 14 | 6 | 9.5 | 12 | 12 | 12 | 12 |  | 50 Ohms | TOP=L2:L3=L2/L4:L6=L5/L7:BOTTOM=L7 |
| I2C3_LS_G2 | OTHERS | BUS | 1 | 4.75 | 5 | 10 | 5 | 14 | 6 | 9.5 | 12 | 12 | 12 | 12 |  | 50 Ohms | TOP=L2:L3=L2/L4:L6=L5/L7:BOTTOM=L7 |
| I2C3_LS_G2 | OTHERS | BUS | 2 | 5 | 5 | 10 | 5 | 14 | 6 | 10 | 12 | 12 | 12 | 12 |  | 50 Ohms | TOP=L2:L3=L2/L4:L6=L5/L7:BOTTOM=L7 |
| I2C3_LS_G2 | OTHERS | BUS | 3 | 5 | 5 | 10 | 5 | 14 | 6 | 10 | 12 | 12 | 12 | 12 |  | 50 Ohms | TOP=L2:L3=L2/L4:L6=L5/L7:BOTTOM=L7 |
| I2C3_LS_G2 | OTHERS | BUS | 4 | 5 | 5 | 10 | 5 | 14 | 6 | 10 | 12 | 12 | 12 | 12 |  | 50 Ohms | TOP=L2:L3=L2/L4:L6=L5/L7:BOTTOM=L7 |
| I2C3_LS_G2 | OTHERS | BUS | 5 | 5 | 5 | 10 | 5 | 14 | 6 | 10 | 12 | 12 | 12 | 12 |  | 50 Ohms | TOP=L2:L3=L2/L4:L6=L5/L7:BOTTOM=L7 |
| I2C3_LS_G2 | OTHERS | BUS | 6 | 5 | 5 | 10 | 5 | 14 | 6 | 10 | 12 | 12 | 12 | 12 |  | 50 Ohms | TOP=L2:L3=L2/L4:L6=L5/L7:BOTTOM=L7 |
| I2C3_LS_G2 | OTHERS | BUS | 7 | 5 | 5 | 10 | 5 | 14 | 6 | 10 | 12 | 12 | 12 | 12 |  | 50 Ohms | TOP=L2:L3=L2/L4:L6=L5/L7:BOTTOM=L7 |
| I2C3_LS_G2 | OTHERS | BUS | 8 | 4.75 | 5 | 10 | 5 | 14 | 6 | 9.5 | 12 | 12 | 12 | 12 |  | 50 Ohms | TOP=L2:L3=L2/L4:L6=L5/L7:BOTTOM=L7 |
| I2C4_LS_G1 | OTHERS | BUS | 1 | 4.75 | 5 | 10 | 5 | 14 | 6 | 9.5 | 12 | 12 | 12 | 12 |  | 50 Ohms | TOP=L2:L3=L2/L4:L6=L5/L7:BOTTOM=L7 |
| I2C4_LS_G1 | OTHERS | BUS | 2 | 5 | 5 | 10 | 5 | 14 | 6 | 10 | 12 | 12 | 12 | 12 |  | 50 Ohms | TOP=L2:L3=L2/L4:L6=L5/L7:BOTTOM=L7 |
| I2C4_LS_G1 | OTHERS | BUS | 3 | 5 | 5 | 10 | 5 | 14 | 6 | 10 | 12 | 12 | 12 | 12 |  | 50 Ohms | TOP=L2:L3=L2/L4:L6=L5/L7:BOTTOM=L7 |
| I2C4_LS_G1 | OTHERS | BUS | 4 | 5 | 5 | 10 | 5 | 14 | 6 | 10 | 12 | 12 | 12 | 12 |  | 50 Ohms | TOP=L2:L3=L2/L4:L6=L5/L7:BOTTOM=L7 |
| I2C4_LS_G1 | OTHERS | BUS | 5 | 5 | 5 | 10 | 5 | 14 | 6 | 10 | 12 | 12 | 12 | 12 |  | 50 Ohms | TOP=L2:L3=L2/L4:L6=L5/L7:BOTTOM=L7 |
| I2C4_LS_G1 | OTHERS | BUS | 6 | 5 | 5 | 10 | 5 | 14 | 6 | 10 | 12 | 12 | 12 | 12 |  | 50 Ohms | TOP=L2:L3=L2/L4:L6=L5/L7:BOTTOM=L7 |
| I2C4_LS_G1 | OTHERS | BUS | 7 | 5 | 5 | 10 | 5 | 14 | 6 | 10 | 12 | 12 | 12 | 12 |  | 50 Ohms | TOP=L2:L3=L2/L4:L6=L5/L7:BOTTOM=L7 |
| I2C4_LS_G1 | OTHERS | BUS | 8 | 4.75 | 5 | 10 | 5 | 14 | 6 | 9.5 | 12 | 12 | 12 | 12 |  | 50 Ohms | TOP=L2:L3=L2/L4:L6=L5/L7:BOTTOM=L7 |
| I2C4_LS_G2 | OTHERS | BUS | 1 | 4.75 | 5 | 10 | 5 | 14 | 6 | 9.5 | 12 | 12 | 12 | 12 |  | 50 Ohms | TOP=L2:L3=L2/L4:L6=L5/L7:BOTTOM=L7 |
| I2C4_LS_G2 | OTHERS | BUS | 2 | 5 | 5 | 10 | 5 | 14 | 6 | 10 | 12 | 12 | 12 | 12 |  | 50 Ohms | TOP=L2:L3=L2/L4:L6=L5/L7:BOTTOM=L7 |
| I2C4_LS_G2 | OTHERS | BUS | 3 | 5 | 5 | 10 | 5 | 14 | 6 | 10 | 12 | 12 | 12 | 12 |  | 50 Ohms | TOP=L2:L3=L2/L4:L6=L5/L7:BOTTOM=L7 |
| I2C4_LS_G2 | OTHERS | BUS | 4 | 5 | 5 | 10 | 5 | 14 | 6 | 10 | 12 | 12 | 12 | 12 |  | 50 Ohms | TOP=L2:L3=L2/L4:L6=L5/L7:BOTTOM=L7 |
| I2C4_LS_G2 | OTHERS | BUS | 5 | 5 | 5 | 10 | 5 | 14 | 6 | 10 | 12 | 12 | 12 | 12 |  | 50 Ohms | TOP=L2:L3=L2/L4:L6=L5/L7:BOTTOM=L7 |
| I2C4_LS_G2 | OTHERS | BUS | 6 | 5 | 5 | 10 | 5 | 14 | 6 | 10 | 12 | 12 | 12 | 12 |  | 50 Ohms | TOP=L2:L3=L2/L4:L6=L5/L7:BOTTOM=L7 |
| I2C4_LS_G2 | OTHERS | BUS | 7 | 5 | 5 | 10 | 5 | 14 | 6 | 10 | 12 | 12 | 12 | 12 |  | 50 Ohms | TOP=L2:L3=L2/L4:L6=L5/L7:BOTTOM=L7 |
| I2C4_LS_G2 | OTHERS | BUS | 8 | 4.75 | 5 | 10 | 5 | 14 | 6 | 9.5 | 12 | 12 | 12 | 12 |  | 50 Ohms | TOP=L2:L3=L2/L4:L6=L5/L7:BOTTOM=L7 |
| I2C5_BUFF_EN | OTHERS | BUS | 1 | 4.75 | 5 | 10 | 5 | 14 | 6 | 9.5 | 12 | 12 | 12 | 12 |  | 50 Ohms | TOP=L2:L3=L2/L4:L6=L5/L7:BOTTOM=L7 |
| I2C5_BUFF_EN | OTHERS | BUS | 2 | 5 | 5 | 10 | 5 | 14 | 6 | 10 | 12 | 12 | 12 | 12 |  | 50 Ohms | TOP=L2:L3=L2/L4:L6=L5/L7:BOTTOM=L7 |
| I2C5_BUFF_EN | OTHERS | BUS | 3 | 5 | 5 | 10 | 5 | 14 | 6 | 10 | 12 | 12 | 12 | 12 |  | 50 Ohms | TOP=L2:L3=L2/L4:L6=L5/L7:BOTTOM=L7 |
| I2C5_BUFF_EN | OTHERS | BUS | 4 | 5 | 5 | 10 | 5 | 14 | 6 | 10 | 12 | 12 | 12 | 12 |  | 50 Ohms | TOP=L2:L3=L2/L4:L6=L5/L7:BOTTOM=L7 |
| I2C5_BUFF_EN | OTHERS | BUS | 5 | 5 | 5 | 10 | 5 | 14 | 6 | 10 | 12 | 12 | 12 | 12 |  | 50 Ohms | TOP=L2:L3=L2/L4:L6=L5/L7:BOTTOM=L7 |
| I2C5_BUFF_EN | OTHERS | BUS | 6 | 5 | 5 | 10 | 5 | 14 | 6 | 10 | 12 | 12 | 12 | 12 |  | 50 Ohms | TOP=L2:L3=L2/L4:L6=L5/L7:BOTTOM=L7 |
| I2C5_BUFF_EN | OTHERS | BUS | 7 | 5 | 5 | 10 | 5 | 14 | 6 | 10 | 12 | 12 | 12 | 12 |  | 50 Ohms | TOP=L2:L3=L2/L4:L6=L5/L7:BOTTOM=L7 |
| I2C5_BUFF_EN | OTHERS | BUS | 8 | 4.75 | 5 | 10 | 5 | 14 | 6 | 9.5 | 12 | 12 | 12 | 12 |  | 50 Ohms | TOP=L2:L3=L2/L4:L6=L5/L7:BOTTOM=L7 |
| I2C5_LS_G1 | OTHERS | BUS | 1 | 4.75 | 5 | 10 | 5 | 14 | 6 | 9.5 | 12 | 12 | 12 | 12 |  | 50 Ohms | TOP=L2:L3=L2/L4:L6=L5/L7:BOTTOM=L7 |
| I2C5_LS_G1 | OTHERS | BUS | 2 | 5 | 5 | 10 | 5 | 14 | 6 | 10 | 12 | 12 | 12 | 12 |  | 50 Ohms | TOP=L2:L3=L2/L4:L6=L5/L7:BOTTOM=L7 |
| I2C5_LS_G1 | OTHERS | BUS | 3 | 5 | 5 | 10 | 5 | 14 | 6 | 10 | 12 | 12 | 12 | 12 |  | 50 Ohms | TOP=L2:L3=L2/L4:L6=L5/L7:BOTTOM=L7 |
| I2C5_LS_G1 | OTHERS | BUS | 4 | 5 | 5 | 10 | 5 | 14 | 6 | 10 | 12 | 12 | 12 | 12 |  | 50 Ohms | TOP=L2:L3=L2/L4:L6=L5/L7:BOTTOM=L7 |
| I2C5_LS_G1 | OTHERS | BUS | 5 | 5 | 5 | 10 | 5 | 14 | 6 | 10 | 12 | 12 | 12 | 12 |  | 50 Ohms | TOP=L2:L3=L2/L4:L6=L5/L7:BOTTOM=L7 |
| I2C5_LS_G1 | OTHERS | BUS | 6 | 5 | 5 | 10 | 5 | 14 | 6 | 10 | 12 | 12 | 12 | 12 |  | 50 Ohms | TOP=L2:L3=L2/L4:L6=L5/L7:BOTTOM=L7 |
| I2C5_LS_G1 | OTHERS | BUS | 7 | 5 | 5 | 10 | 5 | 14 | 6 | 10 | 12 | 12 | 12 | 12 |  | 50 Ohms | TOP=L2:L3=L2/L4:L6=L5/L7:BOTTOM=L7 |
| I2C5_LS_G1 | OTHERS | BUS | 8 | 4.75 | 5 | 10 | 5 | 14 | 6 | 9.5 | 12 | 12 | 12 | 12 |  | 50 Ohms | TOP=L2:L3=L2/L4:L6=L5/L7:BOTTOM=L7 |
| I2C5_LS_G2 | OTHERS | BUS | 1 | 4.75 | 5 | 10 | 5 | 14 | 6 | 9.5 | 12 | 12 | 12 | 12 |  | 50 Ohms | TOP=L2:L3=L2/L4:L6=L5/L7:BOTTOM=L7 |
| I2C5_LS_G2 | OTHERS | BUS | 2 | 5 | 5 | 10 | 5 | 14 | 6 | 10 | 12 | 12 | 12 | 12 |  | 50 Ohms | TOP=L2:L3=L2/L4:L6=L5/L7:BOTTOM=L7 |
| I2C5_LS_G2 | OTHERS | BUS | 3 | 5 | 5 | 10 | 5 | 14 | 6 | 10 | 12 | 12 | 12 | 12 |  | 50 Ohms | TOP=L2:L3=L2/L4:L6=L5/L7:BOTTOM=L7 |
| I2C5_LS_G2 | OTHERS | BUS | 4 | 5 | 5 | 10 | 5 | 14 | 6 | 10 | 12 | 12 | 12 | 12 |  | 50 Ohms | TOP=L2:L3=L2/L4:L6=L5/L7:BOTTOM=L7 |
| I2C5_LS_G2 | OTHERS | BUS | 5 | 5 | 5 | 10 | 5 | 14 | 6 | 10 | 12 | 12 | 12 | 12 |  | 50 Ohms | TOP=L2:L3=L2/L4:L6=L5/L7:BOTTOM=L7 |
| I2C5_LS_G2 | OTHERS | BUS | 6 | 5 | 5 | 10 | 5 | 14 | 6 | 10 | 12 | 12 | 12 | 12 |  | 50 Ohms | TOP=L2:L3=L2/L4:L6=L5/L7:BOTTOM=L7 |
| I2C5_LS_G2 | OTHERS | BUS | 7 | 5 | 5 | 10 | 5 | 14 | 6 | 10 | 12 | 12 | 12 | 12 |  | 50 Ohms | TOP=L2:L3=L2/L4:L6=L5/L7:BOTTOM=L7 |
| I2C5_LS_G2 | OTHERS | BUS | 8 | 4.75 | 5 | 10 | 5 | 14 | 6 | 9.5 | 12 | 12 | 12 | 12 |  | 50 Ohms | TOP=L2:L3=L2/L4:L6=L5/L7:BOTTOM=L7 |
| I2C6_BUF_READY | OTHERS | BUS | 1 | 4.75 | 5 | 10 | 5 | 14 | 6 | 9.5 | 12 | 12 | 12 | 12 |  | 50 Ohms | TOP=L2:L3=L2/L4:L6=L5/L7:BOTTOM=L7 |
| I2C6_BUF_READY | OTHERS | BUS | 2 | 5 | 5 | 10 | 5 | 14 | 6 | 10 | 12 | 12 | 12 | 12 |  | 50 Ohms | TOP=L2:L3=L2/L4:L6=L5/L7:BOTTOM=L7 |
| I2C6_BUF_READY | OTHERS | BUS | 3 | 5 | 5 | 10 | 5 | 14 | 6 | 10 | 12 | 12 | 12 | 12 |  | 50 Ohms | TOP=L2:L3=L2/L4:L6=L5/L7:BOTTOM=L7 |
| I2C6_BUF_READY | OTHERS | BUS | 4 | 5 | 5 | 10 | 5 | 14 | 6 | 10 | 12 | 12 | 12 | 12 |  | 50 Ohms | TOP=L2:L3=L2/L4:L6=L5/L7:BOTTOM=L7 |
| I2C6_BUF_READY | OTHERS | BUS | 5 | 5 | 5 | 10 | 5 | 14 | 6 | 10 | 12 | 12 | 12 | 12 |  | 50 Ohms | TOP=L2:L3=L2/L4:L6=L5/L7:BOTTOM=L7 |
| I2C6_BUF_READY | OTHERS | BUS | 6 | 5 | 5 | 10 | 5 | 14 | 6 | 10 | 12 | 12 | 12 | 12 |  | 50 Ohms | TOP=L2:L3=L2/L4:L6=L5/L7:BOTTOM=L7 |
| I2C6_BUF_READY | OTHERS | BUS | 7 | 5 | 5 | 10 | 5 | 14 | 6 | 10 | 12 | 12 | 12 | 12 |  | 50 Ohms | TOP=L2:L3=L2/L4:L6=L5/L7:BOTTOM=L7 |
| I2C6_BUF_READY | OTHERS | BUS | 8 | 4.75 | 5 | 10 | 5 | 14 | 6 | 9.5 | 12 | 12 | 12 | 12 |  | 50 Ohms | TOP=L2:L3=L2/L4:L6=L5/L7:BOTTOM=L7 |
| I2C6_BUFF_EN | OTHERS | BUS | 1 | 4.75 | 5 | 10 | 5 | 14 | 6 | 9.5 | 12 | 12 | 12 | 12 |  | 50 Ohms | TOP=L2:L3=L2/L4:L6=L5/L7:BOTTOM=L7 |
| I2C6_BUFF_EN | OTHERS | BUS | 2 | 5 | 5 | 10 | 5 | 14 | 6 | 10 | 12 | 12 | 12 | 12 |  | 50 Ohms | TOP=L2:L3=L2/L4:L6=L5/L7:BOTTOM=L7 |
| I2C6_BUFF_EN | OTHERS | BUS | 3 | 5 | 5 | 10 | 5 | 14 | 6 | 10 | 12 | 12 | 12 | 12 |  | 50 Ohms | TOP=L2:L3=L2/L4:L6=L5/L7:BOTTOM=L7 |
| I2C6_BUFF_EN | OTHERS | BUS | 4 | 5 | 5 | 10 | 5 | 14 | 6 | 10 | 12 | 12 | 12 | 12 |  | 50 Ohms | TOP=L2:L3=L2/L4:L6=L5/L7:BOTTOM=L7 |
| I2C6_BUFF_EN | OTHERS | BUS | 5 | 5 | 5 | 10 | 5 | 14 | 6 | 10 | 12 | 12 | 12 | 12 |  | 50 Ohms | TOP=L2:L3=L2/L4:L6=L5/L7:BOTTOM=L7 |
| I2C6_BUFF_EN | OTHERS | BUS | 6 | 5 | 5 | 10 | 5 | 14 | 6 | 10 | 12 | 12 | 12 | 12 |  | 50 Ohms | TOP=L2:L3=L2/L4:L6=L5/L7:BOTTOM=L7 |
| I2C6_BUFF_EN | OTHERS | BUS | 7 | 5 | 5 | 10 | 5 | 14 | 6 | 10 | 12 | 12 | 12 | 12 |  | 50 Ohms | TOP=L2:L3=L2/L4:L6=L5/L7:BOTTOM=L7 |
| I2C6_BUFF_EN | OTHERS | BUS | 8 | 4.75 | 5 | 10 | 5 | 14 | 6 | 9.5 | 12 | 12 | 12 | 12 |  | 50 Ohms | TOP=L2:L3=L2/L4:L6=L5/L7:BOTTOM=L7 |
| I2C6_LS_G1 | OTHERS | BUS | 1 | 4.75 | 5 | 10 | 5 | 14 | 6 | 9.5 | 12 | 12 | 12 | 12 |  | 50 Ohms | TOP=L2:L3=L2/L4:L6=L5/L7:BOTTOM=L7 |
| I2C6_LS_G1 | OTHERS | BUS | 2 | 5 | 5 | 10 | 5 | 14 | 6 | 10 | 12 | 12 | 12 | 12 |  | 50 Ohms | TOP=L2:L3=L2/L4:L6=L5/L7:BOTTOM=L7 |
| I2C6_LS_G1 | OTHERS | BUS | 3 | 5 | 5 | 10 | 5 | 14 | 6 | 10 | 12 | 12 | 12 | 12 |  | 50 Ohms | TOP=L2:L3=L2/L4:L6=L5/L7:BOTTOM=L7 |
| I2C6_LS_G1 | OTHERS | BUS | 4 | 5 | 5 | 10 | 5 | 14 | 6 | 10 | 12 | 12 | 12 | 12 |  | 50 Ohms | TOP=L2:L3=L2/L4:L6=L5/L7:BOTTOM=L7 |
| I2C6_LS_G1 | OTHERS | BUS | 5 | 5 | 5 | 10 | 5 | 14 | 6 | 10 | 12 | 12 | 12 | 12 |  | 50 Ohms | TOP=L2:L3=L2/L4:L6=L5/L7:BOTTOM=L7 |
| I2C6_LS_G1 | OTHERS | BUS | 6 | 5 | 5 | 10 | 5 | 14 | 6 | 10 | 12 | 12 | 12 | 12 |  | 50 Ohms | TOP=L2:L3=L2/L4:L6=L5/L7:BOTTOM=L7 |
| I2C6_LS_G1 | OTHERS | BUS | 7 | 5 | 5 | 10 | 5 | 14 | 6 | 10 | 12 | 12 | 12 | 12 |  | 50 Ohms | TOP=L2:L3=L2/L4:L6=L5/L7:BOTTOM=L7 |
| I2C6_LS_G1 | OTHERS | BUS | 8 | 4.75 | 5 | 10 | 5 | 14 | 6 | 9.5 | 12 | 12 | 12 | 12 |  | 50 Ohms | TOP=L2:L3=L2/L4:L6=L5/L7:BOTTOM=L7 |
| I2C6_LS_G2 | OTHERS | BUS | 1 | 4.75 | 5 | 10 | 5 | 14 | 6 | 9.5 | 12 | 12 | 12 | 12 |  | 50 Ohms | TOP=L2:L3=L2/L4:L6=L5/L7:BOTTOM=L7 |
| I2C6_LS_G2 | OTHERS | BUS | 2 | 5 | 5 | 10 | 5 | 14 | 6 | 10 | 12 | 12 | 12 | 12 |  | 50 Ohms | TOP=L2:L3=L2/L4:L6=L5/L7:BOTTOM=L7 |
| I2C6_LS_G2 | OTHERS | BUS | 3 | 5 | 5 | 10 | 5 | 14 | 6 | 10 | 12 | 12 | 12 | 12 |  | 50 Ohms | TOP=L2:L3=L2/L4:L6=L5/L7:BOTTOM=L7 |
| I2C6_LS_G2 | OTHERS | BUS | 4 | 5 | 5 | 10 | 5 | 14 | 6 | 10 | 12 | 12 | 12 | 12 |  | 50 Ohms | TOP=L2:L3=L2/L4:L6=L5/L7:BOTTOM=L7 |
| I2C6_LS_G2 | OTHERS | BUS | 5 | 5 | 5 | 10 | 5 | 14 | 6 | 10 | 12 | 12 | 12 | 12 |  | 50 Ohms | TOP=L2:L3=L2/L4:L6=L5/L7:BOTTOM=L7 |
| I2C6_LS_G2 | OTHERS | BUS | 6 | 5 | 5 | 10 | 5 | 14 | 6 | 10 | 12 | 12 | 12 | 12 |  | 50 Ohms | TOP=L2:L3=L2/L4:L6=L5/L7:BOTTOM=L7 |
| I2C6_LS_G2 | OTHERS | BUS | 7 | 5 | 5 | 10 | 5 | 14 | 6 | 10 | 12 | 12 | 12 | 12 |  | 50 Ohms | TOP=L2:L3=L2/L4:L6=L5/L7:BOTTOM=L7 |
| I2C6_LS_G2 | OTHERS | BUS | 8 | 4.75 | 5 | 10 | 5 | 14 | 6 | 9.5 | 12 | 12 | 12 | 12 |  | 50 Ohms | TOP=L2:L3=L2/L4:L6=L5/L7:BOTTOM=L7 |
| I2C7_BUF_READY | OTHERS | BUS | 1 | 4.75 | 5 | 10 | 5 | 14 | 6 | 9.5 | 12 | 12 | 12 | 12 |  | 50 Ohms | TOP=L2:L3=L2/L4:L6=L5/L7:BOTTOM=L7 |
| I2C7_BUF_READY | OTHERS | BUS | 2 | 5 | 5 | 10 | 5 | 14 | 6 | 10 | 12 | 12 | 12 | 12 |  | 50 Ohms | TOP=L2:L3=L2/L4:L6=L5/L7:BOTTOM=L7 |
| I2C7_BUF_READY | OTHERS | BUS | 3 | 5 | 5 | 10 | 5 | 14 | 6 | 10 | 12 | 12 | 12 | 12 |  | 50 Ohms | TOP=L2:L3=L2/L4:L6=L5/L7:BOTTOM=L7 |
| I2C7_BUF_READY | OTHERS | BUS | 4 | 5 | 5 | 10 | 5 | 14 | 6 | 10 | 12 | 12 | 12 | 12 |  | 50 Ohms | TOP=L2:L3=L2/L4:L6=L5/L7:BOTTOM=L7 |
| I2C7_BUF_READY | OTHERS | BUS | 5 | 5 | 5 | 10 | 5 | 14 | 6 | 10 | 12 | 12 | 12 | 12 |  | 50 Ohms | TOP=L2:L3=L2/L4:L6=L5/L7:BOTTOM=L7 |
| I2C7_BUF_READY | OTHERS | BUS | 6 | 5 | 5 | 10 | 5 | 14 | 6 | 10 | 12 | 12 | 12 | 12 |  | 50 Ohms | TOP=L2:L3=L2/L4:L6=L5/L7:BOTTOM=L7 |
| I2C7_BUF_READY | OTHERS | BUS | 7 | 5 | 5 | 10 | 5 | 14 | 6 | 10 | 12 | 12 | 12 | 12 |  | 50 Ohms | TOP=L2:L3=L2/L4:L6=L5/L7:BOTTOM=L7 |
| I2C7_BUF_READY | OTHERS | BUS | 8 | 4.75 | 5 | 10 | 5 | 14 | 6 | 9.5 | 12 | 12 | 12 | 12 |  | 50 Ohms | TOP=L2:L3=L2/L4:L6=L5/L7:BOTTOM=L7 |
| I2C7_BUFF_EN | OTHERS | BUS | 1 | 4.75 | 5 | 10 | 5 | 14 | 6 | 9.5 | 12 | 12 | 12 | 12 |  | 50 Ohms | TOP=L2:L3=L2/L4:L6=L5/L7:BOTTOM=L7 |
| I2C7_BUFF_EN | OTHERS | BUS | 2 | 5 | 5 | 10 | 5 | 14 | 6 | 10 | 12 | 12 | 12 | 12 |  | 50 Ohms | TOP=L2:L3=L2/L4:L6=L5/L7:BOTTOM=L7 |
| I2C7_BUFF_EN | OTHERS | BUS | 3 | 5 | 5 | 10 | 5 | 14 | 6 | 10 | 12 | 12 | 12 | 12 |  | 50 Ohms | TOP=L2:L3=L2/L4:L6=L5/L7:BOTTOM=L7 |
| I2C7_BUFF_EN | OTHERS | BUS | 4 | 5 | 5 | 10 | 5 | 14 | 6 | 10 | 12 | 12 | 12 | 12 |  | 50 Ohms | TOP=L2:L3=L2/L4:L6=L5/L7:BOTTOM=L7 |
| I2C7_BUFF_EN | OTHERS | BUS | 5 | 5 | 5 | 10 | 5 | 14 | 6 | 10 | 12 | 12 | 12 | 12 |  | 50 Ohms | TOP=L2:L3=L2/L4:L6=L5/L7:BOTTOM=L7 |
| I2C7_BUFF_EN | OTHERS | BUS | 6 | 5 | 5 | 10 | 5 | 14 | 6 | 10 | 12 | 12 | 12 | 12 |  | 50 Ohms | TOP=L2:L3=L2/L4:L6=L5/L7:BOTTOM=L7 |
| I2C7_BUFF_EN | OTHERS | BUS | 7 | 5 | 5 | 10 | 5 | 14 | 6 | 10 | 12 | 12 | 12 | 12 |  | 50 Ohms | TOP=L2:L3=L2/L4:L6=L5/L7:BOTTOM=L7 |
| I2C7_BUFF_EN | OTHERS | BUS | 8 | 4.75 | 5 | 10 | 5 | 14 | 6 | 9.5 | 12 | 12 | 12 | 12 |  | 50 Ohms | TOP=L2:L3=L2/L4:L6=L5/L7:BOTTOM=L7 |
| I2C7_LS_G1 | OTHERS | BUS | 1 | 4.75 | 5 | 10 | 5 | 14 | 6 | 9.5 | 12 | 12 | 12 | 12 |  | 50 Ohms | TOP=L2:L3=L2/L4:L6=L5/L7:BOTTOM=L7 |
| I2C7_LS_G1 | OTHERS | BUS | 2 | 5 | 5 | 10 | 5 | 14 | 6 | 10 | 12 | 12 | 12 | 12 |  | 50 Ohms | TOP=L2:L3=L2/L4:L6=L5/L7:BOTTOM=L7 |
| I2C7_LS_G1 | OTHERS | BUS | 3 | 5 | 5 | 10 | 5 | 14 | 6 | 10 | 12 | 12 | 12 | 12 |  | 50 Ohms | TOP=L2:L3=L2/L4:L6=L5/L7:BOTTOM=L7 |
| I2C7_LS_G1 | OTHERS | BUS | 4 | 5 | 5 | 10 | 5 | 14 | 6 | 10 | 12 | 12 | 12 | 12 |  | 50 Ohms | TOP=L2:L3=L2/L4:L6=L5/L7:BOTTOM=L7 |
| I2C7_LS_G1 | OTHERS | BUS | 5 | 5 | 5 | 10 | 5 | 14 | 6 | 10 | 12 | 12 | 12 | 12 |  | 50 Ohms | TOP=L2:L3=L2/L4:L6=L5/L7:BOTTOM=L7 |
| I2C7_LS_G1 | OTHERS | BUS | 6 | 5 | 5 | 10 | 5 | 14 | 6 | 10 | 12 | 12 | 12 | 12 |  | 50 Ohms | TOP=L2:L3=L2/L4:L6=L5/L7:BOTTOM=L7 |
| I2C7_LS_G1 | OTHERS | BUS | 7 | 5 | 5 | 10 | 5 | 14 | 6 | 10 | 12 | 12 | 12 | 12 |  | 50 Ohms | TOP=L2:L3=L2/L4:L6=L5/L7:BOTTOM=L7 |
| I2C7_LS_G1 | OTHERS | BUS | 8 | 4.75 | 5 | 10 | 5 | 14 | 6 | 9.5 | 12 | 12 | 12 | 12 |  | 50 Ohms | TOP=L2:L3=L2/L4:L6=L5/L7:BOTTOM=L7 |
| I2C7_LS_G2 | OTHERS | BUS | 1 | 4.75 | 5 | 10 | 5 | 14 | 6 | 9.5 | 12 | 12 | 12 | 12 |  | 50 Ohms | TOP=L2:L3=L2/L4:L6=L5/L7:BOTTOM=L7 |
| I2C7_LS_G2 | OTHERS | BUS | 2 | 5 | 5 | 10 | 5 | 14 | 6 | 10 | 12 | 12 | 12 | 12 |  | 50 Ohms | TOP=L2:L3=L2/L4:L6=L5/L7:BOTTOM=L7 |
| I2C7_LS_G2 | OTHERS | BUS | 3 | 5 | 5 | 10 | 5 | 14 | 6 | 10 | 12 | 12 | 12 | 12 |  | 50 Ohms | TOP=L2:L3=L2/L4:L6=L5/L7:BOTTOM=L7 |
| I2C7_LS_G2 | OTHERS | BUS | 4 | 5 | 5 | 10 | 5 | 14 | 6 | 10 | 12 | 12 | 12 | 12 |  | 50 Ohms | TOP=L2:L3=L2/L4:L6=L5/L7:BOTTOM=L7 |
| I2C7_LS_G2 | OTHERS | BUS | 5 | 5 | 5 | 10 | 5 | 14 | 6 | 10 | 12 | 12 | 12 | 12 |  | 50 Ohms | TOP=L2:L3=L2/L4:L6=L5/L7:BOTTOM=L7 |
| I2C7_LS_G2 | OTHERS | BUS | 6 | 5 | 5 | 10 | 5 | 14 | 6 | 10 | 12 | 12 | 12 | 12 |  | 50 Ohms | TOP=L2:L3=L2/L4:L6=L5/L7:BOTTOM=L7 |
| I2C7_LS_G2 | OTHERS | BUS | 7 | 5 | 5 | 10 | 5 | 14 | 6 | 10 | 12 | 12 | 12 | 12 |  | 50 Ohms | TOP=L2:L3=L2/L4:L6=L5/L7:BOTTOM=L7 |
| I2C7_LS_G2 | OTHERS | BUS | 8 | 4.75 | 5 | 10 | 5 | 14 | 6 | 9.5 | 12 | 12 | 12 | 12 |  | 50 Ohms | TOP=L2:L3=L2/L4:L6=L5/L7:BOTTOM=L7 |
| I2C8_BUF_READY | OTHERS | BUS | 1 | 4.75 | 5 | 10 | 5 | 14 | 6 | 9.5 | 12 | 12 | 12 | 12 |  | 50 Ohms | TOP=L2:L3=L2/L4:L6=L5/L7:BOTTOM=L7 |
| I2C8_BUF_READY | OTHERS | BUS | 2 | 5 | 5 | 10 | 5 | 14 | 6 | 10 | 12 | 12 | 12 | 12 |  | 50 Ohms | TOP=L2:L3=L2/L4:L6=L5/L7:BOTTOM=L7 |
| I2C8_BUF_READY | OTHERS | BUS | 3 | 5 | 5 | 10 | 5 | 14 | 6 | 10 | 12 | 12 | 12 | 12 |  | 50 Ohms | TOP=L2:L3=L2/L4:L6=L5/L7:BOTTOM=L7 |
| I2C8_BUF_READY | OTHERS | BUS | 4 | 5 | 5 | 10 | 5 | 14 | 6 | 10 | 12 | 12 | 12 | 12 |  | 50 Ohms | TOP=L2:L3=L2/L4:L6=L5/L7:BOTTOM=L7 |
| I2C8_BUF_READY | OTHERS | BUS | 5 | 5 | 5 | 10 | 5 | 14 | 6 | 10 | 12 | 12 | 12 | 12 |  | 50 Ohms | TOP=L2:L3=L2/L4:L6=L5/L7:BOTTOM=L7 |
| I2C8_BUF_READY | OTHERS | BUS | 6 | 5 | 5 | 10 | 5 | 14 | 6 | 10 | 12 | 12 | 12 | 12 |  | 50 Ohms | TOP=L2:L3=L2/L4:L6=L5/L7:BOTTOM=L7 |
| I2C8_BUF_READY | OTHERS | BUS | 7 | 5 | 5 | 10 | 5 | 14 | 6 | 10 | 12 | 12 | 12 | 12 |  | 50 Ohms | TOP=L2:L3=L2/L4:L6=L5/L7:BOTTOM=L7 |
| I2C8_BUF_READY | OTHERS | BUS | 8 | 4.75 | 5 | 10 | 5 | 14 | 6 | 9.5 | 12 | 12 | 12 | 12 |  | 50 Ohms | TOP=L2:L3=L2/L4:L6=L5/L7:BOTTOM=L7 |
| I2C8_BUFF_EN | OTHERS | BUS | 1 | 4.75 | 5 | 10 | 5 | 14 | 6 | 9.5 | 12 | 12 | 12 | 12 |  | 50 Ohms | TOP=L2:L3=L2/L4:L6=L5/L7:BOTTOM=L7 |
| I2C8_BUFF_EN | OTHERS | BUS | 2 | 5 | 5 | 10 | 5 | 14 | 6 | 10 | 12 | 12 | 12 | 12 |  | 50 Ohms | TOP=L2:L3=L2/L4:L6=L5/L7:BOTTOM=L7 |
| I2C8_BUFF_EN | OTHERS | BUS | 3 | 5 | 5 | 10 | 5 | 14 | 6 | 10 | 12 | 12 | 12 | 12 |  | 50 Ohms | TOP=L2:L3=L2/L4:L6=L5/L7:BOTTOM=L7 |
| I2C8_BUFF_EN | OTHERS | BUS | 4 | 5 | 5 | 10 | 5 | 14 | 6 | 10 | 12 | 12 | 12 | 12 |  | 50 Ohms | TOP=L2:L3=L2/L4:L6=L5/L7:BOTTOM=L7 |
| I2C8_BUFF_EN | OTHERS | BUS | 5 | 5 | 5 | 10 | 5 | 14 | 6 | 10 | 12 | 12 | 12 | 12 |  | 50 Ohms | TOP=L2:L3=L2/L4:L6=L5/L7:BOTTOM=L7 |
| I2C8_BUFF_EN | OTHERS | BUS | 6 | 5 | 5 | 10 | 5 | 14 | 6 | 10 | 12 | 12 | 12 | 12 |  | 50 Ohms | TOP=L2:L3=L2/L4:L6=L5/L7:BOTTOM=L7 |
| I2C8_BUFF_EN | OTHERS | BUS | 7 | 5 | 5 | 10 | 5 | 14 | 6 | 10 | 12 | 12 | 12 | 12 |  | 50 Ohms | TOP=L2:L3=L2/L4:L6=L5/L7:BOTTOM=L7 |
| I2C8_BUFF_EN | OTHERS | BUS | 8 | 4.75 | 5 | 10 | 5 | 14 | 6 | 9.5 | 12 | 12 | 12 | 12 |  | 50 Ohms | TOP=L2:L3=L2/L4:L6=L5/L7:BOTTOM=L7 |
| I2C8_LS_G1 | OTHERS | BUS | 1 | 4.75 | 5 | 10 | 5 | 14 | 6 | 9.5 | 12 | 12 | 12 | 12 |  | 50 Ohms | TOP=L2:L3=L2/L4:L6=L5/L7:BOTTOM=L7 |
| I2C8_LS_G1 | OTHERS | BUS | 2 | 5 | 5 | 10 | 5 | 14 | 6 | 10 | 12 | 12 | 12 | 12 |  | 50 Ohms | TOP=L2:L3=L2/L4:L6=L5/L7:BOTTOM=L7 |
| I2C8_LS_G1 | OTHERS | BUS | 3 | 5 | 5 | 10 | 5 | 14 | 6 | 10 | 12 | 12 | 12 | 12 |  | 50 Ohms | TOP=L2:L3=L2/L4:L6=L5/L7:BOTTOM=L7 |
| I2C8_LS_G1 | OTHERS | BUS | 4 | 5 | 5 | 10 | 5 | 14 | 6 | 10 | 12 | 12 | 12 | 12 |  | 50 Ohms | TOP=L2:L3=L2/L4:L6=L5/L7:BOTTOM=L7 |
| I2C8_LS_G1 | OTHERS | BUS | 5 | 5 | 5 | 10 | 5 | 14 | 6 | 10 | 12 | 12 | 12 | 12 |  | 50 Ohms | TOP=L2:L3=L2/L4:L6=L5/L7:BOTTOM=L7 |
| I2C8_LS_G1 | OTHERS | BUS | 6 | 5 | 5 | 10 | 5 | 14 | 6 | 10 | 12 | 12 | 12 | 12 |  | 50 Ohms | TOP=L2:L3=L2/L4:L6=L5/L7:BOTTOM=L7 |
| I2C8_LS_G1 | OTHERS | BUS | 7 | 5 | 5 | 10 | 5 | 14 | 6 | 10 | 12 | 12 | 12 | 12 |  | 50 Ohms | TOP=L2:L3=L2/L4:L6=L5/L7:BOTTOM=L7 |
| I2C8_LS_G1 | OTHERS | BUS | 8 | 4.75 | 5 | 10 | 5 | 14 | 6 | 9.5 | 12 | 12 | 12 | 12 |  | 50 Ohms | TOP=L2:L3=L2/L4:L6=L5/L7:BOTTOM=L7 |
| I2C8_LS_G2 | OTHERS | BUS | 1 | 4.75 | 5 | 10 | 5 | 14 | 6 | 9.5 | 12 | 12 | 12 | 12 |  | 50 Ohms | TOP=L2:L3=L2/L4:L6=L5/L7:BOTTOM=L7 |
| I2C8_LS_G2 | OTHERS | BUS | 2 | 5 | 5 | 10 | 5 | 14 | 6 | 10 | 12 | 12 | 12 | 12 |  | 50 Ohms | TOP=L2:L3=L2/L4:L6=L5/L7:BOTTOM=L7 |
| I2C8_LS_G2 | OTHERS | BUS | 3 | 5 | 5 | 10 | 5 | 14 | 6 | 10 | 12 | 12 | 12 | 12 |  | 50 Ohms | TOP=L2:L3=L2/L4:L6=L5/L7:BOTTOM=L7 |
| I2C8_LS_G2 | OTHERS | BUS | 4 | 5 | 5 | 10 | 5 | 14 | 6 | 10 | 12 | 12 | 12 | 12 |  | 50 Ohms | TOP=L2:L3=L2/L4:L6=L5/L7:BOTTOM=L7 |
| I2C8_LS_G2 | OTHERS | BUS | 5 | 5 | 5 | 10 | 5 | 14 | 6 | 10 | 12 | 12 | 12 | 12 |  | 50 Ohms | TOP=L2:L3=L2/L4:L6=L5/L7:BOTTOM=L7 |
| I2C8_LS_G2 | OTHERS | BUS | 6 | 5 | 5 | 10 | 5 | 14 | 6 | 10 | 12 | 12 | 12 | 12 |  | 50 Ohms | TOP=L2:L3=L2/L4:L6=L5/L7:BOTTOM=L7 |
| I2C8_LS_G2 | OTHERS | BUS | 7 | 5 | 5 | 10 | 5 | 14 | 6 | 10 | 12 | 12 | 12 | 12 |  | 50 Ohms | TOP=L2:L3=L2/L4:L6=L5/L7:BOTTOM=L7 |
| I2C8_LS_G2 | OTHERS | BUS | 8 | 4.75 | 5 | 10 | 5 | 14 | 6 | 9.5 | 12 | 12 | 12 | 12 |  | 50 Ohms | TOP=L2:L3=L2/L4:L6=L5/L7:BOTTOM=L7 |
| I2C9_BUF_READY | OTHERS | BUS | 1 | 4.75 | 5 | 10 | 5 | 14 | 6 | 9.5 | 12 | 12 | 12 | 12 |  | 50 Ohms | TOP=L2:L3=L2/L4:L6=L5/L7:BOTTOM=L7 |
| I2C9_BUF_READY | OTHERS | BUS | 2 | 5 | 5 | 10 | 5 | 14 | 6 | 10 | 12 | 12 | 12 | 12 |  | 50 Ohms | TOP=L2:L3=L2/L4:L6=L5/L7:BOTTOM=L7 |
| I2C9_BUF_READY | OTHERS | BUS | 3 | 5 | 5 | 10 | 5 | 14 | 6 | 10 | 12 | 12 | 12 | 12 |  | 50 Ohms | TOP=L2:L3=L2/L4:L6=L5/L7:BOTTOM=L7 |
| I2C9_BUF_READY | OTHERS | BUS | 4 | 5 | 5 | 10 | 5 | 14 | 6 | 10 | 12 | 12 | 12 | 12 |  | 50 Ohms | TOP=L2:L3=L2/L4:L6=L5/L7:BOTTOM=L7 |
| I2C9_BUF_READY | OTHERS | BUS | 5 | 5 | 5 | 10 | 5 | 14 | 6 | 10 | 12 | 12 | 12 | 12 |  | 50 Ohms | TOP=L2:L3=L2/L4:L6=L5/L7:BOTTOM=L7 |
| I2C9_BUF_READY | OTHERS | BUS | 6 | 5 | 5 | 10 | 5 | 14 | 6 | 10 | 12 | 12 | 12 | 12 |  | 50 Ohms | TOP=L2:L3=L2/L4:L6=L5/L7:BOTTOM=L7 |
| I2C9_BUF_READY | OTHERS | BUS | 7 | 5 | 5 | 10 | 5 | 14 | 6 | 10 | 12 | 12 | 12 | 12 |  | 50 Ohms | TOP=L2:L3=L2/L4:L6=L5/L7:BOTTOM=L7 |
| I2C9_BUF_READY | OTHERS | BUS | 8 | 4.75 | 5 | 10 | 5 | 14 | 6 | 9.5 | 12 | 12 | 12 | 12 |  | 50 Ohms | TOP=L2:L3=L2/L4:L6=L5/L7:BOTTOM=L7 |
| I2C9_BUFF_EN | OTHERS | BUS | 1 | 4.75 | 5 | 10 | 5 | 14 | 6 | 9.5 | 12 | 12 | 12 | 12 |  | 50 Ohms | TOP=L2:L3=L2/L4:L6=L5/L7:BOTTOM=L7 |
| I2C9_BUFF_EN | OTHERS | BUS | 2 | 5 | 5 | 10 | 5 | 14 | 6 | 10 | 12 | 12 | 12 | 12 |  | 50 Ohms | TOP=L2:L3=L2/L4:L6=L5/L7:BOTTOM=L7 |
| I2C9_BUFF_EN | OTHERS | BUS | 3 | 5 | 5 | 10 | 5 | 14 | 6 | 10 | 12 | 12 | 12 | 12 |  | 50 Ohms | TOP=L2:L3=L2/L4:L6=L5/L7:BOTTOM=L7 |
| I2C9_BUFF_EN | OTHERS | BUS | 4 | 5 | 5 | 10 | 5 | 14 | 6 | 10 | 12 | 12 | 12 | 12 |  | 50 Ohms | TOP=L2:L3=L2/L4:L6=L5/L7:BOTTOM=L7 |
| I2C9_BUFF_EN | OTHERS | BUS | 5 | 5 | 5 | 10 | 5 | 14 | 6 | 10 | 12 | 12 | 12 | 12 |  | 50 Ohms | TOP=L2:L3=L2/L4:L6=L5/L7:BOTTOM=L7 |
| I2C9_BUFF_EN | OTHERS | BUS | 6 | 5 | 5 | 10 | 5 | 14 | 6 | 10 | 12 | 12 | 12 | 12 |  | 50 Ohms | TOP=L2:L3=L2/L4:L6=L5/L7:BOTTOM=L7 |
| I2C9_BUFF_EN | OTHERS | BUS | 7 | 5 | 5 | 10 | 5 | 14 | 6 | 10 | 12 | 12 | 12 | 12 |  | 50 Ohms | TOP=L2:L3=L2/L4:L6=L5/L7:BOTTOM=L7 |
| I2C9_BUFF_EN | OTHERS | BUS | 8 | 4.75 | 5 | 10 | 5 | 14 | 6 | 9.5 | 12 | 12 | 12 | 12 |  | 50 Ohms | TOP=L2:L3=L2/L4:L6=L5/L7:BOTTOM=L7 |
| INVERTER_G1 | OTHERS | BUS | 1 | 4.75 | 5 | 10 | 5 | 14 | 6 | 9.5 | 12 | 12 | 12 | 12 |  | 50 Ohms | TOP=L2:L3=L2/L4:L6=L5/L7:BOTTOM=L7 |
| INVERTER_G1 | OTHERS | BUS | 2 | 5 | 5 | 10 | 5 | 14 | 6 | 10 | 12 | 12 | 12 | 12 |  | 50 Ohms | TOP=L2:L3=L2/L4:L6=L5/L7:BOTTOM=L7 |
| INVERTER_G1 | OTHERS | BUS | 3 | 5 | 5 | 10 | 5 | 14 | 6 | 10 | 12 | 12 | 12 | 12 |  | 50 Ohms | TOP=L2:L3=L2/L4:L6=L5/L7:BOTTOM=L7 |
| INVERTER_G1 | OTHERS | BUS | 4 | 5 | 5 | 10 | 5 | 14 | 6 | 10 | 12 | 12 | 12 | 12 |  | 50 Ohms | TOP=L2:L3=L2/L4:L6=L5/L7:BOTTOM=L7 |
| INVERTER_G1 | OTHERS | BUS | 5 | 5 | 5 | 10 | 5 | 14 | 6 | 10 | 12 | 12 | 12 | 12 |  | 50 Ohms | TOP=L2:L3=L2/L4:L6=L5/L7:BOTTOM=L7 |
| INVERTER_G1 | OTHERS | BUS | 6 | 5 | 5 | 10 | 5 | 14 | 6 | 10 | 12 | 12 | 12 | 12 |  | 50 Ohms | TOP=L2:L3=L2/L4:L6=L5/L7:BOTTOM=L7 |
| INVERTER_G1 | OTHERS | BUS | 7 | 5 | 5 | 10 | 5 | 14 | 6 | 10 | 12 | 12 | 12 | 12 |  | 50 Ohms | TOP=L2:L3=L2/L4:L6=L5/L7:BOTTOM=L7 |
| INVERTER_G1 | OTHERS | BUS | 8 | 4.75 | 5 | 10 | 5 | 14 | 6 | 9.5 | 12 | 12 | 12 | 12 |  | 50 Ohms | TOP=L2:L3=L2/L4:L6=L5/L7:BOTTOM=L7 |
| INVERTER_G2 | OTHERS | BUS | 1 | 4.75 | 5 | 10 | 5 | 14 | 6 | 9.5 | 12 | 12 | 12 | 12 |  | 50 Ohms | TOP=L2:L3=L2/L4:L6=L5/L7:BOTTOM=L7 |
| INVERTER_G2 | OTHERS | BUS | 2 | 5 | 5 | 10 | 5 | 14 | 6 | 10 | 12 | 12 | 12 | 12 |  | 50 Ohms | TOP=L2:L3=L2/L4:L6=L5/L7:BOTTOM=L7 |
| INVERTER_G2 | OTHERS | BUS | 3 | 5 | 5 | 10 | 5 | 14 | 6 | 10 | 12 | 12 | 12 | 12 |  | 50 Ohms | TOP=L2:L3=L2/L4:L6=L5/L7:BOTTOM=L7 |
| INVERTER_G2 | OTHERS | BUS | 4 | 5 | 5 | 10 | 5 | 14 | 6 | 10 | 12 | 12 | 12 | 12 |  | 50 Ohms | TOP=L2:L3=L2/L4:L6=L5/L7:BOTTOM=L7 |
| INVERTER_G2 | OTHERS | BUS | 5 | 5 | 5 | 10 | 5 | 14 | 6 | 10 | 12 | 12 | 12 | 12 |  | 50 Ohms | TOP=L2:L3=L2/L4:L6=L5/L7:BOTTOM=L7 |
| INVERTER_G2 | OTHERS | BUS | 6 | 5 | 5 | 10 | 5 | 14 | 6 | 10 | 12 | 12 | 12 | 12 |  | 50 Ohms | TOP=L2:L3=L2/L4:L6=L5/L7:BOTTOM=L7 |
| INVERTER_G2 | OTHERS | BUS | 7 | 5 | 5 | 10 | 5 | 14 | 6 | 10 | 12 | 12 | 12 | 12 |  | 50 Ohms | TOP=L2:L3=L2/L4:L6=L5/L7:BOTTOM=L7 |
| INVERTER_G2 | OTHERS | BUS | 8 | 4.75 | 5 | 10 | 5 | 14 | 6 | 9.5 | 12 | 12 | 12 | 12 |  | 50 Ohms | TOP=L2:L3=L2/L4:L6=L5/L7:BOTTOM=L7 |
| IOEXP_INT#_1 | OTHERS | BUS | 1 | 4.75 | 5 | 10 | 5 | 14 | 6 | 9.5 | 12 | 12 | 12 | 12 |  | 50 Ohms | TOP=L2:L3=L2/L4:L6=L5/L7:BOTTOM=L7 |
| IOEXP_INT#_1 | OTHERS | BUS | 2 | 5 | 5 | 10 | 5 | 14 | 6 | 10 | 12 | 12 | 12 | 12 |  | 50 Ohms | TOP=L2:L3=L2/L4:L6=L5/L7:BOTTOM=L7 |
| IOEXP_INT#_1 | OTHERS | BUS | 3 | 5 | 5 | 10 | 5 | 14 | 6 | 10 | 12 | 12 | 12 | 12 |  | 50 Ohms | TOP=L2:L3=L2/L4:L6=L5/L7:BOTTOM=L7 |
| IOEXP_INT#_1 | OTHERS | BUS | 4 | 5 | 5 | 10 | 5 | 14 | 6 | 10 | 12 | 12 | 12 | 12 |  | 50 Ohms | TOP=L2:L3=L2/L4:L6=L5/L7:BOTTOM=L7 |
| IOEXP_INT#_1 | OTHERS | BUS | 5 | 5 | 5 | 10 | 5 | 14 | 6 | 10 | 12 | 12 | 12 | 12 |  | 50 Ohms | TOP=L2:L3=L2/L4:L6=L5/L7:BOTTOM=L7 |
| IOEXP_INT#_1 | OTHERS | BUS | 6 | 5 | 5 | 10 | 5 | 14 | 6 | 10 | 12 | 12 | 12 | 12 |  | 50 Ohms | TOP=L2:L3=L2/L4:L6=L5/L7:BOTTOM=L7 |
| IOEXP_INT#_1 | OTHERS | BUS | 7 | 5 | 5 | 10 | 5 | 14 | 6 | 10 | 12 | 12 | 12 | 12 |  | 50 Ohms | TOP=L2:L3=L2/L4:L6=L5/L7:BOTTOM=L7 |
| IOEXP_INT#_1 | OTHERS | BUS | 8 | 4.75 | 5 | 10 | 5 | 14 | 6 | 9.5 | 12 | 12 | 12 | 12 |  | 50 Ohms | TOP=L2:L3=L2/L4:L6=L5/L7:BOTTOM=L7 |
| IOEXP_INT#_2 | OTHERS | BUS | 1 | 4.75 | 5 | 10 | 5 | 14 | 6 | 9.5 | 12 | 12 | 12 | 12 |  | 50 Ohms | TOP=L2:L3=L2/L4:L6=L5/L7:BOTTOM=L7 |
| IOEXP_INT#_2 | OTHERS | BUS | 2 | 5 | 5 | 10 | 5 | 14 | 6 | 10 | 12 | 12 | 12 | 12 |  | 50 Ohms | TOP=L2:L3=L2/L4:L6=L5/L7:BOTTOM=L7 |
| IOEXP_INT#_2 | OTHERS | BUS | 3 | 5 | 5 | 10 | 5 | 14 | 6 | 10 | 12 | 12 | 12 | 12 |  | 50 Ohms | TOP=L2:L3=L2/L4:L6=L5/L7:BOTTOM=L7 |
| IOEXP_INT#_2 | OTHERS | BUS | 4 | 5 | 5 | 10 | 5 | 14 | 6 | 10 | 12 | 12 | 12 | 12 |  | 50 Ohms | TOP=L2:L3=L2/L4:L6=L5/L7:BOTTOM=L7 |
| IOEXP_INT#_2 | OTHERS | BUS | 5 | 5 | 5 | 10 | 5 | 14 | 6 | 10 | 12 | 12 | 12 | 12 |  | 50 Ohms | TOP=L2:L3=L2/L4:L6=L5/L7:BOTTOM=L7 |
| IOEXP_INT#_2 | OTHERS | BUS | 6 | 5 | 5 | 10 | 5 | 14 | 6 | 10 | 12 | 12 | 12 | 12 |  | 50 Ohms | TOP=L2:L3=L2/L4:L6=L5/L7:BOTTOM=L7 |
| IOEXP_INT#_2 | OTHERS | BUS | 7 | 5 | 5 | 10 | 5 | 14 | 6 | 10 | 12 | 12 | 12 | 12 |  | 50 Ohms | TOP=L2:L3=L2/L4:L6=L5/L7:BOTTOM=L7 |
| IOEXP_INT#_2 | OTHERS | BUS | 8 | 4.75 | 5 | 10 | 5 | 14 | 6 | 9.5 | 12 | 12 | 12 | 12 |  | 50 Ohms | TOP=L2:L3=L2/L4:L6=L5/L7:BOTTOM=L7 |
| IOEXP_INT#_3 | OTHERS | BUS | 1 | 4.75 | 5 | 10 | 5 | 14 | 6 | 9.5 | 12 | 12 | 12 | 12 |  | 50 Ohms | TOP=L2:L3=L2/L4:L6=L5/L7:BOTTOM=L7 |
| IOEXP_INT#_3 | OTHERS | BUS | 2 | 5 | 5 | 10 | 5 | 14 | 6 | 10 | 12 | 12 | 12 | 12 |  | 50 Ohms | TOP=L2:L3=L2/L4:L6=L5/L7:BOTTOM=L7 |
| IOEXP_INT#_3 | OTHERS | BUS | 3 | 5 | 5 | 10 | 5 | 14 | 6 | 10 | 12 | 12 | 12 | 12 |  | 50 Ohms | TOP=L2:L3=L2/L4:L6=L5/L7:BOTTOM=L7 |
| IOEXP_INT#_3 | OTHERS | BUS | 4 | 5 | 5 | 10 | 5 | 14 | 6 | 10 | 12 | 12 | 12 | 12 |  | 50 Ohms | TOP=L2:L3=L2/L4:L6=L5/L7:BOTTOM=L7 |
| IOEXP_INT#_3 | OTHERS | BUS | 5 | 5 | 5 | 10 | 5 | 14 | 6 | 10 | 12 | 12 | 12 | 12 |  | 50 Ohms | TOP=L2:L3=L2/L4:L6=L5/L7:BOTTOM=L7 |
| IOEXP_INT#_3 | OTHERS | BUS | 6 | 5 | 5 | 10 | 5 | 14 | 6 | 10 | 12 | 12 | 12 | 12 |  | 50 Ohms | TOP=L2:L3=L2/L4:L6=L5/L7:BOTTOM=L7 |
| IOEXP_INT#_3 | OTHERS | BUS | 7 | 5 | 5 | 10 | 5 | 14 | 6 | 10 | 12 | 12 | 12 | 12 |  | 50 Ohms | TOP=L2:L3=L2/L4:L6=L5/L7:BOTTOM=L7 |
| IOEXP_INT#_3 | OTHERS | BUS | 8 | 4.75 | 5 | 10 | 5 | 14 | 6 | 9.5 | 12 | 12 | 12 | 12 |  | 50 Ohms | TOP=L2:L3=L2/L4:L6=L5/L7:BOTTOM=L7 |
| IOEXP_INT#_4 | OTHERS | BUS | 1 | 4.75 | 5 | 10 | 5 | 14 | 6 | 9.5 | 12 | 12 | 12 | 12 |  | 50 Ohms | TOP=L2:L3=L2/L4:L6=L5/L7:BOTTOM=L7 |
| IOEXP_INT#_4 | OTHERS | BUS | 2 | 5 | 5 | 10 | 5 | 14 | 6 | 10 | 12 | 12 | 12 | 12 |  | 50 Ohms | TOP=L2:L3=L2/L4:L6=L5/L7:BOTTOM=L7 |
| IOEXP_INT#_4 | OTHERS | BUS | 3 | 5 | 5 | 10 | 5 | 14 | 6 | 10 | 12 | 12 | 12 | 12 |  | 50 Ohms | TOP=L2:L3=L2/L4:L6=L5/L7:BOTTOM=L7 |
| IOEXP_INT#_4 | OTHERS | BUS | 4 | 5 | 5 | 10 | 5 | 14 | 6 | 10 | 12 | 12 | 12 | 12 |  | 50 Ohms | TOP=L2:L3=L2/L4:L6=L5/L7:BOTTOM=L7 |
| IOEXP_INT#_4 | OTHERS | BUS | 5 | 5 | 5 | 10 | 5 | 14 | 6 | 10 | 12 | 12 | 12 | 12 |  | 50 Ohms | TOP=L2:L3=L2/L4:L6=L5/L7:BOTTOM=L7 |
| IOEXP_INT#_4 | OTHERS | BUS | 6 | 5 | 5 | 10 | 5 | 14 | 6 | 10 | 12 | 12 | 12 | 12 |  | 50 Ohms | TOP=L2:L3=L2/L4:L6=L5/L7:BOTTOM=L7 |
| IOEXP_INT#_4 | OTHERS | BUS | 7 | 5 | 5 | 10 | 5 | 14 | 6 | 10 | 12 | 12 | 12 | 12 |  | 50 Ohms | TOP=L2:L3=L2/L4:L6=L5/L7:BOTTOM=L7 |
| IOEXP_INT#_4 | OTHERS | BUS | 8 | 4.75 | 5 | 10 | 5 | 14 | 6 | 9.5 | 12 | 12 | 12 | 12 |  | 50 Ohms | TOP=L2:L3=L2/L4:L6=L5/L7:BOTTOM=L7 |
| IOEXP_PEWAKE# | OTHERS | BUS | 1 | 4.75 | 5 | 10 | 5 | 14 | 6 | 9.5 | 12 | 12 | 12 | 12 |  | 50 Ohms | TOP=L2:L3=L2/L4:L6=L5/L7:BOTTOM=L7 |
| IOEXP_PEWAKE# | OTHERS | BUS | 2 | 5 | 5 | 10 | 5 | 14 | 6 | 10 | 12 | 12 | 12 | 12 |  | 50 Ohms | TOP=L2:L3=L2/L4:L6=L5/L7:BOTTOM=L7 |
| IOEXP_PEWAKE# | OTHERS | BUS | 3 | 5 | 5 | 10 | 5 | 14 | 6 | 10 | 12 | 12 | 12 | 12 |  | 50 Ohms | TOP=L2:L3=L2/L4:L6=L5/L7:BOTTOM=L7 |
| IOEXP_PEWAKE# | OTHERS | BUS | 4 | 5 | 5 | 10 | 5 | 14 | 6 | 10 | 12 | 12 | 12 | 12 |  | 50 Ohms | TOP=L2:L3=L2/L4:L6=L5/L7:BOTTOM=L7 |
| IOEXP_PEWAKE# | OTHERS | BUS | 5 | 5 | 5 | 10 | 5 | 14 | 6 | 10 | 12 | 12 | 12 | 12 |  | 50 Ohms | TOP=L2:L3=L2/L4:L6=L5/L7:BOTTOM=L7 |
| IOEXP_PEWAKE# | OTHERS | BUS | 6 | 5 | 5 | 10 | 5 | 14 | 6 | 10 | 12 | 12 | 12 | 12 |  | 50 Ohms | TOP=L2:L3=L2/L4:L6=L5/L7:BOTTOM=L7 |
| IOEXP_PEWAKE# | OTHERS | BUS | 7 | 5 | 5 | 10 | 5 | 14 | 6 | 10 | 12 | 12 | 12 | 12 |  | 50 Ohms | TOP=L2:L3=L2/L4:L6=L5/L7:BOTTOM=L7 |
| IOEXP_PEWAKE# | OTHERS | BUS | 8 | 4.75 | 5 | 10 | 5 | 14 | 6 | 9.5 | 12 | 12 | 12 | 12 |  | 50 Ohms | TOP=L2:L3=L2/L4:L6=L5/L7:BOTTOM=L7 |
| IOEXP_PMC1_AD0 | OTHERS | BUS | 1 | 4.75 | 5 | 10 | 5 | 14 | 6 | 9.5 | 12 | 12 | 12 | 12 |  | 50 Ohms | TOP=L2:L3=L2/L4:L6=L5/L7:BOTTOM=L7 |
| IOEXP_PMC1_AD0 | OTHERS | BUS | 2 | 5 | 5 | 10 | 5 | 14 | 6 | 10 | 12 | 12 | 12 | 12 |  | 50 Ohms | TOP=L2:L3=L2/L4:L6=L5/L7:BOTTOM=L7 |
| IOEXP_PMC1_AD0 | OTHERS | BUS | 3 | 5 | 5 | 10 | 5 | 14 | 6 | 10 | 12 | 12 | 12 | 12 |  | 50 Ohms | TOP=L2:L3=L2/L4:L6=L5/L7:BOTTOM=L7 |
| IOEXP_PMC1_AD0 | OTHERS | BUS | 4 | 5 | 5 | 10 | 5 | 14 | 6 | 10 | 12 | 12 | 12 | 12 |  | 50 Ohms | TOP=L2:L3=L2/L4:L6=L5/L7:BOTTOM=L7 |
| IOEXP_PMC1_AD0 | OTHERS | BUS | 5 | 5 | 5 | 10 | 5 | 14 | 6 | 10 | 12 | 12 | 12 | 12 |  | 50 Ohms | TOP=L2:L3=L2/L4:L6=L5/L7:BOTTOM=L7 |
| IOEXP_PMC1_AD0 | OTHERS | BUS | 6 | 5 | 5 | 10 | 5 | 14 | 6 | 10 | 12 | 12 | 12 | 12 |  | 50 Ohms | TOP=L2:L3=L2/L4:L6=L5/L7:BOTTOM=L7 |
| IOEXP_PMC1_AD0 | OTHERS | BUS | 7 | 5 | 5 | 10 | 5 | 14 | 6 | 10 | 12 | 12 | 12 | 12 |  | 50 Ohms | TOP=L2:L3=L2/L4:L6=L5/L7:BOTTOM=L7 |
| IOEXP_PMC1_AD0 | OTHERS | BUS | 8 | 4.75 | 5 | 10 | 5 | 14 | 6 | 9.5 | 12 | 12 | 12 | 12 |  | 50 Ohms | TOP=L2:L3=L2/L4:L6=L5/L7:BOTTOM=L7 |
| IOEXP_PMC1_AD1 | OTHERS | BUS | 1 | 4.75 | 5 | 10 | 5 | 14 | 6 | 9.5 | 12 | 12 | 12 | 12 |  | 50 Ohms | TOP=L2:L3=L2/L4:L6=L5/L7:BOTTOM=L7 |
| IOEXP_PMC1_AD1 | OTHERS | BUS | 2 | 5 | 5 | 10 | 5 | 14 | 6 | 10 | 12 | 12 | 12 | 12 |  | 50 Ohms | TOP=L2:L3=L2/L4:L6=L5/L7:BOTTOM=L7 |
| IOEXP_PMC1_AD1 | OTHERS | BUS | 3 | 5 | 5 | 10 | 5 | 14 | 6 | 10 | 12 | 12 | 12 | 12 |  | 50 Ohms | TOP=L2:L3=L2/L4:L6=L5/L7:BOTTOM=L7 |
| IOEXP_PMC1_AD1 | OTHERS | BUS | 4 | 5 | 5 | 10 | 5 | 14 | 6 | 10 | 12 | 12 | 12 | 12 |  | 50 Ohms | TOP=L2:L3=L2/L4:L6=L5/L7:BOTTOM=L7 |
| IOEXP_PMC1_AD1 | OTHERS | BUS | 5 | 5 | 5 | 10 | 5 | 14 | 6 | 10 | 12 | 12 | 12 | 12 |  | 50 Ohms | TOP=L2:L3=L2/L4:L6=L5/L7:BOTTOM=L7 |
| IOEXP_PMC1_AD1 | OTHERS | BUS | 6 | 5 | 5 | 10 | 5 | 14 | 6 | 10 | 12 | 12 | 12 | 12 |  | 50 Ohms | TOP=L2:L3=L2/L4:L6=L5/L7:BOTTOM=L7 |
| IOEXP_PMC1_AD1 | OTHERS | BUS | 7 | 5 | 5 | 10 | 5 | 14 | 6 | 10 | 12 | 12 | 12 | 12 |  | 50 Ohms | TOP=L2:L3=L2/L4:L6=L5/L7:BOTTOM=L7 |
| IOEXP_PMC1_AD1 | OTHERS | BUS | 8 | 4.75 | 5 | 10 | 5 | 14 | 6 | 9.5 | 12 | 12 | 12 | 12 |  | 50 Ohms | TOP=L2:L3=L2/L4:L6=L5/L7:BOTTOM=L7 |
| IOEXP_PMC1_AD2 | OTHERS | BUS | 1 | 4.75 | 5 | 10 | 5 | 14 | 6 | 9.5 | 12 | 12 | 12 | 12 |  | 50 Ohms | TOP=L2:L3=L2/L4:L6=L5/L7:BOTTOM=L7 |
| IOEXP_PMC1_AD2 | OTHERS | BUS | 2 | 5 | 5 | 10 | 5 | 14 | 6 | 10 | 12 | 12 | 12 | 12 |  | 50 Ohms | TOP=L2:L3=L2/L4:L6=L5/L7:BOTTOM=L7 |
| IOEXP_PMC1_AD2 | OTHERS | BUS | 3 | 5 | 5 | 10 | 5 | 14 | 6 | 10 | 12 | 12 | 12 | 12 |  | 50 Ohms | TOP=L2:L3=L2/L4:L6=L5/L7:BOTTOM=L7 |
| IOEXP_PMC1_AD2 | OTHERS | BUS | 4 | 5 | 5 | 10 | 5 | 14 | 6 | 10 | 12 | 12 | 12 | 12 |  | 50 Ohms | TOP=L2:L3=L2/L4:L6=L5/L7:BOTTOM=L7 |
| IOEXP_PMC1_AD2 | OTHERS | BUS | 5 | 5 | 5 | 10 | 5 | 14 | 6 | 10 | 12 | 12 | 12 | 12 |  | 50 Ohms | TOP=L2:L3=L2/L4:L6=L5/L7:BOTTOM=L7 |
| IOEXP_PMC1_AD2 | OTHERS | BUS | 6 | 5 | 5 | 10 | 5 | 14 | 6 | 10 | 12 | 12 | 12 | 12 |  | 50 Ohms | TOP=L2:L3=L2/L4:L6=L5/L7:BOTTOM=L7 |
| IOEXP_PMC1_AD2 | OTHERS | BUS | 7 | 5 | 5 | 10 | 5 | 14 | 6 | 10 | 12 | 12 | 12 | 12 |  | 50 Ohms | TOP=L2:L3=L2/L4:L6=L5/L7:BOTTOM=L7 |
| IOEXP_PMC1_AD2 | OTHERS | BUS | 8 | 4.75 | 5 | 10 | 5 | 14 | 6 | 9.5 | 12 | 12 | 12 | 12 |  | 50 Ohms | TOP=L2:L3=L2/L4:L6=L5/L7:BOTTOM=L7 |
| IOEXP_PMC1_INT# | OTHERS | BUS | 1 | 4.75 | 5 | 10 | 5 | 14 | 6 | 9.5 | 12 | 12 | 12 | 12 |  | 50 Ohms | TOP=L2:L3=L2/L4:L6=L5/L7:BOTTOM=L7 |
| IOEXP_PMC1_INT# | OTHERS | BUS | 2 | 5 | 5 | 10 | 5 | 14 | 6 | 10 | 12 | 12 | 12 | 12 |  | 50 Ohms | TOP=L2:L3=L2/L4:L6=L5/L7:BOTTOM=L7 |
| IOEXP_PMC1_INT# | OTHERS | BUS | 3 | 5 | 5 | 10 | 5 | 14 | 6 | 10 | 12 | 12 | 12 | 12 |  | 50 Ohms | TOP=L2:L3=L2/L4:L6=L5/L7:BOTTOM=L7 |
| IOEXP_PMC1_INT# | OTHERS | BUS | 4 | 5 | 5 | 10 | 5 | 14 | 6 | 10 | 12 | 12 | 12 | 12 |  | 50 Ohms | TOP=L2:L3=L2/L4:L6=L5/L7:BOTTOM=L7 |
| IOEXP_PMC1_INT# | OTHERS | BUS | 5 | 5 | 5 | 10 | 5 | 14 | 6 | 10 | 12 | 12 | 12 | 12 |  | 50 Ohms | TOP=L2:L3=L2/L4:L6=L5/L7:BOTTOM=L7 |
| IOEXP_PMC1_INT# | OTHERS | BUS | 6 | 5 | 5 | 10 | 5 | 14 | 6 | 10 | 12 | 12 | 12 | 12 |  | 50 Ohms | TOP=L2:L3=L2/L4:L6=L5/L7:BOTTOM=L7 |
| IOEXP_PMC1_INT# | OTHERS | BUS | 7 | 5 | 5 | 10 | 5 | 14 | 6 | 10 | 12 | 12 | 12 | 12 |  | 50 Ohms | TOP=L2:L3=L2/L4:L6=L5/L7:BOTTOM=L7 |
| IOEXP_PMC1_INT# | OTHERS | BUS | 8 | 4.75 | 5 | 10 | 5 | 14 | 6 | 9.5 | 12 | 12 | 12 | 12 |  | 50 Ohms | TOP=L2:L3=L2/L4:L6=L5/L7:BOTTOM=L7 |
| IOEXP1_AD0 | OTHERS | BUS | 1 | 4.75 | 5 | 10 | 5 | 14 | 6 | 9.5 | 12 | 12 | 12 | 12 |  | 50 Ohms | TOP=L2:L3=L2/L4:L6=L5/L7:BOTTOM=L7 |
| IOEXP1_AD0 | OTHERS | BUS | 2 | 5 | 5 | 10 | 5 | 14 | 6 | 10 | 12 | 12 | 12 | 12 |  | 50 Ohms | TOP=L2:L3=L2/L4:L6=L5/L7:BOTTOM=L7 |
| IOEXP1_AD0 | OTHERS | BUS | 3 | 5 | 5 | 10 | 5 | 14 | 6 | 10 | 12 | 12 | 12 | 12 |  | 50 Ohms | TOP=L2:L3=L2/L4:L6=L5/L7:BOTTOM=L7 |
| IOEXP1_AD0 | OTHERS | BUS | 4 | 5 | 5 | 10 | 5 | 14 | 6 | 10 | 12 | 12 | 12 | 12 |  | 50 Ohms | TOP=L2:L3=L2/L4:L6=L5/L7:BOTTOM=L7 |
| IOEXP1_AD0 | OTHERS | BUS | 5 | 5 | 5 | 10 | 5 | 14 | 6 | 10 | 12 | 12 | 12 | 12 |  | 50 Ohms | TOP=L2:L3=L2/L4:L6=L5/L7:BOTTOM=L7 |
| IOEXP1_AD0 | OTHERS | BUS | 6 | 5 | 5 | 10 | 5 | 14 | 6 | 10 | 12 | 12 | 12 | 12 |  | 50 Ohms | TOP=L2:L3=L2/L4:L6=L5/L7:BOTTOM=L7 |
| IOEXP1_AD0 | OTHERS | BUS | 7 | 5 | 5 | 10 | 5 | 14 | 6 | 10 | 12 | 12 | 12 | 12 |  | 50 Ohms | TOP=L2:L3=L2/L4:L6=L5/L7:BOTTOM=L7 |
| IOEXP1_AD0 | OTHERS | BUS | 8 | 4.75 | 5 | 10 | 5 | 14 | 6 | 9.5 | 12 | 12 | 12 | 12 |  | 50 Ohms | TOP=L2:L3=L2/L4:L6=L5/L7:BOTTOM=L7 |
| IOEXP1_AD1 | OTHERS | BUS | 1 | 4.75 | 5 | 10 | 5 | 14 | 6 | 9.5 | 12 | 12 | 12 | 12 |  | 50 Ohms | TOP=L2:L3=L2/L4:L6=L5/L7:BOTTOM=L7 |
| IOEXP1_AD1 | OTHERS | BUS | 2 | 5 | 5 | 10 | 5 | 14 | 6 | 10 | 12 | 12 | 12 | 12 |  | 50 Ohms | TOP=L2:L3=L2/L4:L6=L5/L7:BOTTOM=L7 |
| IOEXP1_AD1 | OTHERS | BUS | 3 | 5 | 5 | 10 | 5 | 14 | 6 | 10 | 12 | 12 | 12 | 12 |  | 50 Ohms | TOP=L2:L3=L2/L4:L6=L5/L7:BOTTOM=L7 |
| IOEXP1_AD1 | OTHERS | BUS | 4 | 5 | 5 | 10 | 5 | 14 | 6 | 10 | 12 | 12 | 12 | 12 |  | 50 Ohms | TOP=L2:L3=L2/L4:L6=L5/L7:BOTTOM=L7 |
| IOEXP1_AD1 | OTHERS | BUS | 5 | 5 | 5 | 10 | 5 | 14 | 6 | 10 | 12 | 12 | 12 | 12 |  | 50 Ohms | TOP=L2:L3=L2/L4:L6=L5/L7:BOTTOM=L7 |
| IOEXP1_AD1 | OTHERS | BUS | 6 | 5 | 5 | 10 | 5 | 14 | 6 | 10 | 12 | 12 | 12 | 12 |  | 50 Ohms | TOP=L2:L3=L2/L4:L6=L5/L7:BOTTOM=L7 |
| IOEXP1_AD1 | OTHERS | BUS | 7 | 5 | 5 | 10 | 5 | 14 | 6 | 10 | 12 | 12 | 12 | 12 |  | 50 Ohms | TOP=L2:L3=L2/L4:L6=L5/L7:BOTTOM=L7 |
| IOEXP1_AD1 | OTHERS | BUS | 8 | 4.75 | 5 | 10 | 5 | 14 | 6 | 9.5 | 12 | 12 | 12 | 12 |  | 50 Ohms | TOP=L2:L3=L2/L4:L6=L5/L7:BOTTOM=L7 |
| IOEXP1_AD2 | OTHERS | BUS | 1 | 4.75 | 5 | 10 | 5 | 14 | 6 | 9.5 | 12 | 12 | 12 | 12 |  | 50 Ohms | TOP=L2:L3=L2/L4:L6=L5/L7:BOTTOM=L7 |
| IOEXP1_AD2 | OTHERS | BUS | 2 | 5 | 5 | 10 | 5 | 14 | 6 | 10 | 12 | 12 | 12 | 12 |  | 50 Ohms | TOP=L2:L3=L2/L4:L6=L5/L7:BOTTOM=L7 |
| IOEXP1_AD2 | OTHERS | BUS | 3 | 5 | 5 | 10 | 5 | 14 | 6 | 10 | 12 | 12 | 12 | 12 |  | 50 Ohms | TOP=L2:L3=L2/L4:L6=L5/L7:BOTTOM=L7 |
| IOEXP1_AD2 | OTHERS | BUS | 4 | 5 | 5 | 10 | 5 | 14 | 6 | 10 | 12 | 12 | 12 | 12 |  | 50 Ohms | TOP=L2:L3=L2/L4:L6=L5/L7:BOTTOM=L7 |
| IOEXP1_AD2 | OTHERS | BUS | 5 | 5 | 5 | 10 | 5 | 14 | 6 | 10 | 12 | 12 | 12 | 12 |  | 50 Ohms | TOP=L2:L3=L2/L4:L6=L5/L7:BOTTOM=L7 |
| IOEXP1_AD2 | OTHERS | BUS | 6 | 5 | 5 | 10 | 5 | 14 | 6 | 10 | 12 | 12 | 12 | 12 |  | 50 Ohms | TOP=L2:L3=L2/L4:L6=L5/L7:BOTTOM=L7 |
| IOEXP1_AD2 | OTHERS | BUS | 7 | 5 | 5 | 10 | 5 | 14 | 6 | 10 | 12 | 12 | 12 | 12 |  | 50 Ohms | TOP=L2:L3=L2/L4:L6=L5/L7:BOTTOM=L7 |
| IOEXP1_AD2 | OTHERS | BUS | 8 | 4.75 | 5 | 10 | 5 | 14 | 6 | 9.5 | 12 | 12 | 12 | 12 |  | 50 Ohms | TOP=L2:L3=L2/L4:L6=L5/L7:BOTTOM=L7 |
| IOEXP2_AD0 | OTHERS | BUS | 1 | 4.75 | 5 | 10 | 5 | 14 | 6 | 9.5 | 12 | 12 | 12 | 12 |  | 50 Ohms | TOP=L2:L3=L2/L4:L6=L5/L7:BOTTOM=L7 |
| IOEXP2_AD0 | OTHERS | BUS | 2 | 5 | 5 | 10 | 5 | 14 | 6 | 10 | 12 | 12 | 12 | 12 |  | 50 Ohms | TOP=L2:L3=L2/L4:L6=L5/L7:BOTTOM=L7 |
| IOEXP2_AD0 | OTHERS | BUS | 3 | 5 | 5 | 10 | 5 | 14 | 6 | 10 | 12 | 12 | 12 | 12 |  | 50 Ohms | TOP=L2:L3=L2/L4:L6=L5/L7:BOTTOM=L7 |
| IOEXP2_AD0 | OTHERS | BUS | 4 | 5 | 5 | 10 | 5 | 14 | 6 | 10 | 12 | 12 | 12 | 12 |  | 50 Ohms | TOP=L2:L3=L2/L4:L6=L5/L7:BOTTOM=L7 |
| IOEXP2_AD0 | OTHERS | BUS | 5 | 5 | 5 | 10 | 5 | 14 | 6 | 10 | 12 | 12 | 12 | 12 |  | 50 Ohms | TOP=L2:L3=L2/L4:L6=L5/L7:BOTTOM=L7 |
| IOEXP2_AD0 | OTHERS | BUS | 6 | 5 | 5 | 10 | 5 | 14 | 6 | 10 | 12 | 12 | 12 | 12 |  | 50 Ohms | TOP=L2:L3=L2/L4:L6=L5/L7:BOTTOM=L7 |
| IOEXP2_AD0 | OTHERS | BUS | 7 | 5 | 5 | 10 | 5 | 14 | 6 | 10 | 12 | 12 | 12 | 12 |  | 50 Ohms | TOP=L2:L3=L2/L4:L6=L5/L7:BOTTOM=L7 |
| IOEXP2_AD0 | OTHERS | BUS | 8 | 4.75 | 5 | 10 | 5 | 14 | 6 | 9.5 | 12 | 12 | 12 | 12 |  | 50 Ohms | TOP=L2:L3=L2/L4:L6=L5/L7:BOTTOM=L7 |
| IOEXP2_AD1 | OTHERS | BUS | 1 | 4.75 | 5 | 10 | 5 | 14 | 6 | 9.5 | 12 | 12 | 12 | 12 |  | 50 Ohms | TOP=L2:L3=L2/L4:L6=L5/L7:BOTTOM=L7 |
| IOEXP2_AD1 | OTHERS | BUS | 2 | 5 | 5 | 10 | 5 | 14 | 6 | 10 | 12 | 12 | 12 | 12 |  | 50 Ohms | TOP=L2:L3=L2/L4:L6=L5/L7:BOTTOM=L7 |
| IOEXP2_AD1 | OTHERS | BUS | 3 | 5 | 5 | 10 | 5 | 14 | 6 | 10 | 12 | 12 | 12 | 12 |  | 50 Ohms | TOP=L2:L3=L2/L4:L6=L5/L7:BOTTOM=L7 |
| IOEXP2_AD1 | OTHERS | BUS | 4 | 5 | 5 | 10 | 5 | 14 | 6 | 10 | 12 | 12 | 12 | 12 |  | 50 Ohms | TOP=L2:L3=L2/L4:L6=L5/L7:BOTTOM=L7 |
| IOEXP2_AD1 | OTHERS | BUS | 5 | 5 | 5 | 10 | 5 | 14 | 6 | 10 | 12 | 12 | 12 | 12 |  | 50 Ohms | TOP=L2:L3=L2/L4:L6=L5/L7:BOTTOM=L7 |
| IOEXP2_AD1 | OTHERS | BUS | 6 | 5 | 5 | 10 | 5 | 14 | 6 | 10 | 12 | 12 | 12 | 12 |  | 50 Ohms | TOP=L2:L3=L2/L4:L6=L5/L7:BOTTOM=L7 |
| IOEXP2_AD1 | OTHERS | BUS | 7 | 5 | 5 | 10 | 5 | 14 | 6 | 10 | 12 | 12 | 12 | 12 |  | 50 Ohms | TOP=L2:L3=L2/L4:L6=L5/L7:BOTTOM=L7 |
| IOEXP2_AD1 | OTHERS | BUS | 8 | 4.75 | 5 | 10 | 5 | 14 | 6 | 9.5 | 12 | 12 | 12 | 12 |  | 50 Ohms | TOP=L2:L3=L2/L4:L6=L5/L7:BOTTOM=L7 |
| IOEXP2_AD2 | OTHERS | BUS | 1 | 4.75 | 5 | 10 | 5 | 14 | 6 | 9.5 | 12 | 12 | 12 | 12 |  | 50 Ohms | TOP=L2:L3=L2/L4:L6=L5/L7:BOTTOM=L7 |
| IOEXP2_AD2 | OTHERS | BUS | 2 | 5 | 5 | 10 | 5 | 14 | 6 | 10 | 12 | 12 | 12 | 12 |  | 50 Ohms | TOP=L2:L3=L2/L4:L6=L5/L7:BOTTOM=L7 |
| IOEXP2_AD2 | OTHERS | BUS | 3 | 5 | 5 | 10 | 5 | 14 | 6 | 10 | 12 | 12 | 12 | 12 |  | 50 Ohms | TOP=L2:L3=L2/L4:L6=L5/L7:BOTTOM=L7 |
| IOEXP2_AD2 | OTHERS | BUS | 4 | 5 | 5 | 10 | 5 | 14 | 6 | 10 | 12 | 12 | 12 | 12 |  | 50 Ohms | TOP=L2:L3=L2/L4:L6=L5/L7:BOTTOM=L7 |
| IOEXP2_AD2 | OTHERS | BUS | 5 | 5 | 5 | 10 | 5 | 14 | 6 | 10 | 12 | 12 | 12 | 12 |  | 50 Ohms | TOP=L2:L3=L2/L4:L6=L5/L7:BOTTOM=L7 |
| IOEXP2_AD2 | OTHERS | BUS | 6 | 5 | 5 | 10 | 5 | 14 | 6 | 10 | 12 | 12 | 12 | 12 |  | 50 Ohms | TOP=L2:L3=L2/L4:L6=L5/L7:BOTTOM=L7 |
| IOEXP2_AD2 | OTHERS | BUS | 7 | 5 | 5 | 10 | 5 | 14 | 6 | 10 | 12 | 12 | 12 | 12 |  | 50 Ohms | TOP=L2:L3=L2/L4:L6=L5/L7:BOTTOM=L7 |
| IOEXP2_AD2 | OTHERS | BUS | 8 | 4.75 | 5 | 10 | 5 | 14 | 6 | 9.5 | 12 | 12 | 12 | 12 |  | 50 Ohms | TOP=L2:L3=L2/L4:L6=L5/L7:BOTTOM=L7 |
| IOEXP3_AD0 | OTHERS | BUS | 1 | 4.75 | 5 | 10 | 5 | 14 | 6 | 9.5 | 12 | 12 | 12 | 12 |  | 50 Ohms | TOP=L2:L3=L2/L4:L6=L5/L7:BOTTOM=L7 |
| IOEXP3_AD0 | OTHERS | BUS | 2 | 5 | 5 | 10 | 5 | 14 | 6 | 10 | 12 | 12 | 12 | 12 |  | 50 Ohms | TOP=L2:L3=L2/L4:L6=L5/L7:BOTTOM=L7 |
| IOEXP3_AD0 | OTHERS | BUS | 3 | 5 | 5 | 10 | 5 | 14 | 6 | 10 | 12 | 12 | 12 | 12 |  | 50 Ohms | TOP=L2:L3=L2/L4:L6=L5/L7:BOTTOM=L7 |
| IOEXP3_AD0 | OTHERS | BUS | 4 | 5 | 5 | 10 | 5 | 14 | 6 | 10 | 12 | 12 | 12 | 12 |  | 50 Ohms | TOP=L2:L3=L2/L4:L6=L5/L7:BOTTOM=L7 |
| IOEXP3_AD0 | OTHERS | BUS | 5 | 5 | 5 | 10 | 5 | 14 | 6 | 10 | 12 | 12 | 12 | 12 |  | 50 Ohms | TOP=L2:L3=L2/L4:L6=L5/L7:BOTTOM=L7 |
| IOEXP3_AD0 | OTHERS | BUS | 6 | 5 | 5 | 10 | 5 | 14 | 6 | 10 | 12 | 12 | 12 | 12 |  | 50 Ohms | TOP=L2:L3=L2/L4:L6=L5/L7:BOTTOM=L7 |
| IOEXP3_AD0 | OTHERS | BUS | 7 | 5 | 5 | 10 | 5 | 14 | 6 | 10 | 12 | 12 | 12 | 12 |  | 50 Ohms | TOP=L2:L3=L2/L4:L6=L5/L7:BOTTOM=L7 |
| IOEXP3_AD0 | OTHERS | BUS | 8 | 4.75 | 5 | 10 | 5 | 14 | 6 | 9.5 | 12 | 12 | 12 | 12 |  | 50 Ohms | TOP=L2:L3=L2/L4:L6=L5/L7:BOTTOM=L7 |
| IOEXP3_AD1 | OTHERS | BUS | 1 | 4.75 | 5 | 10 | 5 | 14 | 6 | 9.5 | 12 | 12 | 12 | 12 |  | 50 Ohms | TOP=L2:L3=L2/L4:L6=L5/L7:BOTTOM=L7 |
| IOEXP3_AD1 | OTHERS | BUS | 2 | 5 | 5 | 10 | 5 | 14 | 6 | 10 | 12 | 12 | 12 | 12 |  | 50 Ohms | TOP=L2:L3=L2/L4:L6=L5/L7:BOTTOM=L7 |
| IOEXP3_AD1 | OTHERS | BUS | 3 | 5 | 5 | 10 | 5 | 14 | 6 | 10 | 12 | 12 | 12 | 12 |  | 50 Ohms | TOP=L2:L3=L2/L4:L6=L5/L7:BOTTOM=L7 |
| IOEXP3_AD1 | OTHERS | BUS | 4 | 5 | 5 | 10 | 5 | 14 | 6 | 10 | 12 | 12 | 12 | 12 |  | 50 Ohms | TOP=L2:L3=L2/L4:L6=L5/L7:BOTTOM=L7 |
| IOEXP3_AD1 | OTHERS | BUS | 5 | 5 | 5 | 10 | 5 | 14 | 6 | 10 | 12 | 12 | 12 | 12 |  | 50 Ohms | TOP=L2:L3=L2/L4:L6=L5/L7:BOTTOM=L7 |
| IOEXP3_AD1 | OTHERS | BUS | 6 | 5 | 5 | 10 | 5 | 14 | 6 | 10 | 12 | 12 | 12 | 12 |  | 50 Ohms | TOP=L2:L3=L2/L4:L6=L5/L7:BOTTOM=L7 |
| IOEXP3_AD1 | OTHERS | BUS | 7 | 5 | 5 | 10 | 5 | 14 | 6 | 10 | 12 | 12 | 12 | 12 |  | 50 Ohms | TOP=L2:L3=L2/L4:L6=L5/L7:BOTTOM=L7 |
| IOEXP3_AD1 | OTHERS | BUS | 8 | 4.75 | 5 | 10 | 5 | 14 | 6 | 9.5 | 12 | 12 | 12 | 12 |  | 50 Ohms | TOP=L2:L3=L2/L4:L6=L5/L7:BOTTOM=L7 |
| IOEXP3_AD2 | OTHERS | BUS | 1 | 4.75 | 5 | 10 | 5 | 14 | 6 | 9.5 | 12 | 12 | 12 | 12 |  | 50 Ohms | TOP=L2:L3=L2/L4:L6=L5/L7:BOTTOM=L7 |
| IOEXP3_AD2 | OTHERS | BUS | 2 | 5 | 5 | 10 | 5 | 14 | 6 | 10 | 12 | 12 | 12 | 12 |  | 50 Ohms | TOP=L2:L3=L2/L4:L6=L5/L7:BOTTOM=L7 |
| IOEXP3_AD2 | OTHERS | BUS | 3 | 5 | 5 | 10 | 5 | 14 | 6 | 10 | 12 | 12 | 12 | 12 |  | 50 Ohms | TOP=L2:L3=L2/L4:L6=L5/L7:BOTTOM=L7 |
| IOEXP3_AD2 | OTHERS | BUS | 4 | 5 | 5 | 10 | 5 | 14 | 6 | 10 | 12 | 12 | 12 | 12 |  | 50 Ohms | TOP=L2:L3=L2/L4:L6=L5/L7:BOTTOM=L7 |
| IOEXP3_AD2 | OTHERS | BUS | 5 | 5 | 5 | 10 | 5 | 14 | 6 | 10 | 12 | 12 | 12 | 12 |  | 50 Ohms | TOP=L2:L3=L2/L4:L6=L5/L7:BOTTOM=L7 |
| IOEXP3_AD2 | OTHERS | BUS | 6 | 5 | 5 | 10 | 5 | 14 | 6 | 10 | 12 | 12 | 12 | 12 |  | 50 Ohms | TOP=L2:L3=L2/L4:L6=L5/L7:BOTTOM=L7 |
| IOEXP3_AD2 | OTHERS | BUS | 7 | 5 | 5 | 10 | 5 | 14 | 6 | 10 | 12 | 12 | 12 | 12 |  | 50 Ohms | TOP=L2:L3=L2/L4:L6=L5/L7:BOTTOM=L7 |
| IOEXP3_AD2 | OTHERS | BUS | 8 | 4.75 | 5 | 10 | 5 | 14 | 6 | 9.5 | 12 | 12 | 12 | 12 |  | 50 Ohms | TOP=L2:L3=L2/L4:L6=L5/L7:BOTTOM=L7 |
| IOEXP4_AD0 | OTHERS | BUS | 1 | 4.75 | 5 | 10 | 5 | 14 | 6 | 9.5 | 12 | 12 | 12 | 12 |  | 50 Ohms | TOP=L2:L3=L2/L4:L6=L5/L7:BOTTOM=L7 |
| IOEXP4_AD0 | OTHERS | BUS | 2 | 5 | 5 | 10 | 5 | 14 | 6 | 10 | 12 | 12 | 12 | 12 |  | 50 Ohms | TOP=L2:L3=L2/L4:L6=L5/L7:BOTTOM=L7 |
| IOEXP4_AD0 | OTHERS | BUS | 3 | 5 | 5 | 10 | 5 | 14 | 6 | 10 | 12 | 12 | 12 | 12 |  | 50 Ohms | TOP=L2:L3=L2/L4:L6=L5/L7:BOTTOM=L7 |
| IOEXP4_AD0 | OTHERS | BUS | 4 | 5 | 5 | 10 | 5 | 14 | 6 | 10 | 12 | 12 | 12 | 12 |  | 50 Ohms | TOP=L2:L3=L2/L4:L6=L5/L7:BOTTOM=L7 |
| IOEXP4_AD0 | OTHERS | BUS | 5 | 5 | 5 | 10 | 5 | 14 | 6 | 10 | 12 | 12 | 12 | 12 |  | 50 Ohms | TOP=L2:L3=L2/L4:L6=L5/L7:BOTTOM=L7 |
| IOEXP4_AD0 | OTHERS | BUS | 6 | 5 | 5 | 10 | 5 | 14 | 6 | 10 | 12 | 12 | 12 | 12 |  | 50 Ohms | TOP=L2:L3=L2/L4:L6=L5/L7:BOTTOM=L7 |
| IOEXP4_AD0 | OTHERS | BUS | 7 | 5 | 5 | 10 | 5 | 14 | 6 | 10 | 12 | 12 | 12 | 12 |  | 50 Ohms | TOP=L2:L3=L2/L4:L6=L5/L7:BOTTOM=L7 |
| IOEXP4_AD0 | OTHERS | BUS | 8 | 4.75 | 5 | 10 | 5 | 14 | 6 | 9.5 | 12 | 12 | 12 | 12 |  | 50 Ohms | TOP=L2:L3=L2/L4:L6=L5/L7:BOTTOM=L7 |
| IOEXP4_AD1 | OTHERS | BUS | 1 | 4.75 | 5 | 10 | 5 | 14 | 6 | 9.5 | 12 | 12 | 12 | 12 |  | 50 Ohms | TOP=L2:L3=L2/L4:L6=L5/L7:BOTTOM=L7 |
| IOEXP4_AD1 | OTHERS | BUS | 2 | 5 | 5 | 10 | 5 | 14 | 6 | 10 | 12 | 12 | 12 | 12 |  | 50 Ohms | TOP=L2:L3=L2/L4:L6=L5/L7:BOTTOM=L7 |
| IOEXP4_AD1 | OTHERS | BUS | 3 | 5 | 5 | 10 | 5 | 14 | 6 | 10 | 12 | 12 | 12 | 12 |  | 50 Ohms | TOP=L2:L3=L2/L4:L6=L5/L7:BOTTOM=L7 |
| IOEXP4_AD1 | OTHERS | BUS | 4 | 5 | 5 | 10 | 5 | 14 | 6 | 10 | 12 | 12 | 12 | 12 |  | 50 Ohms | TOP=L2:L3=L2/L4:L6=L5/L7:BOTTOM=L7 |
| IOEXP4_AD1 | OTHERS | BUS | 5 | 5 | 5 | 10 | 5 | 14 | 6 | 10 | 12 | 12 | 12 | 12 |  | 50 Ohms | TOP=L2:L3=L2/L4:L6=L5/L7:BOTTOM=L7 |
| IOEXP4_AD1 | OTHERS | BUS | 6 | 5 | 5 | 10 | 5 | 14 | 6 | 10 | 12 | 12 | 12 | 12 |  | 50 Ohms | TOP=L2:L3=L2/L4:L6=L5/L7:BOTTOM=L7 |
| IOEXP4_AD1 | OTHERS | BUS | 7 | 5 | 5 | 10 | 5 | 14 | 6 | 10 | 12 | 12 | 12 | 12 |  | 50 Ohms | TOP=L2:L3=L2/L4:L6=L5/L7:BOTTOM=L7 |
| IOEXP4_AD1 | OTHERS | BUS | 8 | 4.75 | 5 | 10 | 5 | 14 | 6 | 9.5 | 12 | 12 | 12 | 12 |  | 50 Ohms | TOP=L2:L3=L2/L4:L6=L5/L7:BOTTOM=L7 |
| IOEXP4_AD2 | OTHERS | BUS | 1 | 4.75 | 5 | 10 | 5 | 14 | 6 | 9.5 | 12 | 12 | 12 | 12 |  | 50 Ohms | TOP=L2:L3=L2/L4:L6=L5/L7:BOTTOM=L7 |
| IOEXP4_AD2 | OTHERS | BUS | 2 | 5 | 5 | 10 | 5 | 14 | 6 | 10 | 12 | 12 | 12 | 12 |  | 50 Ohms | TOP=L2:L3=L2/L4:L6=L5/L7:BOTTOM=L7 |
| IOEXP4_AD2 | OTHERS | BUS | 3 | 5 | 5 | 10 | 5 | 14 | 6 | 10 | 12 | 12 | 12 | 12 |  | 50 Ohms | TOP=L2:L3=L2/L4:L6=L5/L7:BOTTOM=L7 |
| IOEXP4_AD2 | OTHERS | BUS | 4 | 5 | 5 | 10 | 5 | 14 | 6 | 10 | 12 | 12 | 12 | 12 |  | 50 Ohms | TOP=L2:L3=L2/L4:L6=L5/L7:BOTTOM=L7 |
| IOEXP4_AD2 | OTHERS | BUS | 5 | 5 | 5 | 10 | 5 | 14 | 6 | 10 | 12 | 12 | 12 | 12 |  | 50 Ohms | TOP=L2:L3=L2/L4:L6=L5/L7:BOTTOM=L7 |
| IOEXP4_AD2 | OTHERS | BUS | 6 | 5 | 5 | 10 | 5 | 14 | 6 | 10 | 12 | 12 | 12 | 12 |  | 50 Ohms | TOP=L2:L3=L2/L4:L6=L5/L7:BOTTOM=L7 |
| IOEXP4_AD2 | OTHERS | BUS | 7 | 5 | 5 | 10 | 5 | 14 | 6 | 10 | 12 | 12 | 12 | 12 |  | 50 Ohms | TOP=L2:L3=L2/L4:L6=L5/L7:BOTTOM=L7 |
| IOEXP4_AD2 | OTHERS | BUS | 8 | 4.75 | 5 | 10 | 5 | 14 | 6 | 9.5 | 12 | 12 | 12 | 12 |  | 50 Ohms | TOP=L2:L3=L2/L4:L6=L5/L7:BOTTOM=L7 |
| IOEXP4_GPIO12 | OTHERS | BUS | 1 | 4.75 | 5 | 10 | 5 | 14 | 6 | 9.5 | 12 | 12 | 12 | 12 |  | 50 Ohms | TOP=L2:L3=L2/L4:L6=L5/L7:BOTTOM=L7 |
| IOEXP4_GPIO12 | OTHERS | BUS | 2 | 5 | 5 | 10 | 5 | 14 | 6 | 10 | 12 | 12 | 12 | 12 |  | 50 Ohms | TOP=L2:L3=L2/L4:L6=L5/L7:BOTTOM=L7 |
| IOEXP4_GPIO12 | OTHERS | BUS | 3 | 5 | 5 | 10 | 5 | 14 | 6 | 10 | 12 | 12 | 12 | 12 |  | 50 Ohms | TOP=L2:L3=L2/L4:L6=L5/L7:BOTTOM=L7 |
| IOEXP4_GPIO12 | OTHERS | BUS | 4 | 5 | 5 | 10 | 5 | 14 | 6 | 10 | 12 | 12 | 12 | 12 |  | 50 Ohms | TOP=L2:L3=L2/L4:L6=L5/L7:BOTTOM=L7 |
| IOEXP4_GPIO12 | OTHERS | BUS | 5 | 5 | 5 | 10 | 5 | 14 | 6 | 10 | 12 | 12 | 12 | 12 |  | 50 Ohms | TOP=L2:L3=L2/L4:L6=L5/L7:BOTTOM=L7 |
| IOEXP4_GPIO12 | OTHERS | BUS | 6 | 5 | 5 | 10 | 5 | 14 | 6 | 10 | 12 | 12 | 12 | 12 |  | 50 Ohms | TOP=L2:L3=L2/L4:L6=L5/L7:BOTTOM=L7 |
| IOEXP4_GPIO12 | OTHERS | BUS | 7 | 5 | 5 | 10 | 5 | 14 | 6 | 10 | 12 | 12 | 12 | 12 |  | 50 Ohms | TOP=L2:L3=L2/L4:L6=L5/L7:BOTTOM=L7 |
| IOEXP4_GPIO12 | OTHERS | BUS | 8 | 4.75 | 5 | 10 | 5 | 14 | 6 | 9.5 | 12 | 12 | 12 | 12 |  | 50 Ohms | TOP=L2:L3=L2/L4:L6=L5/L7:BOTTOM=L7 |
| IOEXP4_GPIO13 | OTHERS | BUS | 1 | 4.75 | 5 | 10 | 5 | 14 | 6 | 9.5 | 12 | 12 | 12 | 12 |  | 50 Ohms | TOP=L2:L3=L2/L4:L6=L5/L7:BOTTOM=L7 |
| IOEXP4_GPIO13 | OTHERS | BUS | 2 | 5 | 5 | 10 | 5 | 14 | 6 | 10 | 12 | 12 | 12 | 12 |  | 50 Ohms | TOP=L2:L3=L2/L4:L6=L5/L7:BOTTOM=L7 |
| IOEXP4_GPIO13 | OTHERS | BUS | 3 | 5 | 5 | 10 | 5 | 14 | 6 | 10 | 12 | 12 | 12 | 12 |  | 50 Ohms | TOP=L2:L3=L2/L4:L6=L5/L7:BOTTOM=L7 |
| IOEXP4_GPIO13 | OTHERS | BUS | 4 | 5 | 5 | 10 | 5 | 14 | 6 | 10 | 12 | 12 | 12 | 12 |  | 50 Ohms | TOP=L2:L3=L2/L4:L6=L5/L7:BOTTOM=L7 |
| IOEXP4_GPIO13 | OTHERS | BUS | 5 | 5 | 5 | 10 | 5 | 14 | 6 | 10 | 12 | 12 | 12 | 12 |  | 50 Ohms | TOP=L2:L3=L2/L4:L6=L5/L7:BOTTOM=L7 |
| IOEXP4_GPIO13 | OTHERS | BUS | 6 | 5 | 5 | 10 | 5 | 14 | 6 | 10 | 12 | 12 | 12 | 12 |  | 50 Ohms | TOP=L2:L3=L2/L4:L6=L5/L7:BOTTOM=L7 |
| IOEXP4_GPIO13 | OTHERS | BUS | 7 | 5 | 5 | 10 | 5 | 14 | 6 | 10 | 12 | 12 | 12 | 12 |  | 50 Ohms | TOP=L2:L3=L2/L4:L6=L5/L7:BOTTOM=L7 |
| IOEXP4_GPIO13 | OTHERS | BUS | 8 | 4.75 | 5 | 10 | 5 | 14 | 6 | 9.5 | 12 | 12 | 12 | 12 |  | 50 Ohms | TOP=L2:L3=L2/L4:L6=L5/L7:BOTTOM=L7 |
| IOEXP4_GPIO14 | OTHERS | BUS | 1 | 4.75 | 5 | 10 | 5 | 14 | 6 | 9.5 | 12 | 12 | 12 | 12 |  | 50 Ohms | TOP=L2:L3=L2/L4:L6=L5/L7:BOTTOM=L7 |
| IOEXP4_GPIO14 | OTHERS | BUS | 2 | 5 | 5 | 10 | 5 | 14 | 6 | 10 | 12 | 12 | 12 | 12 |  | 50 Ohms | TOP=L2:L3=L2/L4:L6=L5/L7:BOTTOM=L7 |
| IOEXP4_GPIO14 | OTHERS | BUS | 3 | 5 | 5 | 10 | 5 | 14 | 6 | 10 | 12 | 12 | 12 | 12 |  | 50 Ohms | TOP=L2:L3=L2/L4:L6=L5/L7:BOTTOM=L7 |
| IOEXP4_GPIO14 | OTHERS | BUS | 4 | 5 | 5 | 10 | 5 | 14 | 6 | 10 | 12 | 12 | 12 | 12 |  | 50 Ohms | TOP=L2:L3=L2/L4:L6=L5/L7:BOTTOM=L7 |
| IOEXP4_GPIO14 | OTHERS | BUS | 5 | 5 | 5 | 10 | 5 | 14 | 6 | 10 | 12 | 12 | 12 | 12 |  | 50 Ohms | TOP=L2:L3=L2/L4:L6=L5/L7:BOTTOM=L7 |
| IOEXP4_GPIO14 | OTHERS | BUS | 6 | 5 | 5 | 10 | 5 | 14 | 6 | 10 | 12 | 12 | 12 | 12 |  | 50 Ohms | TOP=L2:L3=L2/L4:L6=L5/L7:BOTTOM=L7 |
| IOEXP4_GPIO14 | OTHERS | BUS | 7 | 5 | 5 | 10 | 5 | 14 | 6 | 10 | 12 | 12 | 12 | 12 |  | 50 Ohms | TOP=L2:L3=L2/L4:L6=L5/L7:BOTTOM=L7 |
| IOEXP4_GPIO14 | OTHERS | BUS | 8 | 4.75 | 5 | 10 | 5 | 14 | 6 | 9.5 | 12 | 12 | 12 | 12 |  | 50 Ohms | TOP=L2:L3=L2/L4:L6=L5/L7:BOTTOM=L7 |
| JTAG_BMC_TCK | OTHERS | BUS | 1 | 4.75 | 5 | 10 | 5 | 14 | 6 | 9.5 | 12 | 12 | 12 | 12 |  | 50 Ohms | TOP=L2:L3=L2/L4:L6=L5/L7:BOTTOM=L7 |
| JTAG_BMC_TCK | OTHERS | BUS | 2 | 5 | 5 | 10 | 5 | 14 | 6 | 10 | 12 | 12 | 12 | 12 |  | 50 Ohms | TOP=L2:L3=L2/L4:L6=L5/L7:BOTTOM=L7 |
| JTAG_BMC_TCK | OTHERS | BUS | 3 | 5 | 5 | 10 | 5 | 14 | 6 | 10 | 12 | 12 | 12 | 12 |  | 50 Ohms | TOP=L2:L3=L2/L4:L6=L5/L7:BOTTOM=L7 |
| JTAG_BMC_TCK | OTHERS | BUS | 4 | 5 | 5 | 10 | 5 | 14 | 6 | 10 | 12 | 12 | 12 | 12 |  | 50 Ohms | TOP=L2:L3=L2/L4:L6=L5/L7:BOTTOM=L7 |
| JTAG_BMC_TCK | OTHERS | BUS | 5 | 5 | 5 | 10 | 5 | 14 | 6 | 10 | 12 | 12 | 12 | 12 |  | 50 Ohms | TOP=L2:L3=L2/L4:L6=L5/L7:BOTTOM=L7 |
| JTAG_BMC_TCK | OTHERS | BUS | 6 | 5 | 5 | 10 | 5 | 14 | 6 | 10 | 12 | 12 | 12 | 12 |  | 50 Ohms | TOP=L2:L3=L2/L4:L6=L5/L7:BOTTOM=L7 |
| JTAG_BMC_TCK | OTHERS | BUS | 7 | 5 | 5 | 10 | 5 | 14 | 6 | 10 | 12 | 12 | 12 | 12 |  | 50 Ohms | TOP=L2:L3=L2/L4:L6=L5/L7:BOTTOM=L7 |
| JTAG_BMC_TCK | OTHERS | BUS | 8 | 4.75 | 5 | 10 | 5 | 14 | 6 | 9.5 | 12 | 12 | 12 | 12 |  | 50 Ohms | TOP=L2:L3=L2/L4:L6=L5/L7:BOTTOM=L7 |
| JTAG_BMC_TDI | OTHERS | BUS | 1 | 4.75 | 5 | 10 | 5 | 14 | 6 | 9.5 | 12 | 12 | 12 | 12 |  | 50 Ohms | TOP=L2:L3=L2/L4:L6=L5/L7:BOTTOM=L7 |
| JTAG_BMC_TDI | OTHERS | BUS | 2 | 5 | 5 | 10 | 5 | 14 | 6 | 10 | 12 | 12 | 12 | 12 |  | 50 Ohms | TOP=L2:L3=L2/L4:L6=L5/L7:BOTTOM=L7 |
| JTAG_BMC_TDI | OTHERS | BUS | 3 | 5 | 5 | 10 | 5 | 14 | 6 | 10 | 12 | 12 | 12 | 12 |  | 50 Ohms | TOP=L2:L3=L2/L4:L6=L5/L7:BOTTOM=L7 |
| JTAG_BMC_TDI | OTHERS | BUS | 4 | 5 | 5 | 10 | 5 | 14 | 6 | 10 | 12 | 12 | 12 | 12 |  | 50 Ohms | TOP=L2:L3=L2/L4:L6=L5/L7:BOTTOM=L7 |
| JTAG_BMC_TDI | OTHERS | BUS | 5 | 5 | 5 | 10 | 5 | 14 | 6 | 10 | 12 | 12 | 12 | 12 |  | 50 Ohms | TOP=L2:L3=L2/L4:L6=L5/L7:BOTTOM=L7 |
| JTAG_BMC_TDI | OTHERS | BUS | 6 | 5 | 5 | 10 | 5 | 14 | 6 | 10 | 12 | 12 | 12 | 12 |  | 50 Ohms | TOP=L2:L3=L2/L4:L6=L5/L7:BOTTOM=L7 |
| JTAG_BMC_TDI | OTHERS | BUS | 7 | 5 | 5 | 10 | 5 | 14 | 6 | 10 | 12 | 12 | 12 | 12 |  | 50 Ohms | TOP=L2:L3=L2/L4:L6=L5/L7:BOTTOM=L7 |
| JTAG_BMC_TDI | OTHERS | BUS | 8 | 4.75 | 5 | 10 | 5 | 14 | 6 | 9.5 | 12 | 12 | 12 | 12 |  | 50 Ohms | TOP=L2:L3=L2/L4:L6=L5/L7:BOTTOM=L7 |
| JTAG_BMC_TDO | OTHERS | BUS | 1 | 4.75 | 5 | 10 | 5 | 14 | 6 | 9.5 | 12 | 12 | 12 | 12 |  | 50 Ohms | TOP=L2:L3=L2/L4:L6=L5/L7:BOTTOM=L7 |
| JTAG_BMC_TDO | OTHERS | BUS | 2 | 5 | 5 | 10 | 5 | 14 | 6 | 10 | 12 | 12 | 12 | 12 |  | 50 Ohms | TOP=L2:L3=L2/L4:L6=L5/L7:BOTTOM=L7 |
| JTAG_BMC_TDO | OTHERS | BUS | 3 | 5 | 5 | 10 | 5 | 14 | 6 | 10 | 12 | 12 | 12 | 12 |  | 50 Ohms | TOP=L2:L3=L2/L4:L6=L5/L7:BOTTOM=L7 |
| JTAG_BMC_TDO | OTHERS | BUS | 4 | 5 | 5 | 10 | 5 | 14 | 6 | 10 | 12 | 12 | 12 | 12 |  | 50 Ohms | TOP=L2:L3=L2/L4:L6=L5/L7:BOTTOM=L7 |
| JTAG_BMC_TDO | OTHERS | BUS | 5 | 5 | 5 | 10 | 5 | 14 | 6 | 10 | 12 | 12 | 12 | 12 |  | 50 Ohms | TOP=L2:L3=L2/L4:L6=L5/L7:BOTTOM=L7 |
| JTAG_BMC_TDO | OTHERS | BUS | 6 | 5 | 5 | 10 | 5 | 14 | 6 | 10 | 12 | 12 | 12 | 12 |  | 50 Ohms | TOP=L2:L3=L2/L4:L6=L5/L7:BOTTOM=L7 |
| JTAG_BMC_TDO | OTHERS | BUS | 7 | 5 | 5 | 10 | 5 | 14 | 6 | 10 | 12 | 12 | 12 | 12 |  | 50 Ohms | TOP=L2:L3=L2/L4:L6=L5/L7:BOTTOM=L7 |
| JTAG_BMC_TDO | OTHERS | BUS | 8 | 4.75 | 5 | 10 | 5 | 14 | 6 | 9.5 | 12 | 12 | 12 | 12 |  | 50 Ohms | TOP=L2:L3=L2/L4:L6=L5/L7:BOTTOM=L7 |
| JTAG_BMC_TMS | OTHERS | BUS | 1 | 4.75 | 5 | 10 | 5 | 14 | 6 | 9.5 | 12 | 12 | 12 | 12 |  | 50 Ohms | TOP=L2:L3=L2/L4:L6=L5/L7:BOTTOM=L7 |
| JTAG_BMC_TMS | OTHERS | BUS | 2 | 5 | 5 | 10 | 5 | 14 | 6 | 10 | 12 | 12 | 12 | 12 |  | 50 Ohms | TOP=L2:L3=L2/L4:L6=L5/L7:BOTTOM=L7 |
| JTAG_BMC_TMS | OTHERS | BUS | 3 | 5 | 5 | 10 | 5 | 14 | 6 | 10 | 12 | 12 | 12 | 12 |  | 50 Ohms | TOP=L2:L3=L2/L4:L6=L5/L7:BOTTOM=L7 |
| JTAG_BMC_TMS | OTHERS | BUS | 4 | 5 | 5 | 10 | 5 | 14 | 6 | 10 | 12 | 12 | 12 | 12 |  | 50 Ohms | TOP=L2:L3=L2/L4:L6=L5/L7:BOTTOM=L7 |
| JTAG_BMC_TMS | OTHERS | BUS | 5 | 5 | 5 | 10 | 5 | 14 | 6 | 10 | 12 | 12 | 12 | 12 |  | 50 Ohms | TOP=L2:L3=L2/L4:L6=L5/L7:BOTTOM=L7 |
| JTAG_BMC_TMS | OTHERS | BUS | 6 | 5 | 5 | 10 | 5 | 14 | 6 | 10 | 12 | 12 | 12 | 12 |  | 50 Ohms | TOP=L2:L3=L2/L4:L6=L5/L7:BOTTOM=L7 |
| JTAG_BMC_TMS | OTHERS | BUS | 7 | 5 | 5 | 10 | 5 | 14 | 6 | 10 | 12 | 12 | 12 | 12 |  | 50 Ohms | TOP=L2:L3=L2/L4:L6=L5/L7:BOTTOM=L7 |
| JTAG_BMC_TMS | OTHERS | BUS | 8 | 4.75 | 5 | 10 | 5 | 14 | 6 | 9.5 | 12 | 12 | 12 | 12 |  | 50 Ohms | TOP=L2:L3=L2/L4:L6=L5/L7:BOTTOM=L7 |
| JTAG_BMC_TRST_N | OTHERS | BUS | 1 | 4.75 | 5 | 10 | 5 | 14 | 6 | 9.5 | 12 | 12 | 12 | 12 |  | 50 Ohms | TOP=L2:L3=L2/L4:L6=L5/L7:BOTTOM=L7 |
| JTAG_BMC_TRST_N | OTHERS | BUS | 2 | 5 | 5 | 10 | 5 | 14 | 6 | 10 | 12 | 12 | 12 | 12 |  | 50 Ohms | TOP=L2:L3=L2/L4:L6=L5/L7:BOTTOM=L7 |
| JTAG_BMC_TRST_N | OTHERS | BUS | 3 | 5 | 5 | 10 | 5 | 14 | 6 | 10 | 12 | 12 | 12 | 12 |  | 50 Ohms | TOP=L2:L3=L2/L4:L6=L5/L7:BOTTOM=L7 |
| JTAG_BMC_TRST_N | OTHERS | BUS | 4 | 5 | 5 | 10 | 5 | 14 | 6 | 10 | 12 | 12 | 12 | 12 |  | 50 Ohms | TOP=L2:L3=L2/L4:L6=L5/L7:BOTTOM=L7 |
| JTAG_BMC_TRST_N | OTHERS | BUS | 5 | 5 | 5 | 10 | 5 | 14 | 6 | 10 | 12 | 12 | 12 | 12 |  | 50 Ohms | TOP=L2:L3=L2/L4:L6=L5/L7:BOTTOM=L7 |
| JTAG_BMC_TRST_N | OTHERS | BUS | 6 | 5 | 5 | 10 | 5 | 14 | 6 | 10 | 12 | 12 | 12 | 12 |  | 50 Ohms | TOP=L2:L3=L2/L4:L6=L5/L7:BOTTOM=L7 |
| JTAG_BMC_TRST_N | OTHERS | BUS | 7 | 5 | 5 | 10 | 5 | 14 | 6 | 10 | 12 | 12 | 12 | 12 |  | 50 Ohms | TOP=L2:L3=L2/L4:L6=L5/L7:BOTTOM=L7 |
| JTAG_BMC_TRST_N | OTHERS | BUS | 8 | 4.75 | 5 | 10 | 5 | 14 | 6 | 9.5 | 12 | 12 | 12 | 12 |  | 50 Ohms | TOP=L2:L3=L2/L4:L6=L5/L7:BOTTOM=L7 |
| LAN_MAIN_PWR_OK | OTHERS | BUS | 1 | 4.75 | 5 | 10 | 5 | 14 | 6 | 9.5 | 12 | 12 | 12 | 12 |  | 50 Ohms | TOP=L2:L3=L2/L4:L6=L5/L7:BOTTOM=L7 |
| LAN_MAIN_PWR_OK | OTHERS | BUS | 2 | 5 | 5 | 10 | 5 | 14 | 6 | 10 | 12 | 12 | 12 | 12 |  | 50 Ohms | TOP=L2:L3=L2/L4:L6=L5/L7:BOTTOM=L7 |
| LAN_MAIN_PWR_OK | OTHERS | BUS | 3 | 5 | 5 | 10 | 5 | 14 | 6 | 10 | 12 | 12 | 12 | 12 |  | 50 Ohms | TOP=L2:L3=L2/L4:L6=L5/L7:BOTTOM=L7 |
| LAN_MAIN_PWR_OK | OTHERS | BUS | 4 | 5 | 5 | 10 | 5 | 14 | 6 | 10 | 12 | 12 | 12 | 12 |  | 50 Ohms | TOP=L2:L3=L2/L4:L6=L5/L7:BOTTOM=L7 |
| LAN_MAIN_PWR_OK | OTHERS | BUS | 5 | 5 | 5 | 10 | 5 | 14 | 6 | 10 | 12 | 12 | 12 | 12 |  | 50 Ohms | TOP=L2:L3=L2/L4:L6=L5/L7:BOTTOM=L7 |
| LAN_MAIN_PWR_OK | OTHERS | BUS | 6 | 5 | 5 | 10 | 5 | 14 | 6 | 10 | 12 | 12 | 12 | 12 |  | 50 Ohms | TOP=L2:L3=L2/L4:L6=L5/L7:BOTTOM=L7 |
| LAN_MAIN_PWR_OK | OTHERS | BUS | 7 | 5 | 5 | 10 | 5 | 14 | 6 | 10 | 12 | 12 | 12 | 12 |  | 50 Ohms | TOP=L2:L3=L2/L4:L6=L5/L7:BOTTOM=L7 |
| LAN_MAIN_PWR_OK | OTHERS | BUS | 8 | 4.75 | 5 | 10 | 5 | 14 | 6 | 9.5 | 12 | 12 | 12 | 12 |  | 50 Ohms | TOP=L2:L3=L2/L4:L6=L5/L7:BOTTOM=L7 |
| LAN_SE_RSET | OTHERS | BUS | 1 | 4.75 | 5 | 10 | 5 | 14 | 6 | 9.5 | 12 | 12 | 12 | 12 |  | 50 Ohms | TOP=L2:L3=L2/L4:L6=L5/L7:BOTTOM=L7 |
| LAN_SE_RSET | OTHERS | BUS | 2 | 5 | 5 | 10 | 5 | 14 | 6 | 10 | 12 | 12 | 12 | 12 |  | 50 Ohms | TOP=L2:L3=L2/L4:L6=L5/L7:BOTTOM=L7 |
| LAN_SE_RSET | OTHERS | BUS | 3 | 5 | 5 | 10 | 5 | 14 | 6 | 10 | 12 | 12 | 12 | 12 |  | 50 Ohms | TOP=L2:L3=L2/L4:L6=L5/L7:BOTTOM=L7 |
| LAN_SE_RSET | OTHERS | BUS | 4 | 5 | 5 | 10 | 5 | 14 | 6 | 10 | 12 | 12 | 12 | 12 |  | 50 Ohms | TOP=L2:L3=L2/L4:L6=L5/L7:BOTTOM=L7 |
| LAN_SE_RSET | OTHERS | BUS | 5 | 5 | 5 | 10 | 5 | 14 | 6 | 10 | 12 | 12 | 12 | 12 |  | 50 Ohms | TOP=L2:L3=L2/L4:L6=L5/L7:BOTTOM=L7 |
| LAN_SE_RSET | OTHERS | BUS | 6 | 5 | 5 | 10 | 5 | 14 | 6 | 10 | 12 | 12 | 12 | 12 |  | 50 Ohms | TOP=L2:L3=L2/L4:L6=L5/L7:BOTTOM=L7 |
| LAN_SE_RSET | OTHERS | BUS | 7 | 5 | 5 | 10 | 5 | 14 | 6 | 10 | 12 | 12 | 12 | 12 |  | 50 Ohms | TOP=L2:L3=L2/L4:L6=L5/L7:BOTTOM=L7 |
| LAN_SE_RSET | OTHERS | BUS | 8 | 4.75 | 5 | 10 | 5 | 14 | 6 | 9.5 | 12 | 12 | 12 | 12 |  | 50 Ohms | TOP=L2:L3=L2/L4:L6=L5/L7:BOTTOM=L7 |
| LAN_SMB_ALERT_N | OTHERS | BUS | 1 | 4.75 | 5 | 10 | 5 | 14 | 6 | 9.5 | 12 | 12 | 12 | 12 |  | 50 Ohms | TOP=L2:L3=L2/L4:L6=L5/L7:BOTTOM=L7 |
| LAN_SMB_ALERT_N | OTHERS | BUS | 2 | 5 | 5 | 10 | 5 | 14 | 6 | 10 | 12 | 12 | 12 | 12 |  | 50 Ohms | TOP=L2:L3=L2/L4:L6=L5/L7:BOTTOM=L7 |
| LAN_SMB_ALERT_N | OTHERS | BUS | 3 | 5 | 5 | 10 | 5 | 14 | 6 | 10 | 12 | 12 | 12 | 12 |  | 50 Ohms | TOP=L2:L3=L2/L4:L6=L5/L7:BOTTOM=L7 |
| LAN_SMB_ALERT_N | OTHERS | BUS | 4 | 5 | 5 | 10 | 5 | 14 | 6 | 10 | 12 | 12 | 12 | 12 |  | 50 Ohms | TOP=L2:L3=L2/L4:L6=L5/L7:BOTTOM=L7 |
| LAN_SMB_ALERT_N | OTHERS | BUS | 5 | 5 | 5 | 10 | 5 | 14 | 6 | 10 | 12 | 12 | 12 | 12 |  | 50 Ohms | TOP=L2:L3=L2/L4:L6=L5/L7:BOTTOM=L7 |
| LAN_SMB_ALERT_N | OTHERS | BUS | 6 | 5 | 5 | 10 | 5 | 14 | 6 | 10 | 12 | 12 | 12 | 12 |  | 50 Ohms | TOP=L2:L3=L2/L4:L6=L5/L7:BOTTOM=L7 |
| LAN_SMB_ALERT_N | OTHERS | BUS | 7 | 5 | 5 | 10 | 5 | 14 | 6 | 10 | 12 | 12 | 12 | 12 |  | 50 Ohms | TOP=L2:L3=L2/L4:L6=L5/L7:BOTTOM=L7 |
| LAN_SMB_ALERT_N | OTHERS | BUS | 8 | 4.75 | 5 | 10 | 5 | 14 | 6 | 9.5 | 12 | 12 | 12 | 12 |  | 50 Ohms | TOP=L2:L3=L2/L4:L6=L5/L7:BOTTOM=L7 |
| LAN_SMB_ALERT_N_R | OTHERS | BUS | 1 | 4.75 | 5 | 10 | 5 | 14 | 6 | 9.5 | 12 | 12 | 12 | 12 |  | 50 Ohms | TOP=L2:L3=L2/L4:L6=L5/L7:BOTTOM=L7 |
| LAN_SMB_ALERT_N_R | OTHERS | BUS | 2 | 5 | 5 | 10 | 5 | 14 | 6 | 10 | 12 | 12 | 12 | 12 |  | 50 Ohms | TOP=L2:L3=L2/L4:L6=L5/L7:BOTTOM=L7 |
| LAN_SMB_ALERT_N_R | OTHERS | BUS | 3 | 5 | 5 | 10 | 5 | 14 | 6 | 10 | 12 | 12 | 12 | 12 |  | 50 Ohms | TOP=L2:L3=L2/L4:L6=L5/L7:BOTTOM=L7 |
| LAN_SMB_ALERT_N_R | OTHERS | BUS | 4 | 5 | 5 | 10 | 5 | 14 | 6 | 10 | 12 | 12 | 12 | 12 |  | 50 Ohms | TOP=L2:L3=L2/L4:L6=L5/L7:BOTTOM=L7 |
| LAN_SMB_ALERT_N_R | OTHERS | BUS | 5 | 5 | 5 | 10 | 5 | 14 | 6 | 10 | 12 | 12 | 12 | 12 |  | 50 Ohms | TOP=L2:L3=L2/L4:L6=L5/L7:BOTTOM=L7 |
| LAN_SMB_ALERT_N_R | OTHERS | BUS | 6 | 5 | 5 | 10 | 5 | 14 | 6 | 10 | 12 | 12 | 12 | 12 |  | 50 Ohms | TOP=L2:L3=L2/L4:L6=L5/L7:BOTTOM=L7 |
| LAN_SMB_ALERT_N_R | OTHERS | BUS | 7 | 5 | 5 | 10 | 5 | 14 | 6 | 10 | 12 | 12 | 12 | 12 |  | 50 Ohms | TOP=L2:L3=L2/L4:L6=L5/L7:BOTTOM=L7 |
| LAN_SMB_ALERT_N_R | OTHERS | BUS | 8 | 4.75 | 5 | 10 | 5 | 14 | 6 | 9.5 | 12 | 12 | 12 | 12 |  | 50 Ohms | TOP=L2:L3=L2/L4:L6=L5/L7:BOTTOM=L7 |
| LAN1_51 | OTHERS | BUS | 1 | 4.75 | 5 | 10 | 5 | 14 | 6 | 9.5 | 12 | 12 | 12 | 12 |  | 50 Ohms | TOP=L2:L3=L2/L4:L6=L5/L7:BOTTOM=L7 |
| LAN1_51 | OTHERS | BUS | 2 | 5 | 5 | 10 | 5 | 14 | 6 | 10 | 12 | 12 | 12 | 12 |  | 50 Ohms | TOP=L2:L3=L2/L4:L6=L5/L7:BOTTOM=L7 |
| LAN1_51 | OTHERS | BUS | 3 | 5 | 5 | 10 | 5 | 14 | 6 | 10 | 12 | 12 | 12 | 12 |  | 50 Ohms | TOP=L2:L3=L2/L4:L6=L5/L7:BOTTOM=L7 |
| LAN1_51 | OTHERS | BUS | 4 | 5 | 5 | 10 | 5 | 14 | 6 | 10 | 12 | 12 | 12 | 12 |  | 50 Ohms | TOP=L2:L3=L2/L4:L6=L5/L7:BOTTOM=L7 |
| LAN1_51 | OTHERS | BUS | 5 | 5 | 5 | 10 | 5 | 14 | 6 | 10 | 12 | 12 | 12 | 12 |  | 50 Ohms | TOP=L2:L3=L2/L4:L6=L5/L7:BOTTOM=L7 |
| LAN1_51 | OTHERS | BUS | 6 | 5 | 5 | 10 | 5 | 14 | 6 | 10 | 12 | 12 | 12 | 12 |  | 50 Ohms | TOP=L2:L3=L2/L4:L6=L5/L7:BOTTOM=L7 |
| LAN1_51 | OTHERS | BUS | 7 | 5 | 5 | 10 | 5 | 14 | 6 | 10 | 12 | 12 | 12 | 12 |  | 50 Ohms | TOP=L2:L3=L2/L4:L6=L5/L7:BOTTOM=L7 |
| LAN1_51 | OTHERS | BUS | 8 | 4.75 | 5 | 10 | 5 | 14 | 6 | 9.5 | 12 | 12 | 12 | 12 |  | 50 Ohms | TOP=L2:L3=L2/L4:L6=L5/L7:BOTTOM=L7 |
| LAN1_56 | OTHERS | BUS | 1 | 4.75 | 5 | 10 | 5 | 14 | 6 | 9.5 | 12 | 12 | 12 | 12 |  | 50 Ohms | TOP=L2:L3=L2/L4:L6=L5/L7:BOTTOM=L7 |
| LAN1_56 | OTHERS | BUS | 2 | 5 | 5 | 10 | 5 | 14 | 6 | 10 | 12 | 12 | 12 | 12 |  | 50 Ohms | TOP=L2:L3=L2/L4:L6=L5/L7:BOTTOM=L7 |
| LAN1_56 | OTHERS | BUS | 3 | 5 | 5 | 10 | 5 | 14 | 6 | 10 | 12 | 12 | 12 | 12 |  | 50 Ohms | TOP=L2:L3=L2/L4:L6=L5/L7:BOTTOM=L7 |
| LAN1_56 | OTHERS | BUS | 4 | 5 | 5 | 10 | 5 | 14 | 6 | 10 | 12 | 12 | 12 | 12 |  | 50 Ohms | TOP=L2:L3=L2/L4:L6=L5/L7:BOTTOM=L7 |
| LAN1_56 | OTHERS | BUS | 5 | 5 | 5 | 10 | 5 | 14 | 6 | 10 | 12 | 12 | 12 | 12 |  | 50 Ohms | TOP=L2:L3=L2/L4:L6=L5/L7:BOTTOM=L7 |
| LAN1_56 | OTHERS | BUS | 6 | 5 | 5 | 10 | 5 | 14 | 6 | 10 | 12 | 12 | 12 | 12 |  | 50 Ohms | TOP=L2:L3=L2/L4:L6=L5/L7:BOTTOM=L7 |
| LAN1_56 | OTHERS | BUS | 7 | 5 | 5 | 10 | 5 | 14 | 6 | 10 | 12 | 12 | 12 | 12 |  | 50 Ohms | TOP=L2:L3=L2/L4:L6=L5/L7:BOTTOM=L7 |
| LAN1_56 | OTHERS | BUS | 8 | 4.75 | 5 | 10 | 5 | 14 | 6 | 9.5 | 12 | 12 | 12 | 12 |  | 50 Ohms | TOP=L2:L3=L2/L4:L6=L5/L7:BOTTOM=L7 |
| LBI_ADDR_0_R | OTHERS | BUS | 1 | 4.75 | 5 | 10 | 5 | 14 | 6 | 9.5 | 12 | 12 | 12 | 12 |  | 50 Ohms | TOP=L2:L3=L2/L4:L6=L5/L7:BOTTOM=L7 |
| LBI_ADDR_0_R | OTHERS | BUS | 2 | 5 | 5 | 10 | 5 | 14 | 6 | 10 | 12 | 12 | 12 | 12 |  | 50 Ohms | TOP=L2:L3=L2/L4:L6=L5/L7:BOTTOM=L7 |
| LBI_ADDR_0_R | OTHERS | BUS | 3 | 5 | 5 | 10 | 5 | 14 | 6 | 10 | 12 | 12 | 12 | 12 |  | 50 Ohms | TOP=L2:L3=L2/L4:L6=L5/L7:BOTTOM=L7 |
| LBI_ADDR_0_R | OTHERS | BUS | 4 | 5 | 5 | 10 | 5 | 14 | 6 | 10 | 12 | 12 | 12 | 12 |  | 50 Ohms | TOP=L2:L3=L2/L4:L6=L5/L7:BOTTOM=L7 |
| LBI_ADDR_0_R | OTHERS | BUS | 5 | 5 | 5 | 10 | 5 | 14 | 6 | 10 | 12 | 12 | 12 | 12 |  | 50 Ohms | TOP=L2:L3=L2/L4:L6=L5/L7:BOTTOM=L7 |
| LBI_ADDR_0_R | OTHERS | BUS | 6 | 5 | 5 | 10 | 5 | 14 | 6 | 10 | 12 | 12 | 12 | 12 |  | 50 Ohms | TOP=L2:L3=L2/L4:L6=L5/L7:BOTTOM=L7 |
| LBI_ADDR_0_R | OTHERS | BUS | 7 | 5 | 5 | 10 | 5 | 14 | 6 | 10 | 12 | 12 | 12 | 12 |  | 50 Ohms | TOP=L2:L3=L2/L4:L6=L5/L7:BOTTOM=L7 |
| LBI_ADDR_0_R | OTHERS | BUS | 8 | 4.75 | 5 | 10 | 5 | 14 | 6 | 9.5 | 12 | 12 | 12 | 12 |  | 50 Ohms | TOP=L2:L3=L2/L4:L6=L5/L7:BOTTOM=L7 |
| LBI_ADDR_1_R | OTHERS | BUS | 1 | 4.75 | 5 | 10 | 5 | 14 | 6 | 9.5 | 12 | 12 | 12 | 12 |  | 50 Ohms | TOP=L2:L3=L2/L4:L6=L5/L7:BOTTOM=L7 |
| LBI_ADDR_1_R | OTHERS | BUS | 2 | 5 | 5 | 10 | 5 | 14 | 6 | 10 | 12 | 12 | 12 | 12 |  | 50 Ohms | TOP=L2:L3=L2/L4:L6=L5/L7:BOTTOM=L7 |
| LBI_ADDR_1_R | OTHERS | BUS | 3 | 5 | 5 | 10 | 5 | 14 | 6 | 10 | 12 | 12 | 12 | 12 |  | 50 Ohms | TOP=L2:L3=L2/L4:L6=L5/L7:BOTTOM=L7 |
| LBI_ADDR_1_R | OTHERS | BUS | 4 | 5 | 5 | 10 | 5 | 14 | 6 | 10 | 12 | 12 | 12 | 12 |  | 50 Ohms | TOP=L2:L3=L2/L4:L6=L5/L7:BOTTOM=L7 |
| LBI_ADDR_1_R | OTHERS | BUS | 5 | 5 | 5 | 10 | 5 | 14 | 6 | 10 | 12 | 12 | 12 | 12 |  | 50 Ohms | TOP=L2:L3=L2/L4:L6=L5/L7:BOTTOM=L7 |
| LBI_ADDR_1_R | OTHERS | BUS | 6 | 5 | 5 | 10 | 5 | 14 | 6 | 10 | 12 | 12 | 12 | 12 |  | 50 Ohms | TOP=L2:L3=L2/L4:L6=L5/L7:BOTTOM=L7 |
| LBI_ADDR_1_R | OTHERS | BUS | 7 | 5 | 5 | 10 | 5 | 14 | 6 | 10 | 12 | 12 | 12 | 12 |  | 50 Ohms | TOP=L2:L3=L2/L4:L6=L5/L7:BOTTOM=L7 |
| LBI_ADDR_1_R | OTHERS | BUS | 8 | 4.75 | 5 | 10 | 5 | 14 | 6 | 9.5 | 12 | 12 | 12 | 12 |  | 50 Ohms | TOP=L2:L3=L2/L4:L6=L5/L7:BOTTOM=L7 |
| LBI_ADDR_10 | OTHERS | BUS | 1 | 4.75 | 5 | 10 | 5 | 14 | 6 | 9.5 | 12 | 12 | 12 | 12 |  | 50 Ohms | TOP=L2:L3=L2/L4:L6=L5/L7:BOTTOM=L7 |
| LBI_ADDR_10 | OTHERS | BUS | 2 | 5 | 5 | 10 | 5 | 14 | 6 | 10 | 12 | 12 | 12 | 12 |  | 50 Ohms | TOP=L2:L3=L2/L4:L6=L5/L7:BOTTOM=L7 |
| LBI_ADDR_10 | OTHERS | BUS | 3 | 5 | 5 | 10 | 5 | 14 | 6 | 10 | 12 | 12 | 12 | 12 |  | 50 Ohms | TOP=L2:L3=L2/L4:L6=L5/L7:BOTTOM=L7 |
| LBI_ADDR_10 | OTHERS | BUS | 4 | 5 | 5 | 10 | 5 | 14 | 6 | 10 | 12 | 12 | 12 | 12 |  | 50 Ohms | TOP=L2:L3=L2/L4:L6=L5/L7:BOTTOM=L7 |
| LBI_ADDR_10 | OTHERS | BUS | 5 | 5 | 5 | 10 | 5 | 14 | 6 | 10 | 12 | 12 | 12 | 12 |  | 50 Ohms | TOP=L2:L3=L2/L4:L6=L5/L7:BOTTOM=L7 |
| LBI_ADDR_10 | OTHERS | BUS | 6 | 5 | 5 | 10 | 5 | 14 | 6 | 10 | 12 | 12 | 12 | 12 |  | 50 Ohms | TOP=L2:L3=L2/L4:L6=L5/L7:BOTTOM=L7 |
| LBI_ADDR_10 | OTHERS | BUS | 7 | 5 | 5 | 10 | 5 | 14 | 6 | 10 | 12 | 12 | 12 | 12 |  | 50 Ohms | TOP=L2:L3=L2/L4:L6=L5/L7:BOTTOM=L7 |
| LBI_ADDR_10 | OTHERS | BUS | 8 | 4.75 | 5 | 10 | 5 | 14 | 6 | 9.5 | 12 | 12 | 12 | 12 |  | 50 Ohms | TOP=L2:L3=L2/L4:L6=L5/L7:BOTTOM=L7 |
| LBI_ADDR_12_R | OTHERS | BUS | 1 | 4.75 | 5 | 10 | 5 | 14 | 6 | 9.5 | 12 | 12 | 12 | 12 |  | 50 Ohms | TOP=L2:L3=L2/L4:L6=L5/L7:BOTTOM=L7 |
| LBI_ADDR_12_R | OTHERS | BUS | 2 | 5 | 5 | 10 | 5 | 14 | 6 | 10 | 12 | 12 | 12 | 12 |  | 50 Ohms | TOP=L2:L3=L2/L4:L6=L5/L7:BOTTOM=L7 |
| LBI_ADDR_12_R | OTHERS | BUS | 3 | 5 | 5 | 10 | 5 | 14 | 6 | 10 | 12 | 12 | 12 | 12 |  | 50 Ohms | TOP=L2:L3=L2/L4:L6=L5/L7:BOTTOM=L7 |
| LBI_ADDR_12_R | OTHERS | BUS | 4 | 5 | 5 | 10 | 5 | 14 | 6 | 10 | 12 | 12 | 12 | 12 |  | 50 Ohms | TOP=L2:L3=L2/L4:L6=L5/L7:BOTTOM=L7 |
| LBI_ADDR_12_R | OTHERS | BUS | 5 | 5 | 5 | 10 | 5 | 14 | 6 | 10 | 12 | 12 | 12 | 12 |  | 50 Ohms | TOP=L2:L3=L2/L4:L6=L5/L7:BOTTOM=L7 |
| LBI_ADDR_12_R | OTHERS | BUS | 6 | 5 | 5 | 10 | 5 | 14 | 6 | 10 | 12 | 12 | 12 | 12 |  | 50 Ohms | TOP=L2:L3=L2/L4:L6=L5/L7:BOTTOM=L7 |
| LBI_ADDR_12_R | OTHERS | BUS | 7 | 5 | 5 | 10 | 5 | 14 | 6 | 10 | 12 | 12 | 12 | 12 |  | 50 Ohms | TOP=L2:L3=L2/L4:L6=L5/L7:BOTTOM=L7 |
| LBI_ADDR_12_R | OTHERS | BUS | 8 | 4.75 | 5 | 10 | 5 | 14 | 6 | 9.5 | 12 | 12 | 12 | 12 |  | 50 Ohms | TOP=L2:L3=L2/L4:L6=L5/L7:BOTTOM=L7 |
| LBI_ADDR_2_R | OTHERS | BUS | 1 | 4.75 | 5 | 10 | 5 | 14 | 6 | 9.5 | 12 | 12 | 12 | 12 |  | 50 Ohms | TOP=L2:L3=L2/L4:L6=L5/L7:BOTTOM=L7 |
| LBI_ADDR_2_R | OTHERS | BUS | 2 | 5 | 5 | 10 | 5 | 14 | 6 | 10 | 12 | 12 | 12 | 12 |  | 50 Ohms | TOP=L2:L3=L2/L4:L6=L5/L7:BOTTOM=L7 |
| LBI_ADDR_2_R | OTHERS | BUS | 3 | 5 | 5 | 10 | 5 | 14 | 6 | 10 | 12 | 12 | 12 | 12 |  | 50 Ohms | TOP=L2:L3=L2/L4:L6=L5/L7:BOTTOM=L7 |
| LBI_ADDR_2_R | OTHERS | BUS | 4 | 5 | 5 | 10 | 5 | 14 | 6 | 10 | 12 | 12 | 12 | 12 |  | 50 Ohms | TOP=L2:L3=L2/L4:L6=L5/L7:BOTTOM=L7 |
| LBI_ADDR_2_R | OTHERS | BUS | 5 | 5 | 5 | 10 | 5 | 14 | 6 | 10 | 12 | 12 | 12 | 12 |  | 50 Ohms | TOP=L2:L3=L2/L4:L6=L5/L7:BOTTOM=L7 |
| LBI_ADDR_2_R | OTHERS | BUS | 6 | 5 | 5 | 10 | 5 | 14 | 6 | 10 | 12 | 12 | 12 | 12 |  | 50 Ohms | TOP=L2:L3=L2/L4:L6=L5/L7:BOTTOM=L7 |
| LBI_ADDR_2_R | OTHERS | BUS | 7 | 5 | 5 | 10 | 5 | 14 | 6 | 10 | 12 | 12 | 12 | 12 |  | 50 Ohms | TOP=L2:L3=L2/L4:L6=L5/L7:BOTTOM=L7 |
| LBI_ADDR_2_R | OTHERS | BUS | 8 | 4.75 | 5 | 10 | 5 | 14 | 6 | 9.5 | 12 | 12 | 12 | 12 |  | 50 Ohms | TOP=L2:L3=L2/L4:L6=L5/L7:BOTTOM=L7 |
| LBI_ADDR_3_R | OTHERS | BUS | 1 | 4.75 | 5 | 10 | 5 | 14 | 6 | 9.5 | 12 | 12 | 12 | 12 |  | 50 Ohms | TOP=L2:L3=L2/L4:L6=L5/L7:BOTTOM=L7 |
| LBI_ADDR_3_R | OTHERS | BUS | 2 | 5 | 5 | 10 | 5 | 14 | 6 | 10 | 12 | 12 | 12 | 12 |  | 50 Ohms | TOP=L2:L3=L2/L4:L6=L5/L7:BOTTOM=L7 |
| LBI_ADDR_3_R | OTHERS | BUS | 3 | 5 | 5 | 10 | 5 | 14 | 6 | 10 | 12 | 12 | 12 | 12 |  | 50 Ohms | TOP=L2:L3=L2/L4:L6=L5/L7:BOTTOM=L7 |
| LBI_ADDR_3_R | OTHERS | BUS | 4 | 5 | 5 | 10 | 5 | 14 | 6 | 10 | 12 | 12 | 12 | 12 |  | 50 Ohms | TOP=L2:L3=L2/L4:L6=L5/L7:BOTTOM=L7 |
| LBI_ADDR_3_R | OTHERS | BUS | 5 | 5 | 5 | 10 | 5 | 14 | 6 | 10 | 12 | 12 | 12 | 12 |  | 50 Ohms | TOP=L2:L3=L2/L4:L6=L5/L7:BOTTOM=L7 |
| LBI_ADDR_3_R | OTHERS | BUS | 6 | 5 | 5 | 10 | 5 | 14 | 6 | 10 | 12 | 12 | 12 | 12 |  | 50 Ohms | TOP=L2:L3=L2/L4:L6=L5/L7:BOTTOM=L7 |
| LBI_ADDR_3_R | OTHERS | BUS | 7 | 5 | 5 | 10 | 5 | 14 | 6 | 10 | 12 | 12 | 12 | 12 |  | 50 Ohms | TOP=L2:L3=L2/L4:L6=L5/L7:BOTTOM=L7 |
| LBI_ADDR_3_R | OTHERS | BUS | 8 | 4.75 | 5 | 10 | 5 | 14 | 6 | 9.5 | 12 | 12 | 12 | 12 |  | 50 Ohms | TOP=L2:L3=L2/L4:L6=L5/L7:BOTTOM=L7 |
| LBI_ADDR_4_R | OTHERS | BUS | 1 | 4.75 | 5 | 10 | 5 | 14 | 6 | 9.5 | 12 | 12 | 12 | 12 |  | 50 Ohms | TOP=L2:L3=L2/L4:L6=L5/L7:BOTTOM=L7 |
| LBI_ADDR_4_R | OTHERS | BUS | 2 | 5 | 5 | 10 | 5 | 14 | 6 | 10 | 12 | 12 | 12 | 12 |  | 50 Ohms | TOP=L2:L3=L2/L4:L6=L5/L7:BOTTOM=L7 |
| LBI_ADDR_4_R | OTHERS | BUS | 3 | 5 | 5 | 10 | 5 | 14 | 6 | 10 | 12 | 12 | 12 | 12 |  | 50 Ohms | TOP=L2:L3=L2/L4:L6=L5/L7:BOTTOM=L7 |
| LBI_ADDR_4_R | OTHERS | BUS | 4 | 5 | 5 | 10 | 5 | 14 | 6 | 10 | 12 | 12 | 12 | 12 |  | 50 Ohms | TOP=L2:L3=L2/L4:L6=L5/L7:BOTTOM=L7 |
| LBI_ADDR_4_R | OTHERS | BUS | 5 | 5 | 5 | 10 | 5 | 14 | 6 | 10 | 12 | 12 | 12 | 12 |  | 50 Ohms | TOP=L2:L3=L2/L4:L6=L5/L7:BOTTOM=L7 |
| LBI_ADDR_4_R | OTHERS | BUS | 6 | 5 | 5 | 10 | 5 | 14 | 6 | 10 | 12 | 12 | 12 | 12 |  | 50 Ohms | TOP=L2:L3=L2/L4:L6=L5/L7:BOTTOM=L7 |
| LBI_ADDR_4_R | OTHERS | BUS | 7 | 5 | 5 | 10 | 5 | 14 | 6 | 10 | 12 | 12 | 12 | 12 |  | 50 Ohms | TOP=L2:L3=L2/L4:L6=L5/L7:BOTTOM=L7 |
| LBI_ADDR_4_R | OTHERS | BUS | 8 | 4.75 | 5 | 10 | 5 | 14 | 6 | 9.5 | 12 | 12 | 12 | 12 |  | 50 Ohms | TOP=L2:L3=L2/L4:L6=L5/L7:BOTTOM=L7 |
| LBI_ADDR_5_R | OTHERS | BUS | 1 | 4.75 | 5 | 10 | 5 | 14 | 6 | 9.5 | 12 | 12 | 12 | 12 |  | 50 Ohms | TOP=L2:L3=L2/L4:L6=L5/L7:BOTTOM=L7 |
| LBI_ADDR_5_R | OTHERS | BUS | 2 | 5 | 5 | 10 | 5 | 14 | 6 | 10 | 12 | 12 | 12 | 12 |  | 50 Ohms | TOP=L2:L3=L2/L4:L6=L5/L7:BOTTOM=L7 |
| LBI_ADDR_5_R | OTHERS | BUS | 3 | 5 | 5 | 10 | 5 | 14 | 6 | 10 | 12 | 12 | 12 | 12 |  | 50 Ohms | TOP=L2:L3=L2/L4:L6=L5/L7:BOTTOM=L7 |
| LBI_ADDR_5_R | OTHERS | BUS | 4 | 5 | 5 | 10 | 5 | 14 | 6 | 10 | 12 | 12 | 12 | 12 |  | 50 Ohms | TOP=L2:L3=L2/L4:L6=L5/L7:BOTTOM=L7 |
| LBI_ADDR_5_R | OTHERS | BUS | 5 | 5 | 5 | 10 | 5 | 14 | 6 | 10 | 12 | 12 | 12 | 12 |  | 50 Ohms | TOP=L2:L3=L2/L4:L6=L5/L7:BOTTOM=L7 |
| LBI_ADDR_5_R | OTHERS | BUS | 6 | 5 | 5 | 10 | 5 | 14 | 6 | 10 | 12 | 12 | 12 | 12 |  | 50 Ohms | TOP=L2:L3=L2/L4:L6=L5/L7:BOTTOM=L7 |
| LBI_ADDR_5_R | OTHERS | BUS | 7 | 5 | 5 | 10 | 5 | 14 | 6 | 10 | 12 | 12 | 12 | 12 |  | 50 Ohms | TOP=L2:L3=L2/L4:L6=L5/L7:BOTTOM=L7 |
| LBI_ADDR_5_R | OTHERS | BUS | 8 | 4.75 | 5 | 10 | 5 | 14 | 6 | 9.5 | 12 | 12 | 12 | 12 |  | 50 Ohms | TOP=L2:L3=L2/L4:L6=L5/L7:BOTTOM=L7 |
| LBI_ADDR_6_R | OTHERS | BUS | 1 | 4.75 | 5 | 10 | 5 | 14 | 6 | 9.5 | 12 | 12 | 12 | 12 |  | 50 Ohms | TOP=L2:L3=L2/L4:L6=L5/L7:BOTTOM=L7 |
| LBI_ADDR_6_R | OTHERS | BUS | 2 | 5 | 5 | 10 | 5 | 14 | 6 | 10 | 12 | 12 | 12 | 12 |  | 50 Ohms | TOP=L2:L3=L2/L4:L6=L5/L7:BOTTOM=L7 |
| LBI_ADDR_6_R | OTHERS | BUS | 3 | 5 | 5 | 10 | 5 | 14 | 6 | 10 | 12 | 12 | 12 | 12 |  | 50 Ohms | TOP=L2:L3=L2/L4:L6=L5/L7:BOTTOM=L7 |
| LBI_ADDR_6_R | OTHERS | BUS | 4 | 5 | 5 | 10 | 5 | 14 | 6 | 10 | 12 | 12 | 12 | 12 |  | 50 Ohms | TOP=L2:L3=L2/L4:L6=L5/L7:BOTTOM=L7 |
| LBI_ADDR_6_R | OTHERS | BUS | 5 | 5 | 5 | 10 | 5 | 14 | 6 | 10 | 12 | 12 | 12 | 12 |  | 50 Ohms | TOP=L2:L3=L2/L4:L6=L5/L7:BOTTOM=L7 |
| LBI_ADDR_6_R | OTHERS | BUS | 6 | 5 | 5 | 10 | 5 | 14 | 6 | 10 | 12 | 12 | 12 | 12 |  | 50 Ohms | TOP=L2:L3=L2/L4:L6=L5/L7:BOTTOM=L7 |
| LBI_ADDR_6_R | OTHERS | BUS | 7 | 5 | 5 | 10 | 5 | 14 | 6 | 10 | 12 | 12 | 12 | 12 |  | 50 Ohms | TOP=L2:L3=L2/L4:L6=L5/L7:BOTTOM=L7 |
| LBI_ADDR_6_R | OTHERS | BUS | 8 | 4.75 | 5 | 10 | 5 | 14 | 6 | 9.5 | 12 | 12 | 12 | 12 |  | 50 Ohms | TOP=L2:L3=L2/L4:L6=L5/L7:BOTTOM=L7 |
| LBI_ADDR_7_R | OTHERS | BUS | 1 | 4.75 | 5 | 10 | 5 | 14 | 6 | 9.5 | 12 | 12 | 12 | 12 |  | 50 Ohms | TOP=L2:L3=L2/L4:L6=L5/L7:BOTTOM=L7 |
| LBI_ADDR_7_R | OTHERS | BUS | 2 | 5 | 5 | 10 | 5 | 14 | 6 | 10 | 12 | 12 | 12 | 12 |  | 50 Ohms | TOP=L2:L3=L2/L4:L6=L5/L7:BOTTOM=L7 |
| LBI_ADDR_7_R | OTHERS | BUS | 3 | 5 | 5 | 10 | 5 | 14 | 6 | 10 | 12 | 12 | 12 | 12 |  | 50 Ohms | TOP=L2:L3=L2/L4:L6=L5/L7:BOTTOM=L7 |
| LBI_ADDR_7_R | OTHERS | BUS | 4 | 5 | 5 | 10 | 5 | 14 | 6 | 10 | 12 | 12 | 12 | 12 |  | 50 Ohms | TOP=L2:L3=L2/L4:L6=L5/L7:BOTTOM=L7 |
| LBI_ADDR_7_R | OTHERS | BUS | 5 | 5 | 5 | 10 | 5 | 14 | 6 | 10 | 12 | 12 | 12 | 12 |  | 50 Ohms | TOP=L2:L3=L2/L4:L6=L5/L7:BOTTOM=L7 |
| LBI_ADDR_7_R | OTHERS | BUS | 6 | 5 | 5 | 10 | 5 | 14 | 6 | 10 | 12 | 12 | 12 | 12 |  | 50 Ohms | TOP=L2:L3=L2/L4:L6=L5/L7:BOTTOM=L7 |
| LBI_ADDR_7_R | OTHERS | BUS | 7 | 5 | 5 | 10 | 5 | 14 | 6 | 10 | 12 | 12 | 12 | 12 |  | 50 Ohms | TOP=L2:L3=L2/L4:L6=L5/L7:BOTTOM=L7 |
| LBI_ADDR_7_R | OTHERS | BUS | 8 | 4.75 | 5 | 10 | 5 | 14 | 6 | 9.5 | 12 | 12 | 12 | 12 |  | 50 Ohms | TOP=L2:L3=L2/L4:L6=L5/L7:BOTTOM=L7 |
| LBI_ADDR_8 | OTHERS | BUS | 1 | 4.75 | 5 | 10 | 5 | 14 | 6 | 9.5 | 12 | 12 | 12 | 12 |  | 50 Ohms | TOP=L2:L3=L2/L4:L6=L5/L7:BOTTOM=L7 |
| LBI_ADDR_8 | OTHERS | BUS | 2 | 5 | 5 | 10 | 5 | 14 | 6 | 10 | 12 | 12 | 12 | 12 |  | 50 Ohms | TOP=L2:L3=L2/L4:L6=L5/L7:BOTTOM=L7 |
| LBI_ADDR_8 | OTHERS | BUS | 3 | 5 | 5 | 10 | 5 | 14 | 6 | 10 | 12 | 12 | 12 | 12 |  | 50 Ohms | TOP=L2:L3=L2/L4:L6=L5/L7:BOTTOM=L7 |
| LBI_ADDR_8 | OTHERS | BUS | 4 | 5 | 5 | 10 | 5 | 14 | 6 | 10 | 12 | 12 | 12 | 12 |  | 50 Ohms | TOP=L2:L3=L2/L4:L6=L5/L7:BOTTOM=L7 |
| LBI_ADDR_8 | OTHERS | BUS | 5 | 5 | 5 | 10 | 5 | 14 | 6 | 10 | 12 | 12 | 12 | 12 |  | 50 Ohms | TOP=L2:L3=L2/L4:L6=L5/L7:BOTTOM=L7 |
| LBI_ADDR_8 | OTHERS | BUS | 6 | 5 | 5 | 10 | 5 | 14 | 6 | 10 | 12 | 12 | 12 | 12 |  | 50 Ohms | TOP=L2:L3=L2/L4:L6=L5/L7:BOTTOM=L7 |
| LBI_ADDR_8 | OTHERS | BUS | 7 | 5 | 5 | 10 | 5 | 14 | 6 | 10 | 12 | 12 | 12 | 12 |  | 50 Ohms | TOP=L2:L3=L2/L4:L6=L5/L7:BOTTOM=L7 |
| LBI_ADDR_8 | OTHERS | BUS | 8 | 4.75 | 5 | 10 | 5 | 14 | 6 | 9.5 | 12 | 12 | 12 | 12 |  | 50 Ohms | TOP=L2:L3=L2/L4:L6=L5/L7:BOTTOM=L7 |
| LBI_ADDR_9 | OTHERS | BUS | 1 | 4.75 | 5 | 10 | 5 | 14 | 6 | 9.5 | 12 | 12 | 12 | 12 |  | 50 Ohms | TOP=L2:L3=L2/L4:L6=L5/L7:BOTTOM=L7 |
| LBI_ADDR_9 | OTHERS | BUS | 2 | 5 | 5 | 10 | 5 | 14 | 6 | 10 | 12 | 12 | 12 | 12 |  | 50 Ohms | TOP=L2:L3=L2/L4:L6=L5/L7:BOTTOM=L7 |
| LBI_ADDR_9 | OTHERS | BUS | 3 | 5 | 5 | 10 | 5 | 14 | 6 | 10 | 12 | 12 | 12 | 12 |  | 50 Ohms | TOP=L2:L3=L2/L4:L6=L5/L7:BOTTOM=L7 |
| LBI_ADDR_9 | OTHERS | BUS | 4 | 5 | 5 | 10 | 5 | 14 | 6 | 10 | 12 | 12 | 12 | 12 |  | 50 Ohms | TOP=L2:L3=L2/L4:L6=L5/L7:BOTTOM=L7 |
| LBI_ADDR_9 | OTHERS | BUS | 5 | 5 | 5 | 10 | 5 | 14 | 6 | 10 | 12 | 12 | 12 | 12 |  | 50 Ohms | TOP=L2:L3=L2/L4:L6=L5/L7:BOTTOM=L7 |
| LBI_ADDR_9 | OTHERS | BUS | 6 | 5 | 5 | 10 | 5 | 14 | 6 | 10 | 12 | 12 | 12 | 12 |  | 50 Ohms | TOP=L2:L3=L2/L4:L6=L5/L7:BOTTOM=L7 |
| LBI_ADDR_9 | OTHERS | BUS | 7 | 5 | 5 | 10 | 5 | 14 | 6 | 10 | 12 | 12 | 12 | 12 |  | 50 Ohms | TOP=L2:L3=L2/L4:L6=L5/L7:BOTTOM=L7 |
| LBI_ADDR_9 | OTHERS | BUS | 8 | 4.75 | 5 | 10 | 5 | 14 | 6 | 9.5 | 12 | 12 | 12 | 12 |  | 50 Ohms | TOP=L2:L3=L2/L4:L6=L5/L7:BOTTOM=L7 |
| LBI_BYTEN# | OTHERS | BUS | 1 | 4.75 | 5 | 10 | 5 | 14 | 6 | 9.5 | 12 | 12 | 12 | 12 |  | 50 Ohms | TOP=L2:L3=L2/L4:L6=L5/L7:BOTTOM=L7 |
| LBI_BYTEN# | OTHERS | BUS | 2 | 5 | 5 | 10 | 5 | 14 | 6 | 10 | 12 | 12 | 12 | 12 |  | 50 Ohms | TOP=L2:L3=L2/L4:L6=L5/L7:BOTTOM=L7 |
| LBI_BYTEN# | OTHERS | BUS | 3 | 5 | 5 | 10 | 5 | 14 | 6 | 10 | 12 | 12 | 12 | 12 |  | 50 Ohms | TOP=L2:L3=L2/L4:L6=L5/L7:BOTTOM=L7 |
| LBI_BYTEN# | OTHERS | BUS | 4 | 5 | 5 | 10 | 5 | 14 | 6 | 10 | 12 | 12 | 12 | 12 |  | 50 Ohms | TOP=L2:L3=L2/L4:L6=L5/L7:BOTTOM=L7 |
| LBI_BYTEN# | OTHERS | BUS | 5 | 5 | 5 | 10 | 5 | 14 | 6 | 10 | 12 | 12 | 12 | 12 |  | 50 Ohms | TOP=L2:L3=L2/L4:L6=L5/L7:BOTTOM=L7 |
| LBI_BYTEN# | OTHERS | BUS | 6 | 5 | 5 | 10 | 5 | 14 | 6 | 10 | 12 | 12 | 12 | 12 |  | 50 Ohms | TOP=L2:L3=L2/L4:L6=L5/L7:BOTTOM=L7 |
| LBI_BYTEN# | OTHERS | BUS | 7 | 5 | 5 | 10 | 5 | 14 | 6 | 10 | 12 | 12 | 12 | 12 |  | 50 Ohms | TOP=L2:L3=L2/L4:L6=L5/L7:BOTTOM=L7 |
| LBI_BYTEN# | OTHERS | BUS | 8 | 4.75 | 5 | 10 | 5 | 14 | 6 | 9.5 | 12 | 12 | 12 | 12 |  | 50 Ohms | TOP=L2:L3=L2/L4:L6=L5/L7:BOTTOM=L7 |
| LBI_CE#0 | OTHERS | BUS | 1 | 4.75 | 5 | 10 | 5 | 14 | 6 | 9.5 | 12 | 12 | 12 | 12 |  | 50 Ohms | TOP=L2:L3=L2/L4:L6=L5/L7:BOTTOM=L7 |
| LBI_CE#0 | OTHERS | BUS | 2 | 5 | 5 | 10 | 5 | 14 | 6 | 10 | 12 | 12 | 12 | 12 |  | 50 Ohms | TOP=L2:L3=L2/L4:L6=L5/L7:BOTTOM=L7 |
| LBI_CE#0 | OTHERS | BUS | 3 | 5 | 5 | 10 | 5 | 14 | 6 | 10 | 12 | 12 | 12 | 12 |  | 50 Ohms | TOP=L2:L3=L2/L4:L6=L5/L7:BOTTOM=L7 |
| LBI_CE#0 | OTHERS | BUS | 4 | 5 | 5 | 10 | 5 | 14 | 6 | 10 | 12 | 12 | 12 | 12 |  | 50 Ohms | TOP=L2:L3=L2/L4:L6=L5/L7:BOTTOM=L7 |
| LBI_CE#0 | OTHERS | BUS | 5 | 5 | 5 | 10 | 5 | 14 | 6 | 10 | 12 | 12 | 12 | 12 |  | 50 Ohms | TOP=L2:L3=L2/L4:L6=L5/L7:BOTTOM=L7 |
| LBI_CE#0 | OTHERS | BUS | 6 | 5 | 5 | 10 | 5 | 14 | 6 | 10 | 12 | 12 | 12 | 12 |  | 50 Ohms | TOP=L2:L3=L2/L4:L6=L5/L7:BOTTOM=L7 |
| LBI_CE#0 | OTHERS | BUS | 7 | 5 | 5 | 10 | 5 | 14 | 6 | 10 | 12 | 12 | 12 | 12 |  | 50 Ohms | TOP=L2:L3=L2/L4:L6=L5/L7:BOTTOM=L7 |
| LBI_CE#0 | OTHERS | BUS | 8 | 4.75 | 5 | 10 | 5 | 14 | 6 | 9.5 | 12 | 12 | 12 | 12 |  | 50 Ohms | TOP=L2:L3=L2/L4:L6=L5/L7:BOTTOM=L7 |
| LBI_CE#2 | OTHERS | BUS | 1 | 4.75 | 5 | 10 | 5 | 14 | 6 | 9.5 | 12 | 12 | 12 | 12 |  | 50 Ohms | TOP=L2:L3=L2/L4:L6=L5/L7:BOTTOM=L7 |
| LBI_CE#2 | OTHERS | BUS | 2 | 5 | 5 | 10 | 5 | 14 | 6 | 10 | 12 | 12 | 12 | 12 |  | 50 Ohms | TOP=L2:L3=L2/L4:L6=L5/L7:BOTTOM=L7 |
| LBI_CE#2 | OTHERS | BUS | 3 | 5 | 5 | 10 | 5 | 14 | 6 | 10 | 12 | 12 | 12 | 12 |  | 50 Ohms | TOP=L2:L3=L2/L4:L6=L5/L7:BOTTOM=L7 |
| LBI_CE#2 | OTHERS | BUS | 4 | 5 | 5 | 10 | 5 | 14 | 6 | 10 | 12 | 12 | 12 | 12 |  | 50 Ohms | TOP=L2:L3=L2/L4:L6=L5/L7:BOTTOM=L7 |
| LBI_CE#2 | OTHERS | BUS | 5 | 5 | 5 | 10 | 5 | 14 | 6 | 10 | 12 | 12 | 12 | 12 |  | 50 Ohms | TOP=L2:L3=L2/L4:L6=L5/L7:BOTTOM=L7 |
| LBI_CE#2 | OTHERS | BUS | 6 | 5 | 5 | 10 | 5 | 14 | 6 | 10 | 12 | 12 | 12 | 12 |  | 50 Ohms | TOP=L2:L3=L2/L4:L6=L5/L7:BOTTOM=L7 |
| LBI_CE#2 | OTHERS | BUS | 7 | 5 | 5 | 10 | 5 | 14 | 6 | 10 | 12 | 12 | 12 | 12 |  | 50 Ohms | TOP=L2:L3=L2/L4:L6=L5/L7:BOTTOM=L7 |
| LBI_CE#2 | OTHERS | BUS | 8 | 4.75 | 5 | 10 | 5 | 14 | 6 | 9.5 | 12 | 12 | 12 | 12 |  | 50 Ohms | TOP=L2:L3=L2/L4:L6=L5/L7:BOTTOM=L7 |
| LBI_CE#3 | OTHERS | BUS | 1 | 4.75 | 5 | 10 | 5 | 14 | 6 | 9.5 | 12 | 12 | 12 | 12 |  | 50 Ohms | TOP=L2:L3=L2/L4:L6=L5/L7:BOTTOM=L7 |
| LBI_CE#3 | OTHERS | BUS | 2 | 5 | 5 | 10 | 5 | 14 | 6 | 10 | 12 | 12 | 12 | 12 |  | 50 Ohms | TOP=L2:L3=L2/L4:L6=L5/L7:BOTTOM=L7 |
| LBI_CE#3 | OTHERS | BUS | 3 | 5 | 5 | 10 | 5 | 14 | 6 | 10 | 12 | 12 | 12 | 12 |  | 50 Ohms | TOP=L2:L3=L2/L4:L6=L5/L7:BOTTOM=L7 |
| LBI_CE#3 | OTHERS | BUS | 4 | 5 | 5 | 10 | 5 | 14 | 6 | 10 | 12 | 12 | 12 | 12 |  | 50 Ohms | TOP=L2:L3=L2/L4:L6=L5/L7:BOTTOM=L7 |
| LBI_CE#3 | OTHERS | BUS | 5 | 5 | 5 | 10 | 5 | 14 | 6 | 10 | 12 | 12 | 12 | 12 |  | 50 Ohms | TOP=L2:L3=L2/L4:L6=L5/L7:BOTTOM=L7 |
| LBI_CE#3 | OTHERS | BUS | 6 | 5 | 5 | 10 | 5 | 14 | 6 | 10 | 12 | 12 | 12 | 12 |  | 50 Ohms | TOP=L2:L3=L2/L4:L6=L5/L7:BOTTOM=L7 |
| LBI_CE#3 | OTHERS | BUS | 7 | 5 | 5 | 10 | 5 | 14 | 6 | 10 | 12 | 12 | 12 | 12 |  | 50 Ohms | TOP=L2:L3=L2/L4:L6=L5/L7:BOTTOM=L7 |
| LBI_CE#3 | OTHERS | BUS | 8 | 4.75 | 5 | 10 | 5 | 14 | 6 | 9.5 | 12 | 12 | 12 | 12 |  | 50 Ohms | TOP=L2:L3=L2/L4:L6=L5/L7:BOTTOM=L7 |
| LBI_DATA_0 | OTHERS | BUS | 1 | 4.75 | 5 | 10 | 5 | 14 | 6 | 9.5 | 12 | 12 | 12 | 12 |  | 50 Ohms | TOP=L2:L3=L2/L4:L6=L5/L7:BOTTOM=L7 |
| LBI_DATA_0 | OTHERS | BUS | 2 | 5 | 5 | 10 | 5 | 14 | 6 | 10 | 12 | 12 | 12 | 12 |  | 50 Ohms | TOP=L2:L3=L2/L4:L6=L5/L7:BOTTOM=L7 |
| LBI_DATA_0 | OTHERS | BUS | 3 | 5 | 5 | 10 | 5 | 14 | 6 | 10 | 12 | 12 | 12 | 12 |  | 50 Ohms | TOP=L2:L3=L2/L4:L6=L5/L7:BOTTOM=L7 |
| LBI_DATA_0 | OTHERS | BUS | 4 | 5 | 5 | 10 | 5 | 14 | 6 | 10 | 12 | 12 | 12 | 12 |  | 50 Ohms | TOP=L2:L3=L2/L4:L6=L5/L7:BOTTOM=L7 |
| LBI_DATA_0 | OTHERS | BUS | 5 | 5 | 5 | 10 | 5 | 14 | 6 | 10 | 12 | 12 | 12 | 12 |  | 50 Ohms | TOP=L2:L3=L2/L4:L6=L5/L7:BOTTOM=L7 |
| LBI_DATA_0 | OTHERS | BUS | 6 | 5 | 5 | 10 | 5 | 14 | 6 | 10 | 12 | 12 | 12 | 12 |  | 50 Ohms | TOP=L2:L3=L2/L4:L6=L5/L7:BOTTOM=L7 |
| LBI_DATA_0 | OTHERS | BUS | 7 | 5 | 5 | 10 | 5 | 14 | 6 | 10 | 12 | 12 | 12 | 12 |  | 50 Ohms | TOP=L2:L3=L2/L4:L6=L5/L7:BOTTOM=L7 |
| LBI_DATA_0 | OTHERS | BUS | 8 | 4.75 | 5 | 10 | 5 | 14 | 6 | 9.5 | 12 | 12 | 12 | 12 |  | 50 Ohms | TOP=L2:L3=L2/L4:L6=L5/L7:BOTTOM=L7 |
| LBI_DATA_1 | OTHERS | BUS | 1 | 4.75 | 5 | 10 | 5 | 14 | 6 | 9.5 | 12 | 12 | 12 | 12 |  | 50 Ohms | TOP=L2:L3=L2/L4:L6=L5/L7:BOTTOM=L7 |
| LBI_DATA_1 | OTHERS | BUS | 2 | 5 | 5 | 10 | 5 | 14 | 6 | 10 | 12 | 12 | 12 | 12 |  | 50 Ohms | TOP=L2:L3=L2/L4:L6=L5/L7:BOTTOM=L7 |
| LBI_DATA_1 | OTHERS | BUS | 3 | 5 | 5 | 10 | 5 | 14 | 6 | 10 | 12 | 12 | 12 | 12 |  | 50 Ohms | TOP=L2:L3=L2/L4:L6=L5/L7:BOTTOM=L7 |
| LBI_DATA_1 | OTHERS | BUS | 4 | 5 | 5 | 10 | 5 | 14 | 6 | 10 | 12 | 12 | 12 | 12 |  | 50 Ohms | TOP=L2:L3=L2/L4:L6=L5/L7:BOTTOM=L7 |
| LBI_DATA_1 | OTHERS | BUS | 5 | 5 | 5 | 10 | 5 | 14 | 6 | 10 | 12 | 12 | 12 | 12 |  | 50 Ohms | TOP=L2:L3=L2/L4:L6=L5/L7:BOTTOM=L7 |
| LBI_DATA_1 | OTHERS | BUS | 6 | 5 | 5 | 10 | 5 | 14 | 6 | 10 | 12 | 12 | 12 | 12 |  | 50 Ohms | TOP=L2:L3=L2/L4:L6=L5/L7:BOTTOM=L7 |
| LBI_DATA_1 | OTHERS | BUS | 7 | 5 | 5 | 10 | 5 | 14 | 6 | 10 | 12 | 12 | 12 | 12 |  | 50 Ohms | TOP=L2:L3=L2/L4:L6=L5/L7:BOTTOM=L7 |
| LBI_DATA_1 | OTHERS | BUS | 8 | 4.75 | 5 | 10 | 5 | 14 | 6 | 9.5 | 12 | 12 | 12 | 12 |  | 50 Ohms | TOP=L2:L3=L2/L4:L6=L5/L7:BOTTOM=L7 |
| LBI_DATA_2 | OTHERS | BUS | 1 | 4.75 | 5 | 10 | 5 | 14 | 6 | 9.5 | 12 | 12 | 12 | 12 |  | 50 Ohms | TOP=L2:L3=L2/L4:L6=L5/L7:BOTTOM=L7 |
| LBI_DATA_2 | OTHERS | BUS | 2 | 5 | 5 | 10 | 5 | 14 | 6 | 10 | 12 | 12 | 12 | 12 |  | 50 Ohms | TOP=L2:L3=L2/L4:L6=L5/L7:BOTTOM=L7 |
| LBI_DATA_2 | OTHERS | BUS | 3 | 5 | 5 | 10 | 5 | 14 | 6 | 10 | 12 | 12 | 12 | 12 |  | 50 Ohms | TOP=L2:L3=L2/L4:L6=L5/L7:BOTTOM=L7 |
| LBI_DATA_2 | OTHERS | BUS | 4 | 5 | 5 | 10 | 5 | 14 | 6 | 10 | 12 | 12 | 12 | 12 |  | 50 Ohms | TOP=L2:L3=L2/L4:L6=L5/L7:BOTTOM=L7 |
| LBI_DATA_2 | OTHERS | BUS | 5 | 5 | 5 | 10 | 5 | 14 | 6 | 10 | 12 | 12 | 12 | 12 |  | 50 Ohms | TOP=L2:L3=L2/L4:L6=L5/L7:BOTTOM=L7 |
| LBI_DATA_2 | OTHERS | BUS | 6 | 5 | 5 | 10 | 5 | 14 | 6 | 10 | 12 | 12 | 12 | 12 |  | 50 Ohms | TOP=L2:L3=L2/L4:L6=L5/L7:BOTTOM=L7 |
| LBI_DATA_2 | OTHERS | BUS | 7 | 5 | 5 | 10 | 5 | 14 | 6 | 10 | 12 | 12 | 12 | 12 |  | 50 Ohms | TOP=L2:L3=L2/L4:L6=L5/L7:BOTTOM=L7 |
| LBI_DATA_2 | OTHERS | BUS | 8 | 4.75 | 5 | 10 | 5 | 14 | 6 | 9.5 | 12 | 12 | 12 | 12 |  | 50 Ohms | TOP=L2:L3=L2/L4:L6=L5/L7:BOTTOM=L7 |
| LBI_DATA_3 | OTHERS | BUS | 1 | 4.75 | 5 | 10 | 5 | 14 | 6 | 9.5 | 12 | 12 | 12 | 12 |  | 50 Ohms | TOP=L2:L3=L2/L4:L6=L5/L7:BOTTOM=L7 |
| LBI_DATA_3 | OTHERS | BUS | 2 | 5 | 5 | 10 | 5 | 14 | 6 | 10 | 12 | 12 | 12 | 12 |  | 50 Ohms | TOP=L2:L3=L2/L4:L6=L5/L7:BOTTOM=L7 |
| LBI_DATA_3 | OTHERS | BUS | 3 | 5 | 5 | 10 | 5 | 14 | 6 | 10 | 12 | 12 | 12 | 12 |  | 50 Ohms | TOP=L2:L3=L2/L4:L6=L5/L7:BOTTOM=L7 |
| LBI_DATA_3 | OTHERS | BUS | 4 | 5 | 5 | 10 | 5 | 14 | 6 | 10 | 12 | 12 | 12 | 12 |  | 50 Ohms | TOP=L2:L3=L2/L4:L6=L5/L7:BOTTOM=L7 |
| LBI_DATA_3 | OTHERS | BUS | 5 | 5 | 5 | 10 | 5 | 14 | 6 | 10 | 12 | 12 | 12 | 12 |  | 50 Ohms | TOP=L2:L3=L2/L4:L6=L5/L7:BOTTOM=L7 |
| LBI_DATA_3 | OTHERS | BUS | 6 | 5 | 5 | 10 | 5 | 14 | 6 | 10 | 12 | 12 | 12 | 12 |  | 50 Ohms | TOP=L2:L3=L2/L4:L6=L5/L7:BOTTOM=L7 |
| LBI_DATA_3 | OTHERS | BUS | 7 | 5 | 5 | 10 | 5 | 14 | 6 | 10 | 12 | 12 | 12 | 12 |  | 50 Ohms | TOP=L2:L3=L2/L4:L6=L5/L7:BOTTOM=L7 |
| LBI_DATA_3 | OTHERS | BUS | 8 | 4.75 | 5 | 10 | 5 | 14 | 6 | 9.5 | 12 | 12 | 12 | 12 |  | 50 Ohms | TOP=L2:L3=L2/L4:L6=L5/L7:BOTTOM=L7 |
| LBI_DATA_4 | OTHERS | BUS | 1 | 4.75 | 5 | 10 | 5 | 14 | 6 | 9.5 | 12 | 12 | 12 | 12 |  | 50 Ohms | TOP=L2:L3=L2/L4:L6=L5/L7:BOTTOM=L7 |
| LBI_DATA_4 | OTHERS | BUS | 2 | 5 | 5 | 10 | 5 | 14 | 6 | 10 | 12 | 12 | 12 | 12 |  | 50 Ohms | TOP=L2:L3=L2/L4:L6=L5/L7:BOTTOM=L7 |
| LBI_DATA_4 | OTHERS | BUS | 3 | 5 | 5 | 10 | 5 | 14 | 6 | 10 | 12 | 12 | 12 | 12 |  | 50 Ohms | TOP=L2:L3=L2/L4:L6=L5/L7:BOTTOM=L7 |
| LBI_DATA_4 | OTHERS | BUS | 4 | 5 | 5 | 10 | 5 | 14 | 6 | 10 | 12 | 12 | 12 | 12 |  | 50 Ohms | TOP=L2:L3=L2/L4:L6=L5/L7:BOTTOM=L7 |
| LBI_DATA_4 | OTHERS | BUS | 5 | 5 | 5 | 10 | 5 | 14 | 6 | 10 | 12 | 12 | 12 | 12 |  | 50 Ohms | TOP=L2:L3=L2/L4:L6=L5/L7:BOTTOM=L7 |
| LBI_DATA_4 | OTHERS | BUS | 6 | 5 | 5 | 10 | 5 | 14 | 6 | 10 | 12 | 12 | 12 | 12 |  | 50 Ohms | TOP=L2:L3=L2/L4:L6=L5/L7:BOTTOM=L7 |
| LBI_DATA_4 | OTHERS | BUS | 7 | 5 | 5 | 10 | 5 | 14 | 6 | 10 | 12 | 12 | 12 | 12 |  | 50 Ohms | TOP=L2:L3=L2/L4:L6=L5/L7:BOTTOM=L7 |
| LBI_DATA_4 | OTHERS | BUS | 8 | 4.75 | 5 | 10 | 5 | 14 | 6 | 9.5 | 12 | 12 | 12 | 12 |  | 50 Ohms | TOP=L2:L3=L2/L4:L6=L5/L7:BOTTOM=L7 |
| LBI_DATA_5 | OTHERS | BUS | 1 | 4.75 | 5 | 10 | 5 | 14 | 6 | 9.5 | 12 | 12 | 12 | 12 |  | 50 Ohms | TOP=L2:L3=L2/L4:L6=L5/L7:BOTTOM=L7 |
| LBI_DATA_5 | OTHERS | BUS | 2 | 5 | 5 | 10 | 5 | 14 | 6 | 10 | 12 | 12 | 12 | 12 |  | 50 Ohms | TOP=L2:L3=L2/L4:L6=L5/L7:BOTTOM=L7 |
| LBI_DATA_5 | OTHERS | BUS | 3 | 5 | 5 | 10 | 5 | 14 | 6 | 10 | 12 | 12 | 12 | 12 |  | 50 Ohms | TOP=L2:L3=L2/L4:L6=L5/L7:BOTTOM=L7 |
| LBI_DATA_5 | OTHERS | BUS | 4 | 5 | 5 | 10 | 5 | 14 | 6 | 10 | 12 | 12 | 12 | 12 |  | 50 Ohms | TOP=L2:L3=L2/L4:L6=L5/L7:BOTTOM=L7 |
| LBI_DATA_5 | OTHERS | BUS | 5 | 5 | 5 | 10 | 5 | 14 | 6 | 10 | 12 | 12 | 12 | 12 |  | 50 Ohms | TOP=L2:L3=L2/L4:L6=L5/L7:BOTTOM=L7 |
| LBI_DATA_5 | OTHERS | BUS | 6 | 5 | 5 | 10 | 5 | 14 | 6 | 10 | 12 | 12 | 12 | 12 |  | 50 Ohms | TOP=L2:L3=L2/L4:L6=L5/L7:BOTTOM=L7 |
| LBI_DATA_5 | OTHERS | BUS | 7 | 5 | 5 | 10 | 5 | 14 | 6 | 10 | 12 | 12 | 12 | 12 |  | 50 Ohms | TOP=L2:L3=L2/L4:L6=L5/L7:BOTTOM=L7 |
| LBI_DATA_5 | OTHERS | BUS | 8 | 4.75 | 5 | 10 | 5 | 14 | 6 | 9.5 | 12 | 12 | 12 | 12 |  | 50 Ohms | TOP=L2:L3=L2/L4:L6=L5/L7:BOTTOM=L7 |
| LBI_DATA_6 | OTHERS | BUS | 1 | 4.75 | 5 | 10 | 5 | 14 | 6 | 9.5 | 12 | 12 | 12 | 12 |  | 50 Ohms | TOP=L2:L3=L2/L4:L6=L5/L7:BOTTOM=L7 |
| LBI_DATA_6 | OTHERS | BUS | 2 | 5 | 5 | 10 | 5 | 14 | 6 | 10 | 12 | 12 | 12 | 12 |  | 50 Ohms | TOP=L2:L3=L2/L4:L6=L5/L7:BOTTOM=L7 |
| LBI_DATA_6 | OTHERS | BUS | 3 | 5 | 5 | 10 | 5 | 14 | 6 | 10 | 12 | 12 | 12 | 12 |  | 50 Ohms | TOP=L2:L3=L2/L4:L6=L5/L7:BOTTOM=L7 |
| LBI_DATA_6 | OTHERS | BUS | 4 | 5 | 5 | 10 | 5 | 14 | 6 | 10 | 12 | 12 | 12 | 12 |  | 50 Ohms | TOP=L2:L3=L2/L4:L6=L5/L7:BOTTOM=L7 |
| LBI_DATA_6 | OTHERS | BUS | 5 | 5 | 5 | 10 | 5 | 14 | 6 | 10 | 12 | 12 | 12 | 12 |  | 50 Ohms | TOP=L2:L3=L2/L4:L6=L5/L7:BOTTOM=L7 |
| LBI_DATA_6 | OTHERS | BUS | 6 | 5 | 5 | 10 | 5 | 14 | 6 | 10 | 12 | 12 | 12 | 12 |  | 50 Ohms | TOP=L2:L3=L2/L4:L6=L5/L7:BOTTOM=L7 |
| LBI_DATA_6 | OTHERS | BUS | 7 | 5 | 5 | 10 | 5 | 14 | 6 | 10 | 12 | 12 | 12 | 12 |  | 50 Ohms | TOP=L2:L3=L2/L4:L6=L5/L7:BOTTOM=L7 |
| LBI_DATA_6 | OTHERS | BUS | 8 | 4.75 | 5 | 10 | 5 | 14 | 6 | 9.5 | 12 | 12 | 12 | 12 |  | 50 Ohms | TOP=L2:L3=L2/L4:L6=L5/L7:BOTTOM=L7 |
| LBI_DATA_7 | OTHERS | BUS | 1 | 4.75 | 5 | 10 | 5 | 14 | 6 | 9.5 | 12 | 12 | 12 | 12 |  | 50 Ohms | TOP=L2:L3=L2/L4:L6=L5/L7:BOTTOM=L7 |
| LBI_DATA_7 | OTHERS | BUS | 2 | 5 | 5 | 10 | 5 | 14 | 6 | 10 | 12 | 12 | 12 | 12 |  | 50 Ohms | TOP=L2:L3=L2/L4:L6=L5/L7:BOTTOM=L7 |
| LBI_DATA_7 | OTHERS | BUS | 3 | 5 | 5 | 10 | 5 | 14 | 6 | 10 | 12 | 12 | 12 | 12 |  | 50 Ohms | TOP=L2:L3=L2/L4:L6=L5/L7:BOTTOM=L7 |
| LBI_DATA_7 | OTHERS | BUS | 4 | 5 | 5 | 10 | 5 | 14 | 6 | 10 | 12 | 12 | 12 | 12 |  | 50 Ohms | TOP=L2:L3=L2/L4:L6=L5/L7:BOTTOM=L7 |
| LBI_DATA_7 | OTHERS | BUS | 5 | 5 | 5 | 10 | 5 | 14 | 6 | 10 | 12 | 12 | 12 | 12 |  | 50 Ohms | TOP=L2:L3=L2/L4:L6=L5/L7:BOTTOM=L7 |
| LBI_DATA_7 | OTHERS | BUS | 6 | 5 | 5 | 10 | 5 | 14 | 6 | 10 | 12 | 12 | 12 | 12 |  | 50 Ohms | TOP=L2:L3=L2/L4:L6=L5/L7:BOTTOM=L7 |
| LBI_DATA_7 | OTHERS | BUS | 7 | 5 | 5 | 10 | 5 | 14 | 6 | 10 | 12 | 12 | 12 | 12 |  | 50 Ohms | TOP=L2:L3=L2/L4:L6=L5/L7:BOTTOM=L7 |
| LBI_DATA_7 | OTHERS | BUS | 8 | 4.75 | 5 | 10 | 5 | 14 | 6 | 9.5 | 12 | 12 | 12 | 12 |  | 50 Ohms | TOP=L2:L3=L2/L4:L6=L5/L7:BOTTOM=L7 |
| LBI_DATA_8 | OTHERS | BUS | 1 | 4.75 | 5 | 10 | 5 | 14 | 6 | 9.5 | 12 | 12 | 12 | 12 |  | 50 Ohms | TOP=L2:L3=L2/L4:L6=L5/L7:BOTTOM=L7 |
| LBI_DATA_8 | OTHERS | BUS | 2 | 5 | 5 | 10 | 5 | 14 | 6 | 10 | 12 | 12 | 12 | 12 |  | 50 Ohms | TOP=L2:L3=L2/L4:L6=L5/L7:BOTTOM=L7 |
| LBI_DATA_8 | OTHERS | BUS | 3 | 5 | 5 | 10 | 5 | 14 | 6 | 10 | 12 | 12 | 12 | 12 |  | 50 Ohms | TOP=L2:L3=L2/L4:L6=L5/L7:BOTTOM=L7 |
| LBI_DATA_8 | OTHERS | BUS | 4 | 5 | 5 | 10 | 5 | 14 | 6 | 10 | 12 | 12 | 12 | 12 |  | 50 Ohms | TOP=L2:L3=L2/L4:L6=L5/L7:BOTTOM=L7 |
| LBI_DATA_8 | OTHERS | BUS | 5 | 5 | 5 | 10 | 5 | 14 | 6 | 10 | 12 | 12 | 12 | 12 |  | 50 Ohms | TOP=L2:L3=L2/L4:L6=L5/L7:BOTTOM=L7 |
| LBI_DATA_8 | OTHERS | BUS | 6 | 5 | 5 | 10 | 5 | 14 | 6 | 10 | 12 | 12 | 12 | 12 |  | 50 Ohms | TOP=L2:L3=L2/L4:L6=L5/L7:BOTTOM=L7 |
| LBI_DATA_8 | OTHERS | BUS | 7 | 5 | 5 | 10 | 5 | 14 | 6 | 10 | 12 | 12 | 12 | 12 |  | 50 Ohms | TOP=L2:L3=L2/L4:L6=L5/L7:BOTTOM=L7 |
| LBI_DATA_8 | OTHERS | BUS | 8 | 4.75 | 5 | 10 | 5 | 14 | 6 | 9.5 | 12 | 12 | 12 | 12 |  | 50 Ohms | TOP=L2:L3=L2/L4:L6=L5/L7:BOTTOM=L7 |
| LBI_DATA_9 | OTHERS | BUS | 1 | 4.75 | 5 | 10 | 5 | 14 | 6 | 9.5 | 12 | 12 | 12 | 12 |  | 50 Ohms | TOP=L2:L3=L2/L4:L6=L5/L7:BOTTOM=L7 |
| LBI_DATA_9 | OTHERS | BUS | 2 | 5 | 5 | 10 | 5 | 14 | 6 | 10 | 12 | 12 | 12 | 12 |  | 50 Ohms | TOP=L2:L3=L2/L4:L6=L5/L7:BOTTOM=L7 |
| LBI_DATA_9 | OTHERS | BUS | 3 | 5 | 5 | 10 | 5 | 14 | 6 | 10 | 12 | 12 | 12 | 12 |  | 50 Ohms | TOP=L2:L3=L2/L4:L6=L5/L7:BOTTOM=L7 |
| LBI_DATA_9 | OTHERS | BUS | 4 | 5 | 5 | 10 | 5 | 14 | 6 | 10 | 12 | 12 | 12 | 12 |  | 50 Ohms | TOP=L2:L3=L2/L4:L6=L5/L7:BOTTOM=L7 |
| LBI_DATA_9 | OTHERS | BUS | 5 | 5 | 5 | 10 | 5 | 14 | 6 | 10 | 12 | 12 | 12 | 12 |  | 50 Ohms | TOP=L2:L3=L2/L4:L6=L5/L7:BOTTOM=L7 |
| LBI_DATA_9 | OTHERS | BUS | 6 | 5 | 5 | 10 | 5 | 14 | 6 | 10 | 12 | 12 | 12 | 12 |  | 50 Ohms | TOP=L2:L3=L2/L4:L6=L5/L7:BOTTOM=L7 |
| LBI_DATA_9 | OTHERS | BUS | 7 | 5 | 5 | 10 | 5 | 14 | 6 | 10 | 12 | 12 | 12 | 12 |  | 50 Ohms | TOP=L2:L3=L2/L4:L6=L5/L7:BOTTOM=L7 |
| LBI_DATA_9 | OTHERS | BUS | 8 | 4.75 | 5 | 10 | 5 | 14 | 6 | 9.5 | 12 | 12 | 12 | 12 |  | 50 Ohms | TOP=L2:L3=L2/L4:L6=L5/L7:BOTTOM=L7 |
| LBI_DATA10 | OTHERS | BUS | 1 | 4.75 | 5 | 10 | 5 | 14 | 6 | 9.5 | 12 | 12 | 12 | 12 |  | 50 Ohms | TOP=L2:L3=L2/L4:L6=L5/L7:BOTTOM=L7 |
| LBI_DATA10 | OTHERS | BUS | 2 | 5 | 5 | 10 | 5 | 14 | 6 | 10 | 12 | 12 | 12 | 12 |  | 50 Ohms | TOP=L2:L3=L2/L4:L6=L5/L7:BOTTOM=L7 |
| LBI_DATA10 | OTHERS | BUS | 3 | 5 | 5 | 10 | 5 | 14 | 6 | 10 | 12 | 12 | 12 | 12 |  | 50 Ohms | TOP=L2:L3=L2/L4:L6=L5/L7:BOTTOM=L7 |
| LBI_DATA10 | OTHERS | BUS | 4 | 5 | 5 | 10 | 5 | 14 | 6 | 10 | 12 | 12 | 12 | 12 |  | 50 Ohms | TOP=L2:L3=L2/L4:L6=L5/L7:BOTTOM=L7 |
| LBI_DATA10 | OTHERS | BUS | 5 | 5 | 5 | 10 | 5 | 14 | 6 | 10 | 12 | 12 | 12 | 12 |  | 50 Ohms | TOP=L2:L3=L2/L4:L6=L5/L7:BOTTOM=L7 |
| LBI_DATA10 | OTHERS | BUS | 6 | 5 | 5 | 10 | 5 | 14 | 6 | 10 | 12 | 12 | 12 | 12 |  | 50 Ohms | TOP=L2:L3=L2/L4:L6=L5/L7:BOTTOM=L7 |
| LBI_DATA10 | OTHERS | BUS | 7 | 5 | 5 | 10 | 5 | 14 | 6 | 10 | 12 | 12 | 12 | 12 |  | 50 Ohms | TOP=L2:L3=L2/L4:L6=L5/L7:BOTTOM=L7 |
| LBI_DATA10 | OTHERS | BUS | 8 | 4.75 | 5 | 10 | 5 | 14 | 6 | 9.5 | 12 | 12 | 12 | 12 |  | 50 Ohms | TOP=L2:L3=L2/L4:L6=L5/L7:BOTTOM=L7 |
| LBI_DATA11_R | OTHERS | BUS | 1 | 4.75 | 5 | 10 | 5 | 14 | 6 | 9.5 | 12 | 12 | 12 | 12 |  | 50 Ohms | TOP=L2:L3=L2/L4:L6=L5/L7:BOTTOM=L7 |
| LBI_DATA11_R | OTHERS | BUS | 2 | 5 | 5 | 10 | 5 | 14 | 6 | 10 | 12 | 12 | 12 | 12 |  | 50 Ohms | TOP=L2:L3=L2/L4:L6=L5/L7:BOTTOM=L7 |
| LBI_DATA11_R | OTHERS | BUS | 3 | 5 | 5 | 10 | 5 | 14 | 6 | 10 | 12 | 12 | 12 | 12 |  | 50 Ohms | TOP=L2:L3=L2/L4:L6=L5/L7:BOTTOM=L7 |
| LBI_DATA11_R | OTHERS | BUS | 4 | 5 | 5 | 10 | 5 | 14 | 6 | 10 | 12 | 12 | 12 | 12 |  | 50 Ohms | TOP=L2:L3=L2/L4:L6=L5/L7:BOTTOM=L7 |
| LBI_DATA11_R | OTHERS | BUS | 5 | 5 | 5 | 10 | 5 | 14 | 6 | 10 | 12 | 12 | 12 | 12 |  | 50 Ohms | TOP=L2:L3=L2/L4:L6=L5/L7:BOTTOM=L7 |
| LBI_DATA11_R | OTHERS | BUS | 6 | 5 | 5 | 10 | 5 | 14 | 6 | 10 | 12 | 12 | 12 | 12 |  | 50 Ohms | TOP=L2:L3=L2/L4:L6=L5/L7:BOTTOM=L7 |
| LBI_DATA11_R | OTHERS | BUS | 7 | 5 | 5 | 10 | 5 | 14 | 6 | 10 | 12 | 12 | 12 | 12 |  | 50 Ohms | TOP=L2:L3=L2/L4:L6=L5/L7:BOTTOM=L7 |
| LBI_DATA11_R | OTHERS | BUS | 8 | 4.75 | 5 | 10 | 5 | 14 | 6 | 9.5 | 12 | 12 | 12 | 12 |  | 50 Ohms | TOP=L2:L3=L2/L4:L6=L5/L7:BOTTOM=L7 |
| LBI_DATA12_R | OTHERS | BUS | 1 | 4.75 | 5 | 10 | 5 | 14 | 6 | 9.5 | 12 | 12 | 12 | 12 |  | 50 Ohms | TOP=L2:L3=L2/L4:L6=L5/L7:BOTTOM=L7 |
| LBI_DATA12_R | OTHERS | BUS | 2 | 5 | 5 | 10 | 5 | 14 | 6 | 10 | 12 | 12 | 12 | 12 |  | 50 Ohms | TOP=L2:L3=L2/L4:L6=L5/L7:BOTTOM=L7 |
| LBI_DATA12_R | OTHERS | BUS | 3 | 5 | 5 | 10 | 5 | 14 | 6 | 10 | 12 | 12 | 12 | 12 |  | 50 Ohms | TOP=L2:L3=L2/L4:L6=L5/L7:BOTTOM=L7 |
| LBI_DATA12_R | OTHERS | BUS | 4 | 5 | 5 | 10 | 5 | 14 | 6 | 10 | 12 | 12 | 12 | 12 |  | 50 Ohms | TOP=L2:L3=L2/L4:L6=L5/L7:BOTTOM=L7 |
| LBI_DATA12_R | OTHERS | BUS | 5 | 5 | 5 | 10 | 5 | 14 | 6 | 10 | 12 | 12 | 12 | 12 |  | 50 Ohms | TOP=L2:L3=L2/L4:L6=L5/L7:BOTTOM=L7 |
| LBI_DATA12_R | OTHERS | BUS | 6 | 5 | 5 | 10 | 5 | 14 | 6 | 10 | 12 | 12 | 12 | 12 |  | 50 Ohms | TOP=L2:L3=L2/L4:L6=L5/L7:BOTTOM=L7 |
| LBI_DATA12_R | OTHERS | BUS | 7 | 5 | 5 | 10 | 5 | 14 | 6 | 10 | 12 | 12 | 12 | 12 |  | 50 Ohms | TOP=L2:L3=L2/L4:L6=L5/L7:BOTTOM=L7 |
| LBI_DATA12_R | OTHERS | BUS | 8 | 4.75 | 5 | 10 | 5 | 14 | 6 | 9.5 | 12 | 12 | 12 | 12 |  | 50 Ohms | TOP=L2:L3=L2/L4:L6=L5/L7:BOTTOM=L7 |
| LBI_DATA13_R | OTHERS | BUS | 1 | 4.75 | 5 | 10 | 5 | 14 | 6 | 9.5 | 12 | 12 | 12 | 12 |  | 50 Ohms | TOP=L2:L3=L2/L4:L6=L5/L7:BOTTOM=L7 |
| LBI_DATA13_R | OTHERS | BUS | 2 | 5 | 5 | 10 | 5 | 14 | 6 | 10 | 12 | 12 | 12 | 12 |  | 50 Ohms | TOP=L2:L3=L2/L4:L6=L5/L7:BOTTOM=L7 |
| LBI_DATA13_R | OTHERS | BUS | 3 | 5 | 5 | 10 | 5 | 14 | 6 | 10 | 12 | 12 | 12 | 12 |  | 50 Ohms | TOP=L2:L3=L2/L4:L6=L5/L7:BOTTOM=L7 |
| LBI_DATA13_R | OTHERS | BUS | 4 | 5 | 5 | 10 | 5 | 14 | 6 | 10 | 12 | 12 | 12 | 12 |  | 50 Ohms | TOP=L2:L3=L2/L4:L6=L5/L7:BOTTOM=L7 |
| LBI_DATA13_R | OTHERS | BUS | 5 | 5 | 5 | 10 | 5 | 14 | 6 | 10 | 12 | 12 | 12 | 12 |  | 50 Ohms | TOP=L2:L3=L2/L4:L6=L5/L7:BOTTOM=L7 |
| LBI_DATA13_R | OTHERS | BUS | 6 | 5 | 5 | 10 | 5 | 14 | 6 | 10 | 12 | 12 | 12 | 12 |  | 50 Ohms | TOP=L2:L3=L2/L4:L6=L5/L7:BOTTOM=L7 |
| LBI_DATA13_R | OTHERS | BUS | 7 | 5 | 5 | 10 | 5 | 14 | 6 | 10 | 12 | 12 | 12 | 12 |  | 50 Ohms | TOP=L2:L3=L2/L4:L6=L5/L7:BOTTOM=L7 |
| LBI_DATA13_R | OTHERS | BUS | 8 | 4.75 | 5 | 10 | 5 | 14 | 6 | 9.5 | 12 | 12 | 12 | 12 |  | 50 Ohms | TOP=L2:L3=L2/L4:L6=L5/L7:BOTTOM=L7 |
| LBI_DATA14_R | OTHERS | BUS | 1 | 4.75 | 5 | 10 | 5 | 14 | 6 | 9.5 | 12 | 12 | 12 | 12 |  | 50 Ohms | TOP=L2:L3=L2/L4:L6=L5/L7:BOTTOM=L7 |
| LBI_DATA14_R | OTHERS | BUS | 2 | 5 | 5 | 10 | 5 | 14 | 6 | 10 | 12 | 12 | 12 | 12 |  | 50 Ohms | TOP=L2:L3=L2/L4:L6=L5/L7:BOTTOM=L7 |
| LBI_DATA14_R | OTHERS | BUS | 3 | 5 | 5 | 10 | 5 | 14 | 6 | 10 | 12 | 12 | 12 | 12 |  | 50 Ohms | TOP=L2:L3=L2/L4:L6=L5/L7:BOTTOM=L7 |
| LBI_DATA14_R | OTHERS | BUS | 4 | 5 | 5 | 10 | 5 | 14 | 6 | 10 | 12 | 12 | 12 | 12 |  | 50 Ohms | TOP=L2:L3=L2/L4:L6=L5/L7:BOTTOM=L7 |
| LBI_DATA14_R | OTHERS | BUS | 5 | 5 | 5 | 10 | 5 | 14 | 6 | 10 | 12 | 12 | 12 | 12 |  | 50 Ohms | TOP=L2:L3=L2/L4:L6=L5/L7:BOTTOM=L7 |
| LBI_DATA14_R | OTHERS | BUS | 6 | 5 | 5 | 10 | 5 | 14 | 6 | 10 | 12 | 12 | 12 | 12 |  | 50 Ohms | TOP=L2:L3=L2/L4:L6=L5/L7:BOTTOM=L7 |
| LBI_DATA14_R | OTHERS | BUS | 7 | 5 | 5 | 10 | 5 | 14 | 6 | 10 | 12 | 12 | 12 | 12 |  | 50 Ohms | TOP=L2:L3=L2/L4:L6=L5/L7:BOTTOM=L7 |
| LBI_DATA14_R | OTHERS | BUS | 8 | 4.75 | 5 | 10 | 5 | 14 | 6 | 9.5 | 12 | 12 | 12 | 12 |  | 50 Ohms | TOP=L2:L3=L2/L4:L6=L5/L7:BOTTOM=L7 |
| LBI_DATA15 | OTHERS | BUS | 1 | 4.75 | 5 | 10 | 5 | 14 | 6 | 9.5 | 12 | 12 | 12 | 12 |  | 50 Ohms | TOP=L2:L3=L2/L4:L6=L5/L7:BOTTOM=L7 |
| LBI_DATA15 | OTHERS | BUS | 2 | 5 | 5 | 10 | 5 | 14 | 6 | 10 | 12 | 12 | 12 | 12 |  | 50 Ohms | TOP=L2:L3=L2/L4:L6=L5/L7:BOTTOM=L7 |
| LBI_DATA15 | OTHERS | BUS | 3 | 5 | 5 | 10 | 5 | 14 | 6 | 10 | 12 | 12 | 12 | 12 |  | 50 Ohms | TOP=L2:L3=L2/L4:L6=L5/L7:BOTTOM=L7 |
| LBI_DATA15 | OTHERS | BUS | 4 | 5 | 5 | 10 | 5 | 14 | 6 | 10 | 12 | 12 | 12 | 12 |  | 50 Ohms | TOP=L2:L3=L2/L4:L6=L5/L7:BOTTOM=L7 |
| LBI_DATA15 | OTHERS | BUS | 5 | 5 | 5 | 10 | 5 | 14 | 6 | 10 | 12 | 12 | 12 | 12 |  | 50 Ohms | TOP=L2:L3=L2/L4:L6=L5/L7:BOTTOM=L7 |
| LBI_DATA15 | OTHERS | BUS | 6 | 5 | 5 | 10 | 5 | 14 | 6 | 10 | 12 | 12 | 12 | 12 |  | 50 Ohms | TOP=L2:L3=L2/L4:L6=L5/L7:BOTTOM=L7 |
| LBI_DATA15 | OTHERS | BUS | 7 | 5 | 5 | 10 | 5 | 14 | 6 | 10 | 12 | 12 | 12 | 12 |  | 50 Ohms | TOP=L2:L3=L2/L4:L6=L5/L7:BOTTOM=L7 |
| LBI_DATA15 | OTHERS | BUS | 8 | 4.75 | 5 | 10 | 5 | 14 | 6 | 9.5 | 12 | 12 | 12 | 12 |  | 50 Ohms | TOP=L2:L3=L2/L4:L6=L5/L7:BOTTOM=L7 |
| LBI_OE# | OTHERS | BUS | 1 | 4.75 | 5 | 10 | 5 | 14 | 6 | 9.5 | 12 | 12 | 12 | 12 |  | 50 Ohms | TOP=L2:L3=L2/L4:L6=L5/L7:BOTTOM=L7 |
| LBI_OE# | OTHERS | BUS | 2 | 5 | 5 | 10 | 5 | 14 | 6 | 10 | 12 | 12 | 12 | 12 |  | 50 Ohms | TOP=L2:L3=L2/L4:L6=L5/L7:BOTTOM=L7 |
| LBI_OE# | OTHERS | BUS | 3 | 5 | 5 | 10 | 5 | 14 | 6 | 10 | 12 | 12 | 12 | 12 |  | 50 Ohms | TOP=L2:L3=L2/L4:L6=L5/L7:BOTTOM=L7 |
| LBI_OE# | OTHERS | BUS | 4 | 5 | 5 | 10 | 5 | 14 | 6 | 10 | 12 | 12 | 12 | 12 |  | 50 Ohms | TOP=L2:L3=L2/L4:L6=L5/L7:BOTTOM=L7 |
| LBI_OE# | OTHERS | BUS | 5 | 5 | 5 | 10 | 5 | 14 | 6 | 10 | 12 | 12 | 12 | 12 |  | 50 Ohms | TOP=L2:L3=L2/L4:L6=L5/L7:BOTTOM=L7 |
| LBI_OE# | OTHERS | BUS | 6 | 5 | 5 | 10 | 5 | 14 | 6 | 10 | 12 | 12 | 12 | 12 |  | 50 Ohms | TOP=L2:L3=L2/L4:L6=L5/L7:BOTTOM=L7 |
| LBI_OE# | OTHERS | BUS | 7 | 5 | 5 | 10 | 5 | 14 | 6 | 10 | 12 | 12 | 12 | 12 |  | 50 Ohms | TOP=L2:L3=L2/L4:L6=L5/L7:BOTTOM=L7 |
| LBI_OE# | OTHERS | BUS | 8 | 4.75 | 5 | 10 | 5 | 14 | 6 | 9.5 | 12 | 12 | 12 | 12 |  | 50 Ohms | TOP=L2:L3=L2/L4:L6=L5/L7:BOTTOM=L7 |
| LBI_WE# | OTHERS | BUS | 1 | 4.75 | 5 | 10 | 5 | 14 | 6 | 9.5 | 12 | 12 | 12 | 12 |  | 50 Ohms | TOP=L2:L3=L2/L4:L6=L5/L7:BOTTOM=L7 |
| LBI_WE# | OTHERS | BUS | 2 | 5 | 5 | 10 | 5 | 14 | 6 | 10 | 12 | 12 | 12 | 12 |  | 50 Ohms | TOP=L2:L3=L2/L4:L6=L5/L7:BOTTOM=L7 |
| LBI_WE# | OTHERS | BUS | 3 | 5 | 5 | 10 | 5 | 14 | 6 | 10 | 12 | 12 | 12 | 12 |  | 50 Ohms | TOP=L2:L3=L2/L4:L6=L5/L7:BOTTOM=L7 |
| LBI_WE# | OTHERS | BUS | 4 | 5 | 5 | 10 | 5 | 14 | 6 | 10 | 12 | 12 | 12 | 12 |  | 50 Ohms | TOP=L2:L3=L2/L4:L6=L5/L7:BOTTOM=L7 |
| LBI_WE# | OTHERS | BUS | 5 | 5 | 5 | 10 | 5 | 14 | 6 | 10 | 12 | 12 | 12 | 12 |  | 50 Ohms | TOP=L2:L3=L2/L4:L6=L5/L7:BOTTOM=L7 |
| LBI_WE# | OTHERS | BUS | 6 | 5 | 5 | 10 | 5 | 14 | 6 | 10 | 12 | 12 | 12 | 12 |  | 50 Ohms | TOP=L2:L3=L2/L4:L6=L5/L7:BOTTOM=L7 |
| LBI_WE# | OTHERS | BUS | 7 | 5 | 5 | 10 | 5 | 14 | 6 | 10 | 12 | 12 | 12 | 12 |  | 50 Ohms | TOP=L2:L3=L2/L4:L6=L5/L7:BOTTOM=L7 |
| LBI_WE# | OTHERS | BUS | 8 | 4.75 | 5 | 10 | 5 | 14 | 6 | 9.5 | 12 | 12 | 12 | 12 |  | 50 Ohms | TOP=L2:L3=L2/L4:L6=L5/L7:BOTTOM=L7 |
| LED_DR_LED0 | OTHERS | BUS | 1 | 4.75 | 5 | 10 | 5 | 14 | 6 | 9.5 | 12 | 12 | 12 | 12 |  | 50 Ohms | TOP=L2:L3=L2/L4:L6=L5/L7:BOTTOM=L7 |
| LED_DR_LED0 | OTHERS | BUS | 2 | 5 | 5 | 10 | 5 | 14 | 6 | 10 | 12 | 12 | 12 | 12 |  | 50 Ohms | TOP=L2:L3=L2/L4:L6=L5/L7:BOTTOM=L7 |
| LED_DR_LED0 | OTHERS | BUS | 3 | 5 | 5 | 10 | 5 | 14 | 6 | 10 | 12 | 12 | 12 | 12 |  | 50 Ohms | TOP=L2:L3=L2/L4:L6=L5/L7:BOTTOM=L7 |
| LED_DR_LED0 | OTHERS | BUS | 4 | 5 | 5 | 10 | 5 | 14 | 6 | 10 | 12 | 12 | 12 | 12 |  | 50 Ohms | TOP=L2:L3=L2/L4:L6=L5/L7:BOTTOM=L7 |
| LED_DR_LED0 | OTHERS | BUS | 5 | 5 | 5 | 10 | 5 | 14 | 6 | 10 | 12 | 12 | 12 | 12 |  | 50 Ohms | TOP=L2:L3=L2/L4:L6=L5/L7:BOTTOM=L7 |
| LED_DR_LED0 | OTHERS | BUS | 6 | 5 | 5 | 10 | 5 | 14 | 6 | 10 | 12 | 12 | 12 | 12 |  | 50 Ohms | TOP=L2:L3=L2/L4:L6=L5/L7:BOTTOM=L7 |
| LED_DR_LED0 | OTHERS | BUS | 7 | 5 | 5 | 10 | 5 | 14 | 6 | 10 | 12 | 12 | 12 | 12 |  | 50 Ohms | TOP=L2:L3=L2/L4:L6=L5/L7:BOTTOM=L7 |
| LED_DR_LED0 | OTHERS | BUS | 8 | 4.75 | 5 | 10 | 5 | 14 | 6 | 9.5 | 12 | 12 | 12 | 12 |  | 50 Ohms | TOP=L2:L3=L2/L4:L6=L5/L7:BOTTOM=L7 |
| LED_DR_LED1 | OTHERS | BUS | 1 | 4.75 | 5 | 10 | 5 | 14 | 6 | 9.5 | 12 | 12 | 12 | 12 |  | 50 Ohms | TOP=L2:L3=L2/L4:L6=L5/L7:BOTTOM=L7 |
| LED_DR_LED1 | OTHERS | BUS | 2 | 5 | 5 | 10 | 5 | 14 | 6 | 10 | 12 | 12 | 12 | 12 |  | 50 Ohms | TOP=L2:L3=L2/L4:L6=L5/L7:BOTTOM=L7 |
| LED_DR_LED1 | OTHERS | BUS | 3 | 5 | 5 | 10 | 5 | 14 | 6 | 10 | 12 | 12 | 12 | 12 |  | 50 Ohms | TOP=L2:L3=L2/L4:L6=L5/L7:BOTTOM=L7 |
| LED_DR_LED1 | OTHERS | BUS | 4 | 5 | 5 | 10 | 5 | 14 | 6 | 10 | 12 | 12 | 12 | 12 |  | 50 Ohms | TOP=L2:L3=L2/L4:L6=L5/L7:BOTTOM=L7 |
| LED_DR_LED1 | OTHERS | BUS | 5 | 5 | 5 | 10 | 5 | 14 | 6 | 10 | 12 | 12 | 12 | 12 |  | 50 Ohms | TOP=L2:L3=L2/L4:L6=L5/L7:BOTTOM=L7 |
| LED_DR_LED1 | OTHERS | BUS | 6 | 5 | 5 | 10 | 5 | 14 | 6 | 10 | 12 | 12 | 12 | 12 |  | 50 Ohms | TOP=L2:L3=L2/L4:L6=L5/L7:BOTTOM=L7 |
| LED_DR_LED1 | OTHERS | BUS | 7 | 5 | 5 | 10 | 5 | 14 | 6 | 10 | 12 | 12 | 12 | 12 |  | 50 Ohms | TOP=L2:L3=L2/L4:L6=L5/L7:BOTTOM=L7 |
| LED_DR_LED1 | OTHERS | BUS | 8 | 4.75 | 5 | 10 | 5 | 14 | 6 | 9.5 | 12 | 12 | 12 | 12 |  | 50 Ohms | TOP=L2:L3=L2/L4:L6=L5/L7:BOTTOM=L7 |
| LED_MDI0_100M_1G_N | OTHERS | BUS | 1 | 4.75 | 5 | 10 | 5 | 14 | 6 | 9.5 | 12 | 12 | 12 | 12 |  | 50 Ohms | TOP=L2:L3=L2/L4:L6=L5/L7:BOTTOM=L7 |
| LED_MDI0_100M_1G_N | OTHERS | BUS | 2 | 5 | 5 | 10 | 5 | 14 | 6 | 10 | 12 | 12 | 12 | 12 |  | 50 Ohms | TOP=L2:L3=L2/L4:L6=L5/L7:BOTTOM=L7 |
| LED_MDI0_100M_1G_N | OTHERS | BUS | 3 | 5 | 5 | 10 | 5 | 14 | 6 | 10 | 12 | 12 | 12 | 12 |  | 50 Ohms | TOP=L2:L3=L2/L4:L6=L5/L7:BOTTOM=L7 |
| LED_MDI0_100M_1G_N | OTHERS | BUS | 4 | 5 | 5 | 10 | 5 | 14 | 6 | 10 | 12 | 12 | 12 | 12 |  | 50 Ohms | TOP=L2:L3=L2/L4:L6=L5/L7:BOTTOM=L7 |
| LED_MDI0_100M_1G_N | OTHERS | BUS | 5 | 5 | 5 | 10 | 5 | 14 | 6 | 10 | 12 | 12 | 12 | 12 |  | 50 Ohms | TOP=L2:L3=L2/L4:L6=L5/L7:BOTTOM=L7 |
| LED_MDI0_100M_1G_N | OTHERS | BUS | 6 | 5 | 5 | 10 | 5 | 14 | 6 | 10 | 12 | 12 | 12 | 12 |  | 50 Ohms | TOP=L2:L3=L2/L4:L6=L5/L7:BOTTOM=L7 |
| LED_MDI0_100M_1G_N | OTHERS | BUS | 7 | 5 | 5 | 10 | 5 | 14 | 6 | 10 | 12 | 12 | 12 | 12 |  | 50 Ohms | TOP=L2:L3=L2/L4:L6=L5/L7:BOTTOM=L7 |
| LED_MDI0_100M_1G_N | OTHERS | BUS | 8 | 4.75 | 5 | 10 | 5 | 14 | 6 | 9.5 | 12 | 12 | 12 | 12 |  | 50 Ohms | TOP=L2:L3=L2/L4:L6=L5/L7:BOTTOM=L7 |
| LED_MDI0_100M_N | OTHERS | BUS | 1 | 4.75 | 5 | 10 | 5 | 14 | 6 | 9.5 | 12 | 12 | 12 | 12 |  | 50 Ohms | TOP=L2:L3=L2/L4:L6=L5/L7:BOTTOM=L7 |
| LED_MDI0_100M_N | OTHERS | BUS | 2 | 5 | 5 | 10 | 5 | 14 | 6 | 10 | 12 | 12 | 12 | 12 |  | 50 Ohms | TOP=L2:L3=L2/L4:L6=L5/L7:BOTTOM=L7 |
| LED_MDI0_100M_N | OTHERS | BUS | 3 | 5 | 5 | 10 | 5 | 14 | 6 | 10 | 12 | 12 | 12 | 12 |  | 50 Ohms | TOP=L2:L3=L2/L4:L6=L5/L7:BOTTOM=L7 |
| LED_MDI0_100M_N | OTHERS | BUS | 4 | 5 | 5 | 10 | 5 | 14 | 6 | 10 | 12 | 12 | 12 | 12 |  | 50 Ohms | TOP=L2:L3=L2/L4:L6=L5/L7:BOTTOM=L7 |
| LED_MDI0_100M_N | OTHERS | BUS | 5 | 5 | 5 | 10 | 5 | 14 | 6 | 10 | 12 | 12 | 12 | 12 |  | 50 Ohms | TOP=L2:L3=L2/L4:L6=L5/L7:BOTTOM=L7 |
| LED_MDI0_100M_N | OTHERS | BUS | 6 | 5 | 5 | 10 | 5 | 14 | 6 | 10 | 12 | 12 | 12 | 12 |  | 50 Ohms | TOP=L2:L3=L2/L4:L6=L5/L7:BOTTOM=L7 |
| LED_MDI0_100M_N | OTHERS | BUS | 7 | 5 | 5 | 10 | 5 | 14 | 6 | 10 | 12 | 12 | 12 | 12 |  | 50 Ohms | TOP=L2:L3=L2/L4:L6=L5/L7:BOTTOM=L7 |
| LED_MDI0_100M_N | OTHERS | BUS | 8 | 4.75 | 5 | 10 | 5 | 14 | 6 | 9.5 | 12 | 12 | 12 | 12 |  | 50 Ohms | TOP=L2:L3=L2/L4:L6=L5/L7:BOTTOM=L7 |
| LED_MDI0_100M_N_R | OTHERS | BUS | 1 | 4.75 | 5 | 10 | 5 | 14 | 6 | 9.5 | 12 | 12 | 12 | 12 |  | 50 Ohms | TOP=L2:L3=L2/L4:L6=L5/L7:BOTTOM=L7 |
| LED_MDI0_100M_N_R | OTHERS | BUS | 2 | 5 | 5 | 10 | 5 | 14 | 6 | 10 | 12 | 12 | 12 | 12 |  | 50 Ohms | TOP=L2:L3=L2/L4:L6=L5/L7:BOTTOM=L7 |
| LED_MDI0_100M_N_R | OTHERS | BUS | 3 | 5 | 5 | 10 | 5 | 14 | 6 | 10 | 12 | 12 | 12 | 12 |  | 50 Ohms | TOP=L2:L3=L2/L4:L6=L5/L7:BOTTOM=L7 |
| LED_MDI0_100M_N_R | OTHERS | BUS | 4 | 5 | 5 | 10 | 5 | 14 | 6 | 10 | 12 | 12 | 12 | 12 |  | 50 Ohms | TOP=L2:L3=L2/L4:L6=L5/L7:BOTTOM=L7 |
| LED_MDI0_100M_N_R | OTHERS | BUS | 5 | 5 | 5 | 10 | 5 | 14 | 6 | 10 | 12 | 12 | 12 | 12 |  | 50 Ohms | TOP=L2:L3=L2/L4:L6=L5/L7:BOTTOM=L7 |
| LED_MDI0_100M_N_R | OTHERS | BUS | 6 | 5 | 5 | 10 | 5 | 14 | 6 | 10 | 12 | 12 | 12 | 12 |  | 50 Ohms | TOP=L2:L3=L2/L4:L6=L5/L7:BOTTOM=L7 |
| LED_MDI0_100M_N_R | OTHERS | BUS | 7 | 5 | 5 | 10 | 5 | 14 | 6 | 10 | 12 | 12 | 12 | 12 |  | 50 Ohms | TOP=L2:L3=L2/L4:L6=L5/L7:BOTTOM=L7 |
| LED_MDI0_100M_N_R | OTHERS | BUS | 8 | 4.75 | 5 | 10 | 5 | 14 | 6 | 9.5 | 12 | 12 | 12 | 12 |  | 50 Ohms | TOP=L2:L3=L2/L4:L6=L5/L7:BOTTOM=L7 |
| LED_MDI0_1G_N | OTHERS | BUS | 1 | 4.75 | 5 | 10 | 5 | 14 | 6 | 9.5 | 12 | 12 | 12 | 12 |  | 50 Ohms | TOP=L2:L3=L2/L4:L6=L5/L7:BOTTOM=L7 |
| LED_MDI0_1G_N | OTHERS | BUS | 2 | 5 | 5 | 10 | 5 | 14 | 6 | 10 | 12 | 12 | 12 | 12 |  | 50 Ohms | TOP=L2:L3=L2/L4:L6=L5/L7:BOTTOM=L7 |
| LED_MDI0_1G_N | OTHERS | BUS | 3 | 5 | 5 | 10 | 5 | 14 | 6 | 10 | 12 | 12 | 12 | 12 |  | 50 Ohms | TOP=L2:L3=L2/L4:L6=L5/L7:BOTTOM=L7 |
| LED_MDI0_1G_N | OTHERS | BUS | 4 | 5 | 5 | 10 | 5 | 14 | 6 | 10 | 12 | 12 | 12 | 12 |  | 50 Ohms | TOP=L2:L3=L2/L4:L6=L5/L7:BOTTOM=L7 |
| LED_MDI0_1G_N | OTHERS | BUS | 5 | 5 | 5 | 10 | 5 | 14 | 6 | 10 | 12 | 12 | 12 | 12 |  | 50 Ohms | TOP=L2:L3=L2/L4:L6=L5/L7:BOTTOM=L7 |
| LED_MDI0_1G_N | OTHERS | BUS | 6 | 5 | 5 | 10 | 5 | 14 | 6 | 10 | 12 | 12 | 12 | 12 |  | 50 Ohms | TOP=L2:L3=L2/L4:L6=L5/L7:BOTTOM=L7 |
| LED_MDI0_1G_N | OTHERS | BUS | 7 | 5 | 5 | 10 | 5 | 14 | 6 | 10 | 12 | 12 | 12 | 12 |  | 50 Ohms | TOP=L2:L3=L2/L4:L6=L5/L7:BOTTOM=L7 |
| LED_MDI0_1G_N | OTHERS | BUS | 8 | 4.75 | 5 | 10 | 5 | 14 | 6 | 9.5 | 12 | 12 | 12 | 12 |  | 50 Ohms | TOP=L2:L3=L2/L4:L6=L5/L7:BOTTOM=L7 |
| LED_MDI0_1G_N_R | OTHERS | BUS | 1 | 4.75 | 5 | 10 | 5 | 14 | 6 | 9.5 | 12 | 12 | 12 | 12 |  | 50 Ohms | TOP=L2:L3=L2/L4:L6=L5/L7:BOTTOM=L7 |
| LED_MDI0_1G_N_R | OTHERS | BUS | 2 | 5 | 5 | 10 | 5 | 14 | 6 | 10 | 12 | 12 | 12 | 12 |  | 50 Ohms | TOP=L2:L3=L2/L4:L6=L5/L7:BOTTOM=L7 |
| LED_MDI0_1G_N_R | OTHERS | BUS | 3 | 5 | 5 | 10 | 5 | 14 | 6 | 10 | 12 | 12 | 12 | 12 |  | 50 Ohms | TOP=L2:L3=L2/L4:L6=L5/L7:BOTTOM=L7 |
| LED_MDI0_1G_N_R | OTHERS | BUS | 4 | 5 | 5 | 10 | 5 | 14 | 6 | 10 | 12 | 12 | 12 | 12 |  | 50 Ohms | TOP=L2:L3=L2/L4:L6=L5/L7:BOTTOM=L7 |
| LED_MDI0_1G_N_R | OTHERS | BUS | 5 | 5 | 5 | 10 | 5 | 14 | 6 | 10 | 12 | 12 | 12 | 12 |  | 50 Ohms | TOP=L2:L3=L2/L4:L6=L5/L7:BOTTOM=L7 |
| LED_MDI0_1G_N_R | OTHERS | BUS | 6 | 5 | 5 | 10 | 5 | 14 | 6 | 10 | 12 | 12 | 12 | 12 |  | 50 Ohms | TOP=L2:L3=L2/L4:L6=L5/L7:BOTTOM=L7 |
| LED_MDI0_1G_N_R | OTHERS | BUS | 7 | 5 | 5 | 10 | 5 | 14 | 6 | 10 | 12 | 12 | 12 | 12 |  | 50 Ohms | TOP=L2:L3=L2/L4:L6=L5/L7:BOTTOM=L7 |
| LED_MDI0_1G_N_R | OTHERS | BUS | 8 | 4.75 | 5 | 10 | 5 | 14 | 6 | 9.5 | 12 | 12 | 12 | 12 |  | 50 Ohms | TOP=L2:L3=L2/L4:L6=L5/L7:BOTTOM=L7 |
| LED_MDI0_ACT | OTHERS | BUS | 1 | 4.75 | 5 | 10 | 5 | 14 | 6 | 9.5 | 12 | 12 | 12 | 12 |  | 50 Ohms | TOP=L2:L3=L2/L4:L6=L5/L7:BOTTOM=L7 |
| LED_MDI0_ACT | OTHERS | BUS | 2 | 5 | 5 | 10 | 5 | 14 | 6 | 10 | 12 | 12 | 12 | 12 |  | 50 Ohms | TOP=L2:L3=L2/L4:L6=L5/L7:BOTTOM=L7 |
| LED_MDI0_ACT | OTHERS | BUS | 3 | 5 | 5 | 10 | 5 | 14 | 6 | 10 | 12 | 12 | 12 | 12 |  | 50 Ohms | TOP=L2:L3=L2/L4:L6=L5/L7:BOTTOM=L7 |
| LED_MDI0_ACT | OTHERS | BUS | 4 | 5 | 5 | 10 | 5 | 14 | 6 | 10 | 12 | 12 | 12 | 12 |  | 50 Ohms | TOP=L2:L3=L2/L4:L6=L5/L7:BOTTOM=L7 |
| LED_MDI0_ACT | OTHERS | BUS | 5 | 5 | 5 | 10 | 5 | 14 | 6 | 10 | 12 | 12 | 12 | 12 |  | 50 Ohms | TOP=L2:L3=L2/L4:L6=L5/L7:BOTTOM=L7 |
| LED_MDI0_ACT | OTHERS | BUS | 6 | 5 | 5 | 10 | 5 | 14 | 6 | 10 | 12 | 12 | 12 | 12 |  | 50 Ohms | TOP=L2:L3=L2/L4:L6=L5/L7:BOTTOM=L7 |
| LED_MDI0_ACT | OTHERS | BUS | 7 | 5 | 5 | 10 | 5 | 14 | 6 | 10 | 12 | 12 | 12 | 12 |  | 50 Ohms | TOP=L2:L3=L2/L4:L6=L5/L7:BOTTOM=L7 |
| LED_MDI0_ACT | OTHERS | BUS | 8 | 4.75 | 5 | 10 | 5 | 14 | 6 | 9.5 | 12 | 12 | 12 | 12 |  | 50 Ohms | TOP=L2:L3=L2/L4:L6=L5/L7:BOTTOM=L7 |
| LED_MDI0_LINK_N | OTHERS | BUS | 1 | 4.75 | 5 | 10 | 5 | 14 | 6 | 9.5 | 12 | 12 | 12 | 12 |  | 50 Ohms | TOP=L2:L3=L2/L4:L6=L5/L7:BOTTOM=L7 |
| LED_MDI0_LINK_N | OTHERS | BUS | 2 | 5 | 5 | 10 | 5 | 14 | 6 | 10 | 12 | 12 | 12 | 12 |  | 50 Ohms | TOP=L2:L3=L2/L4:L6=L5/L7:BOTTOM=L7 |
| LED_MDI0_LINK_N | OTHERS | BUS | 3 | 5 | 5 | 10 | 5 | 14 | 6 | 10 | 12 | 12 | 12 | 12 |  | 50 Ohms | TOP=L2:L3=L2/L4:L6=L5/L7:BOTTOM=L7 |
| LED_MDI0_LINK_N | OTHERS | BUS | 4 | 5 | 5 | 10 | 5 | 14 | 6 | 10 | 12 | 12 | 12 | 12 |  | 50 Ohms | TOP=L2:L3=L2/L4:L6=L5/L7:BOTTOM=L7 |
| LED_MDI0_LINK_N | OTHERS | BUS | 5 | 5 | 5 | 10 | 5 | 14 | 6 | 10 | 12 | 12 | 12 | 12 |  | 50 Ohms | TOP=L2:L3=L2/L4:L6=L5/L7:BOTTOM=L7 |
| LED_MDI0_LINK_N | OTHERS | BUS | 6 | 5 | 5 | 10 | 5 | 14 | 6 | 10 | 12 | 12 | 12 | 12 |  | 50 Ohms | TOP=L2:L3=L2/L4:L6=L5/L7:BOTTOM=L7 |
| LED_MDI0_LINK_N | OTHERS | BUS | 7 | 5 | 5 | 10 | 5 | 14 | 6 | 10 | 12 | 12 | 12 | 12 |  | 50 Ohms | TOP=L2:L3=L2/L4:L6=L5/L7:BOTTOM=L7 |
| LED_MDI0_LINK_N | OTHERS | BUS | 8 | 4.75 | 5 | 10 | 5 | 14 | 6 | 9.5 | 12 | 12 | 12 | 12 |  | 50 Ohms | TOP=L2:L3=L2/L4:L6=L5/L7:BOTTOM=L7 |
| LED_PWR_N_ON | OTHERS | BUS | 1 | 4.75 | 5 | 10 | 5 | 14 | 6 | 9.5 | 12 | 12 | 12 | 12 |  | 50 Ohms | TOP=L2:L3=L2/L4:L6=L5/L7:BOTTOM=L7 |
| LED_PWR_N_ON | OTHERS | BUS | 2 | 5 | 5 | 10 | 5 | 14 | 6 | 10 | 12 | 12 | 12 | 12 |  | 50 Ohms | TOP=L2:L3=L2/L4:L6=L5/L7:BOTTOM=L7 |
| LED_PWR_N_ON | OTHERS | BUS | 3 | 5 | 5 | 10 | 5 | 14 | 6 | 10 | 12 | 12 | 12 | 12 |  | 50 Ohms | TOP=L2:L3=L2/L4:L6=L5/L7:BOTTOM=L7 |
| LED_PWR_N_ON | OTHERS | BUS | 4 | 5 | 5 | 10 | 5 | 14 | 6 | 10 | 12 | 12 | 12 | 12 |  | 50 Ohms | TOP=L2:L3=L2/L4:L6=L5/L7:BOTTOM=L7 |
| LED_PWR_N_ON | OTHERS | BUS | 5 | 5 | 5 | 10 | 5 | 14 | 6 | 10 | 12 | 12 | 12 | 12 |  | 50 Ohms | TOP=L2:L3=L2/L4:L6=L5/L7:BOTTOM=L7 |
| LED_PWR_N_ON | OTHERS | BUS | 6 | 5 | 5 | 10 | 5 | 14 | 6 | 10 | 12 | 12 | 12 | 12 |  | 50 Ohms | TOP=L2:L3=L2/L4:L6=L5/L7:BOTTOM=L7 |
| LED_PWR_N_ON | OTHERS | BUS | 7 | 5 | 5 | 10 | 5 | 14 | 6 | 10 | 12 | 12 | 12 | 12 |  | 50 Ohms | TOP=L2:L3=L2/L4:L6=L5/L7:BOTTOM=L7 |
| LED_PWR_N_ON | OTHERS | BUS | 8 | 4.75 | 5 | 10 | 5 | 14 | 6 | 9.5 | 12 | 12 | 12 | 12 |  | 50 Ohms | TOP=L2:L3=L2/L4:L6=L5/L7:BOTTOM=L7 |
| LED_PWR_N_R | OTHERS | BUS | 1 | 4.75 | 5 | 10 | 5 | 14 | 6 | 9.5 | 12 | 12 | 12 | 12 |  | 50 Ohms | TOP=L2:L3=L2/L4:L6=L5/L7:BOTTOM=L7 |
| LED_PWR_N_R | OTHERS | BUS | 2 | 5 | 5 | 10 | 5 | 14 | 6 | 10 | 12 | 12 | 12 | 12 |  | 50 Ohms | TOP=L2:L3=L2/L4:L6=L5/L7:BOTTOM=L7 |
| LED_PWR_N_R | OTHERS | BUS | 3 | 5 | 5 | 10 | 5 | 14 | 6 | 10 | 12 | 12 | 12 | 12 |  | 50 Ohms | TOP=L2:L3=L2/L4:L6=L5/L7:BOTTOM=L7 |
| LED_PWR_N_R | OTHERS | BUS | 4 | 5 | 5 | 10 | 5 | 14 | 6 | 10 | 12 | 12 | 12 | 12 |  | 50 Ohms | TOP=L2:L3=L2/L4:L6=L5/L7:BOTTOM=L7 |
| LED_PWR_N_R | OTHERS | BUS | 5 | 5 | 5 | 10 | 5 | 14 | 6 | 10 | 12 | 12 | 12 | 12 |  | 50 Ohms | TOP=L2:L3=L2/L4:L6=L5/L7:BOTTOM=L7 |
| LED_PWR_N_R | OTHERS | BUS | 6 | 5 | 5 | 10 | 5 | 14 | 6 | 10 | 12 | 12 | 12 | 12 |  | 50 Ohms | TOP=L2:L3=L2/L4:L6=L5/L7:BOTTOM=L7 |
| LED_PWR_N_R | OTHERS | BUS | 7 | 5 | 5 | 10 | 5 | 14 | 6 | 10 | 12 | 12 | 12 | 12 |  | 50 Ohms | TOP=L2:L3=L2/L4:L6=L5/L7:BOTTOM=L7 |
| LED_PWR_N_R | OTHERS | BUS | 8 | 4.75 | 5 | 10 | 5 | 14 | 6 | 9.5 | 12 | 12 | 12 | 12 |  | 50 Ohms | TOP=L2:L3=L2/L4:L6=L5/L7:BOTTOM=L7 |
| LED_Q_1 | OTHERS | BUS | 1 | 4.75 | 5 | 10 | 5 | 14 | 6 | 9.5 | 12 | 12 | 12 | 12 |  | 50 Ohms | TOP=L2:L3=L2/L4:L6=L5/L7:BOTTOM=L7 |
| LED_Q_1 | OTHERS | BUS | 2 | 5 | 5 | 10 | 5 | 14 | 6 | 10 | 12 | 12 | 12 | 12 |  | 50 Ohms | TOP=L2:L3=L2/L4:L6=L5/L7:BOTTOM=L7 |
| LED_Q_1 | OTHERS | BUS | 3 | 5 | 5 | 10 | 5 | 14 | 6 | 10 | 12 | 12 | 12 | 12 |  | 50 Ohms | TOP=L2:L3=L2/L4:L6=L5/L7:BOTTOM=L7 |
| LED_Q_1 | OTHERS | BUS | 4 | 5 | 5 | 10 | 5 | 14 | 6 | 10 | 12 | 12 | 12 | 12 |  | 50 Ohms | TOP=L2:L3=L2/L4:L6=L5/L7:BOTTOM=L7 |
| LED_Q_1 | OTHERS | BUS | 5 | 5 | 5 | 10 | 5 | 14 | 6 | 10 | 12 | 12 | 12 | 12 |  | 50 Ohms | TOP=L2:L3=L2/L4:L6=L5/L7:BOTTOM=L7 |
| LED_Q_1 | OTHERS | BUS | 6 | 5 | 5 | 10 | 5 | 14 | 6 | 10 | 12 | 12 | 12 | 12 |  | 50 Ohms | TOP=L2:L3=L2/L4:L6=L5/L7:BOTTOM=L7 |
| LED_Q_1 | OTHERS | BUS | 7 | 5 | 5 | 10 | 5 | 14 | 6 | 10 | 12 | 12 | 12 | 12 |  | 50 Ohms | TOP=L2:L3=L2/L4:L6=L5/L7:BOTTOM=L7 |
| LED_Q_1 | OTHERS | BUS | 8 | 4.75 | 5 | 10 | 5 | 14 | 6 | 9.5 | 12 | 12 | 12 | 12 |  | 50 Ohms | TOP=L2:L3=L2/L4:L6=L5/L7:BOTTOM=L7 |
| LED_Q_10 | OTHERS | BUS | 1 | 4.75 | 5 | 10 | 5 | 14 | 6 | 9.5 | 12 | 12 | 12 | 12 |  | 50 Ohms | TOP=L2:L3=L2/L4:L6=L5/L7:BOTTOM=L7 |
| LED_Q_10 | OTHERS | BUS | 2 | 5 | 5 | 10 | 5 | 14 | 6 | 10 | 12 | 12 | 12 | 12 |  | 50 Ohms | TOP=L2:L3=L2/L4:L6=L5/L7:BOTTOM=L7 |
| LED_Q_10 | OTHERS | BUS | 3 | 5 | 5 | 10 | 5 | 14 | 6 | 10 | 12 | 12 | 12 | 12 |  | 50 Ohms | TOP=L2:L3=L2/L4:L6=L5/L7:BOTTOM=L7 |
| LED_Q_10 | OTHERS | BUS | 4 | 5 | 5 | 10 | 5 | 14 | 6 | 10 | 12 | 12 | 12 | 12 |  | 50 Ohms | TOP=L2:L3=L2/L4:L6=L5/L7:BOTTOM=L7 |
| LED_Q_10 | OTHERS | BUS | 5 | 5 | 5 | 10 | 5 | 14 | 6 | 10 | 12 | 12 | 12 | 12 |  | 50 Ohms | TOP=L2:L3=L2/L4:L6=L5/L7:BOTTOM=L7 |
| LED_Q_10 | OTHERS | BUS | 6 | 5 | 5 | 10 | 5 | 14 | 6 | 10 | 12 | 12 | 12 | 12 |  | 50 Ohms | TOP=L2:L3=L2/L4:L6=L5/L7:BOTTOM=L7 |
| LED_Q_10 | OTHERS | BUS | 7 | 5 | 5 | 10 | 5 | 14 | 6 | 10 | 12 | 12 | 12 | 12 |  | 50 Ohms | TOP=L2:L3=L2/L4:L6=L5/L7:BOTTOM=L7 |
| LED_Q_10 | OTHERS | BUS | 8 | 4.75 | 5 | 10 | 5 | 14 | 6 | 9.5 | 12 | 12 | 12 | 12 |  | 50 Ohms | TOP=L2:L3=L2/L4:L6=L5/L7:BOTTOM=L7 |
| LED_Q_11 | OTHERS | BUS | 1 | 4.75 | 5 | 10 | 5 | 14 | 6 | 9.5 | 12 | 12 | 12 | 12 |  | 50 Ohms | TOP=L2:L3=L2/L4:L6=L5/L7:BOTTOM=L7 |
| LED_Q_11 | OTHERS | BUS | 2 | 5 | 5 | 10 | 5 | 14 | 6 | 10 | 12 | 12 | 12 | 12 |  | 50 Ohms | TOP=L2:L3=L2/L4:L6=L5/L7:BOTTOM=L7 |
| LED_Q_11 | OTHERS | BUS | 3 | 5 | 5 | 10 | 5 | 14 | 6 | 10 | 12 | 12 | 12 | 12 |  | 50 Ohms | TOP=L2:L3=L2/L4:L6=L5/L7:BOTTOM=L7 |
| LED_Q_11 | OTHERS | BUS | 4 | 5 | 5 | 10 | 5 | 14 | 6 | 10 | 12 | 12 | 12 | 12 |  | 50 Ohms | TOP=L2:L3=L2/L4:L6=L5/L7:BOTTOM=L7 |
| LED_Q_11 | OTHERS | BUS | 5 | 5 | 5 | 10 | 5 | 14 | 6 | 10 | 12 | 12 | 12 | 12 |  | 50 Ohms | TOP=L2:L3=L2/L4:L6=L5/L7:BOTTOM=L7 |
| LED_Q_11 | OTHERS | BUS | 6 | 5 | 5 | 10 | 5 | 14 | 6 | 10 | 12 | 12 | 12 | 12 |  | 50 Ohms | TOP=L2:L3=L2/L4:L6=L5/L7:BOTTOM=L7 |
| LED_Q_11 | OTHERS | BUS | 7 | 5 | 5 | 10 | 5 | 14 | 6 | 10 | 12 | 12 | 12 | 12 |  | 50 Ohms | TOP=L2:L3=L2/L4:L6=L5/L7:BOTTOM=L7 |
| LED_Q_11 | OTHERS | BUS | 8 | 4.75 | 5 | 10 | 5 | 14 | 6 | 9.5 | 12 | 12 | 12 | 12 |  | 50 Ohms | TOP=L2:L3=L2/L4:L6=L5/L7:BOTTOM=L7 |
| LED_Q_12 | OTHERS | BUS | 1 | 4.75 | 5 | 10 | 5 | 14 | 6 | 9.5 | 12 | 12 | 12 | 12 |  | 50 Ohms | TOP=L2:L3=L2/L4:L6=L5/L7:BOTTOM=L7 |
| LED_Q_12 | OTHERS | BUS | 2 | 5 | 5 | 10 | 5 | 14 | 6 | 10 | 12 | 12 | 12 | 12 |  | 50 Ohms | TOP=L2:L3=L2/L4:L6=L5/L7:BOTTOM=L7 |
| LED_Q_12 | OTHERS | BUS | 3 | 5 | 5 | 10 | 5 | 14 | 6 | 10 | 12 | 12 | 12 | 12 |  | 50 Ohms | TOP=L2:L3=L2/L4:L6=L5/L7:BOTTOM=L7 |
| LED_Q_12 | OTHERS | BUS | 4 | 5 | 5 | 10 | 5 | 14 | 6 | 10 | 12 | 12 | 12 | 12 |  | 50 Ohms | TOP=L2:L3=L2/L4:L6=L5/L7:BOTTOM=L7 |
| LED_Q_12 | OTHERS | BUS | 5 | 5 | 5 | 10 | 5 | 14 | 6 | 10 | 12 | 12 | 12 | 12 |  | 50 Ohms | TOP=L2:L3=L2/L4:L6=L5/L7:BOTTOM=L7 |
| LED_Q_12 | OTHERS | BUS | 6 | 5 | 5 | 10 | 5 | 14 | 6 | 10 | 12 | 12 | 12 | 12 |  | 50 Ohms | TOP=L2:L3=L2/L4:L6=L5/L7:BOTTOM=L7 |
| LED_Q_12 | OTHERS | BUS | 7 | 5 | 5 | 10 | 5 | 14 | 6 | 10 | 12 | 12 | 12 | 12 |  | 50 Ohms | TOP=L2:L3=L2/L4:L6=L5/L7:BOTTOM=L7 |
| LED_Q_12 | OTHERS | BUS | 8 | 4.75 | 5 | 10 | 5 | 14 | 6 | 9.5 | 12 | 12 | 12 | 12 |  | 50 Ohms | TOP=L2:L3=L2/L4:L6=L5/L7:BOTTOM=L7 |
| LED_Q_13 | OTHERS | BUS | 1 | 4.75 | 5 | 10 | 5 | 14 | 6 | 9.5 | 12 | 12 | 12 | 12 |  | 50 Ohms | TOP=L2:L3=L2/L4:L6=L5/L7:BOTTOM=L7 |
| LED_Q_13 | OTHERS | BUS | 2 | 5 | 5 | 10 | 5 | 14 | 6 | 10 | 12 | 12 | 12 | 12 |  | 50 Ohms | TOP=L2:L3=L2/L4:L6=L5/L7:BOTTOM=L7 |
| LED_Q_13 | OTHERS | BUS | 3 | 5 | 5 | 10 | 5 | 14 | 6 | 10 | 12 | 12 | 12 | 12 |  | 50 Ohms | TOP=L2:L3=L2/L4:L6=L5/L7:BOTTOM=L7 |
| LED_Q_13 | OTHERS | BUS | 4 | 5 | 5 | 10 | 5 | 14 | 6 | 10 | 12 | 12 | 12 | 12 |  | 50 Ohms | TOP=L2:L3=L2/L4:L6=L5/L7:BOTTOM=L7 |
| LED_Q_13 | OTHERS | BUS | 5 | 5 | 5 | 10 | 5 | 14 | 6 | 10 | 12 | 12 | 12 | 12 |  | 50 Ohms | TOP=L2:L3=L2/L4:L6=L5/L7:BOTTOM=L7 |
| LED_Q_13 | OTHERS | BUS | 6 | 5 | 5 | 10 | 5 | 14 | 6 | 10 | 12 | 12 | 12 | 12 |  | 50 Ohms | TOP=L2:L3=L2/L4:L6=L5/L7:BOTTOM=L7 |
| LED_Q_13 | OTHERS | BUS | 7 | 5 | 5 | 10 | 5 | 14 | 6 | 10 | 12 | 12 | 12 | 12 |  | 50 Ohms | TOP=L2:L3=L2/L4:L6=L5/L7:BOTTOM=L7 |
| LED_Q_13 | OTHERS | BUS | 8 | 4.75 | 5 | 10 | 5 | 14 | 6 | 9.5 | 12 | 12 | 12 | 12 |  | 50 Ohms | TOP=L2:L3=L2/L4:L6=L5/L7:BOTTOM=L7 |
| LED_Q_14 | OTHERS | BUS | 1 | 4.75 | 5 | 10 | 5 | 14 | 6 | 9.5 | 12 | 12 | 12 | 12 |  | 50 Ohms | TOP=L2:L3=L2/L4:L6=L5/L7:BOTTOM=L7 |
| LED_Q_14 | OTHERS | BUS | 2 | 5 | 5 | 10 | 5 | 14 | 6 | 10 | 12 | 12 | 12 | 12 |  | 50 Ohms | TOP=L2:L3=L2/L4:L6=L5/L7:BOTTOM=L7 |
| LED_Q_14 | OTHERS | BUS | 3 | 5 | 5 | 10 | 5 | 14 | 6 | 10 | 12 | 12 | 12 | 12 |  | 50 Ohms | TOP=L2:L3=L2/L4:L6=L5/L7:BOTTOM=L7 |
| LED_Q_14 | OTHERS | BUS | 4 | 5 | 5 | 10 | 5 | 14 | 6 | 10 | 12 | 12 | 12 | 12 |  | 50 Ohms | TOP=L2:L3=L2/L4:L6=L5/L7:BOTTOM=L7 |
| LED_Q_14 | OTHERS | BUS | 5 | 5 | 5 | 10 | 5 | 14 | 6 | 10 | 12 | 12 | 12 | 12 |  | 50 Ohms | TOP=L2:L3=L2/L4:L6=L5/L7:BOTTOM=L7 |
| LED_Q_14 | OTHERS | BUS | 6 | 5 | 5 | 10 | 5 | 14 | 6 | 10 | 12 | 12 | 12 | 12 |  | 50 Ohms | TOP=L2:L3=L2/L4:L6=L5/L7:BOTTOM=L7 |
| LED_Q_14 | OTHERS | BUS | 7 | 5 | 5 | 10 | 5 | 14 | 6 | 10 | 12 | 12 | 12 | 12 |  | 50 Ohms | TOP=L2:L3=L2/L4:L6=L5/L7:BOTTOM=L7 |
| LED_Q_14 | OTHERS | BUS | 8 | 4.75 | 5 | 10 | 5 | 14 | 6 | 9.5 | 12 | 12 | 12 | 12 |  | 50 Ohms | TOP=L2:L3=L2/L4:L6=L5/L7:BOTTOM=L7 |
| LED_Q_2 | OTHERS | BUS | 1 | 4.75 | 5 | 10 | 5 | 14 | 6 | 9.5 | 12 | 12 | 12 | 12 |  | 50 Ohms | TOP=L2:L3=L2/L4:L6=L5/L7:BOTTOM=L7 |
| LED_Q_2 | OTHERS | BUS | 2 | 5 | 5 | 10 | 5 | 14 | 6 | 10 | 12 | 12 | 12 | 12 |  | 50 Ohms | TOP=L2:L3=L2/L4:L6=L5/L7:BOTTOM=L7 |
| LED_Q_2 | OTHERS | BUS | 3 | 5 | 5 | 10 | 5 | 14 | 6 | 10 | 12 | 12 | 12 | 12 |  | 50 Ohms | TOP=L2:L3=L2/L4:L6=L5/L7:BOTTOM=L7 |
| LED_Q_2 | OTHERS | BUS | 4 | 5 | 5 | 10 | 5 | 14 | 6 | 10 | 12 | 12 | 12 | 12 |  | 50 Ohms | TOP=L2:L3=L2/L4:L6=L5/L7:BOTTOM=L7 |
| LED_Q_2 | OTHERS | BUS | 5 | 5 | 5 | 10 | 5 | 14 | 6 | 10 | 12 | 12 | 12 | 12 |  | 50 Ohms | TOP=L2:L3=L2/L4:L6=L5/L7:BOTTOM=L7 |
| LED_Q_2 | OTHERS | BUS | 6 | 5 | 5 | 10 | 5 | 14 | 6 | 10 | 12 | 12 | 12 | 12 |  | 50 Ohms | TOP=L2:L3=L2/L4:L6=L5/L7:BOTTOM=L7 |
| LED_Q_2 | OTHERS | BUS | 7 | 5 | 5 | 10 | 5 | 14 | 6 | 10 | 12 | 12 | 12 | 12 |  | 50 Ohms | TOP=L2:L3=L2/L4:L6=L5/L7:BOTTOM=L7 |
| LED_Q_2 | OTHERS | BUS | 8 | 4.75 | 5 | 10 | 5 | 14 | 6 | 9.5 | 12 | 12 | 12 | 12 |  | 50 Ohms | TOP=L2:L3=L2/L4:L6=L5/L7:BOTTOM=L7 |
| LED_Q_3 | OTHERS | BUS | 1 | 4.75 | 5 | 10 | 5 | 14 | 6 | 9.5 | 12 | 12 | 12 | 12 |  | 50 Ohms | TOP=L2:L3=L2/L4:L6=L5/L7:BOTTOM=L7 |
| LED_Q_3 | OTHERS | BUS | 2 | 5 | 5 | 10 | 5 | 14 | 6 | 10 | 12 | 12 | 12 | 12 |  | 50 Ohms | TOP=L2:L3=L2/L4:L6=L5/L7:BOTTOM=L7 |
| LED_Q_3 | OTHERS | BUS | 3 | 5 | 5 | 10 | 5 | 14 | 6 | 10 | 12 | 12 | 12 | 12 |  | 50 Ohms | TOP=L2:L3=L2/L4:L6=L5/L7:BOTTOM=L7 |
| LED_Q_3 | OTHERS | BUS | 4 | 5 | 5 | 10 | 5 | 14 | 6 | 10 | 12 | 12 | 12 | 12 |  | 50 Ohms | TOP=L2:L3=L2/L4:L6=L5/L7:BOTTOM=L7 |
| LED_Q_3 | OTHERS | BUS | 5 | 5 | 5 | 10 | 5 | 14 | 6 | 10 | 12 | 12 | 12 | 12 |  | 50 Ohms | TOP=L2:L3=L2/L4:L6=L5/L7:BOTTOM=L7 |
| LED_Q_3 | OTHERS | BUS | 6 | 5 | 5 | 10 | 5 | 14 | 6 | 10 | 12 | 12 | 12 | 12 |  | 50 Ohms | TOP=L2:L3=L2/L4:L6=L5/L7:BOTTOM=L7 |
| LED_Q_3 | OTHERS | BUS | 7 | 5 | 5 | 10 | 5 | 14 | 6 | 10 | 12 | 12 | 12 | 12 |  | 50 Ohms | TOP=L2:L3=L2/L4:L6=L5/L7:BOTTOM=L7 |
| LED_Q_3 | OTHERS | BUS | 8 | 4.75 | 5 | 10 | 5 | 14 | 6 | 9.5 | 12 | 12 | 12 | 12 |  | 50 Ohms | TOP=L2:L3=L2/L4:L6=L5/L7:BOTTOM=L7 |
| LED_Q_4 | OTHERS | BUS | 1 | 4.75 | 5 | 10 | 5 | 14 | 6 | 9.5 | 12 | 12 | 12 | 12 |  | 50 Ohms | TOP=L2:L3=L2/L4:L6=L5/L7:BOTTOM=L7 |
| LED_Q_4 | OTHERS | BUS | 2 | 5 | 5 | 10 | 5 | 14 | 6 | 10 | 12 | 12 | 12 | 12 |  | 50 Ohms | TOP=L2:L3=L2/L4:L6=L5/L7:BOTTOM=L7 |
| LED_Q_4 | OTHERS | BUS | 3 | 5 | 5 | 10 | 5 | 14 | 6 | 10 | 12 | 12 | 12 | 12 |  | 50 Ohms | TOP=L2:L3=L2/L4:L6=L5/L7:BOTTOM=L7 |
| LED_Q_4 | OTHERS | BUS | 4 | 5 | 5 | 10 | 5 | 14 | 6 | 10 | 12 | 12 | 12 | 12 |  | 50 Ohms | TOP=L2:L3=L2/L4:L6=L5/L7:BOTTOM=L7 |
| LED_Q_4 | OTHERS | BUS | 5 | 5 | 5 | 10 | 5 | 14 | 6 | 10 | 12 | 12 | 12 | 12 |  | 50 Ohms | TOP=L2:L3=L2/L4:L6=L5/L7:BOTTOM=L7 |
| LED_Q_4 | OTHERS | BUS | 6 | 5 | 5 | 10 | 5 | 14 | 6 | 10 | 12 | 12 | 12 | 12 |  | 50 Ohms | TOP=L2:L3=L2/L4:L6=L5/L7:BOTTOM=L7 |
| LED_Q_4 | OTHERS | BUS | 7 | 5 | 5 | 10 | 5 | 14 | 6 | 10 | 12 | 12 | 12 | 12 |  | 50 Ohms | TOP=L2:L3=L2/L4:L6=L5/L7:BOTTOM=L7 |
| LED_Q_4 | OTHERS | BUS | 8 | 4.75 | 5 | 10 | 5 | 14 | 6 | 9.5 | 12 | 12 | 12 | 12 |  | 50 Ohms | TOP=L2:L3=L2/L4:L6=L5/L7:BOTTOM=L7 |
| LED_Q_5 | OTHERS | BUS | 1 | 4.75 | 5 | 10 | 5 | 14 | 6 | 9.5 | 12 | 12 | 12 | 12 |  | 50 Ohms | TOP=L2:L3=L2/L4:L6=L5/L7:BOTTOM=L7 |
| LED_Q_5 | OTHERS | BUS | 2 | 5 | 5 | 10 | 5 | 14 | 6 | 10 | 12 | 12 | 12 | 12 |  | 50 Ohms | TOP=L2:L3=L2/L4:L6=L5/L7:BOTTOM=L7 |
| LED_Q_5 | OTHERS | BUS | 3 | 5 | 5 | 10 | 5 | 14 | 6 | 10 | 12 | 12 | 12 | 12 |  | 50 Ohms | TOP=L2:L3=L2/L4:L6=L5/L7:BOTTOM=L7 |
| LED_Q_5 | OTHERS | BUS | 4 | 5 | 5 | 10 | 5 | 14 | 6 | 10 | 12 | 12 | 12 | 12 |  | 50 Ohms | TOP=L2:L3=L2/L4:L6=L5/L7:BOTTOM=L7 |
| LED_Q_5 | OTHERS | BUS | 5 | 5 | 5 | 10 | 5 | 14 | 6 | 10 | 12 | 12 | 12 | 12 |  | 50 Ohms | TOP=L2:L3=L2/L4:L6=L5/L7:BOTTOM=L7 |
| LED_Q_5 | OTHERS | BUS | 6 | 5 | 5 | 10 | 5 | 14 | 6 | 10 | 12 | 12 | 12 | 12 |  | 50 Ohms | TOP=L2:L3=L2/L4:L6=L5/L7:BOTTOM=L7 |
| LED_Q_5 | OTHERS | BUS | 7 | 5 | 5 | 10 | 5 | 14 | 6 | 10 | 12 | 12 | 12 | 12 |  | 50 Ohms | TOP=L2:L3=L2/L4:L6=L5/L7:BOTTOM=L7 |
| LED_Q_5 | OTHERS | BUS | 8 | 4.75 | 5 | 10 | 5 | 14 | 6 | 9.5 | 12 | 12 | 12 | 12 |  | 50 Ohms | TOP=L2:L3=L2/L4:L6=L5/L7:BOTTOM=L7 |
| LED_Q_6 | OTHERS | BUS | 1 | 4.75 | 5 | 10 | 5 | 14 | 6 | 9.5 | 12 | 12 | 12 | 12 |  | 50 Ohms | TOP=L2:L3=L2/L4:L6=L5/L7:BOTTOM=L7 |
| LED_Q_6 | OTHERS | BUS | 2 | 5 | 5 | 10 | 5 | 14 | 6 | 10 | 12 | 12 | 12 | 12 |  | 50 Ohms | TOP=L2:L3=L2/L4:L6=L5/L7:BOTTOM=L7 |
| LED_Q_6 | OTHERS | BUS | 3 | 5 | 5 | 10 | 5 | 14 | 6 | 10 | 12 | 12 | 12 | 12 |  | 50 Ohms | TOP=L2:L3=L2/L4:L6=L5/L7:BOTTOM=L7 |
| LED_Q_6 | OTHERS | BUS | 4 | 5 | 5 | 10 | 5 | 14 | 6 | 10 | 12 | 12 | 12 | 12 |  | 50 Ohms | TOP=L2:L3=L2/L4:L6=L5/L7:BOTTOM=L7 |
| LED_Q_6 | OTHERS | BUS | 5 | 5 | 5 | 10 | 5 | 14 | 6 | 10 | 12 | 12 | 12 | 12 |  | 50 Ohms | TOP=L2:L3=L2/L4:L6=L5/L7:BOTTOM=L7 |
| LED_Q_6 | OTHERS | BUS | 6 | 5 | 5 | 10 | 5 | 14 | 6 | 10 | 12 | 12 | 12 | 12 |  | 50 Ohms | TOP=L2:L3=L2/L4:L6=L5/L7:BOTTOM=L7 |
| LED_Q_6 | OTHERS | BUS | 7 | 5 | 5 | 10 | 5 | 14 | 6 | 10 | 12 | 12 | 12 | 12 |  | 50 Ohms | TOP=L2:L3=L2/L4:L6=L5/L7:BOTTOM=L7 |
| LED_Q_6 | OTHERS | BUS | 8 | 4.75 | 5 | 10 | 5 | 14 | 6 | 9.5 | 12 | 12 | 12 | 12 |  | 50 Ohms | TOP=L2:L3=L2/L4:L6=L5/L7:BOTTOM=L7 |
| LED_Q_7 | OTHERS | BUS | 1 | 4.75 | 5 | 10 | 5 | 14 | 6 | 9.5 | 12 | 12 | 12 | 12 |  | 50 Ohms | TOP=L2:L3=L2/L4:L6=L5/L7:BOTTOM=L7 |
| LED_Q_7 | OTHERS | BUS | 2 | 5 | 5 | 10 | 5 | 14 | 6 | 10 | 12 | 12 | 12 | 12 |  | 50 Ohms | TOP=L2:L3=L2/L4:L6=L5/L7:BOTTOM=L7 |
| LED_Q_7 | OTHERS | BUS | 3 | 5 | 5 | 10 | 5 | 14 | 6 | 10 | 12 | 12 | 12 | 12 |  | 50 Ohms | TOP=L2:L3=L2/L4:L6=L5/L7:BOTTOM=L7 |
| LED_Q_7 | OTHERS | BUS | 4 | 5 | 5 | 10 | 5 | 14 | 6 | 10 | 12 | 12 | 12 | 12 |  | 50 Ohms | TOP=L2:L3=L2/L4:L6=L5/L7:BOTTOM=L7 |
| LED_Q_7 | OTHERS | BUS | 5 | 5 | 5 | 10 | 5 | 14 | 6 | 10 | 12 | 12 | 12 | 12 |  | 50 Ohms | TOP=L2:L3=L2/L4:L6=L5/L7:BOTTOM=L7 |
| LED_Q_7 | OTHERS | BUS | 6 | 5 | 5 | 10 | 5 | 14 | 6 | 10 | 12 | 12 | 12 | 12 |  | 50 Ohms | TOP=L2:L3=L2/L4:L6=L5/L7:BOTTOM=L7 |
| LED_Q_7 | OTHERS | BUS | 7 | 5 | 5 | 10 | 5 | 14 | 6 | 10 | 12 | 12 | 12 | 12 |  | 50 Ohms | TOP=L2:L3=L2/L4:L6=L5/L7:BOTTOM=L7 |
| LED_Q_7 | OTHERS | BUS | 8 | 4.75 | 5 | 10 | 5 | 14 | 6 | 9.5 | 12 | 12 | 12 | 12 |  | 50 Ohms | TOP=L2:L3=L2/L4:L6=L5/L7:BOTTOM=L7 |
| LED_Q_8 | OTHERS | BUS | 1 | 4.75 | 5 | 10 | 5 | 14 | 6 | 9.5 | 12 | 12 | 12 | 12 |  | 50 Ohms | TOP=L2:L3=L2/L4:L6=L5/L7:BOTTOM=L7 |
| LED_Q_8 | OTHERS | BUS | 2 | 5 | 5 | 10 | 5 | 14 | 6 | 10 | 12 | 12 | 12 | 12 |  | 50 Ohms | TOP=L2:L3=L2/L4:L6=L5/L7:BOTTOM=L7 |
| LED_Q_8 | OTHERS | BUS | 3 | 5 | 5 | 10 | 5 | 14 | 6 | 10 | 12 | 12 | 12 | 12 |  | 50 Ohms | TOP=L2:L3=L2/L4:L6=L5/L7:BOTTOM=L7 |
| LED_Q_8 | OTHERS | BUS | 4 | 5 | 5 | 10 | 5 | 14 | 6 | 10 | 12 | 12 | 12 | 12 |  | 50 Ohms | TOP=L2:L3=L2/L4:L6=L5/L7:BOTTOM=L7 |
| LED_Q_8 | OTHERS | BUS | 5 | 5 | 5 | 10 | 5 | 14 | 6 | 10 | 12 | 12 | 12 | 12 |  | 50 Ohms | TOP=L2:L3=L2/L4:L6=L5/L7:BOTTOM=L7 |
| LED_Q_8 | OTHERS | BUS | 6 | 5 | 5 | 10 | 5 | 14 | 6 | 10 | 12 | 12 | 12 | 12 |  | 50 Ohms | TOP=L2:L3=L2/L4:L6=L5/L7:BOTTOM=L7 |
| LED_Q_8 | OTHERS | BUS | 7 | 5 | 5 | 10 | 5 | 14 | 6 | 10 | 12 | 12 | 12 | 12 |  | 50 Ohms | TOP=L2:L3=L2/L4:L6=L5/L7:BOTTOM=L7 |
| LED_Q_8 | OTHERS | BUS | 8 | 4.75 | 5 | 10 | 5 | 14 | 6 | 9.5 | 12 | 12 | 12 | 12 |  | 50 Ohms | TOP=L2:L3=L2/L4:L6=L5/L7:BOTTOM=L7 |
| LED_Q_9 | OTHERS | BUS | 1 | 4.75 | 5 | 10 | 5 | 14 | 6 | 9.5 | 12 | 12 | 12 | 12 |  | 50 Ohms | TOP=L2:L3=L2/L4:L6=L5/L7:BOTTOM=L7 |
| LED_Q_9 | OTHERS | BUS | 2 | 5 | 5 | 10 | 5 | 14 | 6 | 10 | 12 | 12 | 12 | 12 |  | 50 Ohms | TOP=L2:L3=L2/L4:L6=L5/L7:BOTTOM=L7 |
| LED_Q_9 | OTHERS | BUS | 3 | 5 | 5 | 10 | 5 | 14 | 6 | 10 | 12 | 12 | 12 | 12 |  | 50 Ohms | TOP=L2:L3=L2/L4:L6=L5/L7:BOTTOM=L7 |
| LED_Q_9 | OTHERS | BUS | 4 | 5 | 5 | 10 | 5 | 14 | 6 | 10 | 12 | 12 | 12 | 12 |  | 50 Ohms | TOP=L2:L3=L2/L4:L6=L5/L7:BOTTOM=L7 |
| LED_Q_9 | OTHERS | BUS | 5 | 5 | 5 | 10 | 5 | 14 | 6 | 10 | 12 | 12 | 12 | 12 |  | 50 Ohms | TOP=L2:L3=L2/L4:L6=L5/L7:BOTTOM=L7 |
| LED_Q_9 | OTHERS | BUS | 6 | 5 | 5 | 10 | 5 | 14 | 6 | 10 | 12 | 12 | 12 | 12 |  | 50 Ohms | TOP=L2:L3=L2/L4:L6=L5/L7:BOTTOM=L7 |
| LED_Q_9 | OTHERS | BUS | 7 | 5 | 5 | 10 | 5 | 14 | 6 | 10 | 12 | 12 | 12 | 12 |  | 50 Ohms | TOP=L2:L3=L2/L4:L6=L5/L7:BOTTOM=L7 |
| LED_Q_9 | OTHERS | BUS | 8 | 4.75 | 5 | 10 | 5 | 14 | 6 | 9.5 | 12 | 12 | 12 | 12 |  | 50 Ohms | TOP=L2:L3=L2/L4:L6=L5/L7:BOTTOM=L7 |
| LED_R_1 | OTHERS | BUS | 1 | 4.75 | 5 | 10 | 5 | 14 | 6 | 9.5 | 12 | 12 | 12 | 12 |  | 50 Ohms | TOP=L2:L3=L2/L4:L6=L5/L7:BOTTOM=L7 |
| LED_R_1 | OTHERS | BUS | 2 | 5 | 5 | 10 | 5 | 14 | 6 | 10 | 12 | 12 | 12 | 12 |  | 50 Ohms | TOP=L2:L3=L2/L4:L6=L5/L7:BOTTOM=L7 |
| LED_R_1 | OTHERS | BUS | 3 | 5 | 5 | 10 | 5 | 14 | 6 | 10 | 12 | 12 | 12 | 12 |  | 50 Ohms | TOP=L2:L3=L2/L4:L6=L5/L7:BOTTOM=L7 |
| LED_R_1 | OTHERS | BUS | 4 | 5 | 5 | 10 | 5 | 14 | 6 | 10 | 12 | 12 | 12 | 12 |  | 50 Ohms | TOP=L2:L3=L2/L4:L6=L5/L7:BOTTOM=L7 |
| LED_R_1 | OTHERS | BUS | 5 | 5 | 5 | 10 | 5 | 14 | 6 | 10 | 12 | 12 | 12 | 12 |  | 50 Ohms | TOP=L2:L3=L2/L4:L6=L5/L7:BOTTOM=L7 |
| LED_R_1 | OTHERS | BUS | 6 | 5 | 5 | 10 | 5 | 14 | 6 | 10 | 12 | 12 | 12 | 12 |  | 50 Ohms | TOP=L2:L3=L2/L4:L6=L5/L7:BOTTOM=L7 |
| LED_R_1 | OTHERS | BUS | 7 | 5 | 5 | 10 | 5 | 14 | 6 | 10 | 12 | 12 | 12 | 12 |  | 50 Ohms | TOP=L2:L3=L2/L4:L6=L5/L7:BOTTOM=L7 |
| LED_R_1 | OTHERS | BUS | 8 | 4.75 | 5 | 10 | 5 | 14 | 6 | 9.5 | 12 | 12 | 12 | 12 |  | 50 Ohms | TOP=L2:L3=L2/L4:L6=L5/L7:BOTTOM=L7 |
| LED_R_10 | OTHERS | BUS | 1 | 4.75 | 5 | 10 | 5 | 14 | 6 | 9.5 | 12 | 12 | 12 | 12 |  | 50 Ohms | TOP=L2:L3=L2/L4:L6=L5/L7:BOTTOM=L7 |
| LED_R_10 | OTHERS | BUS | 2 | 5 | 5 | 10 | 5 | 14 | 6 | 10 | 12 | 12 | 12 | 12 |  | 50 Ohms | TOP=L2:L3=L2/L4:L6=L5/L7:BOTTOM=L7 |
| LED_R_10 | OTHERS | BUS | 3 | 5 | 5 | 10 | 5 | 14 | 6 | 10 | 12 | 12 | 12 | 12 |  | 50 Ohms | TOP=L2:L3=L2/L4:L6=L5/L7:BOTTOM=L7 |
| LED_R_10 | OTHERS | BUS | 4 | 5 | 5 | 10 | 5 | 14 | 6 | 10 | 12 | 12 | 12 | 12 |  | 50 Ohms | TOP=L2:L3=L2/L4:L6=L5/L7:BOTTOM=L7 |
| LED_R_10 | OTHERS | BUS | 5 | 5 | 5 | 10 | 5 | 14 | 6 | 10 | 12 | 12 | 12 | 12 |  | 50 Ohms | TOP=L2:L3=L2/L4:L6=L5/L7:BOTTOM=L7 |
| LED_R_10 | OTHERS | BUS | 6 | 5 | 5 | 10 | 5 | 14 | 6 | 10 | 12 | 12 | 12 | 12 |  | 50 Ohms | TOP=L2:L3=L2/L4:L6=L5/L7:BOTTOM=L7 |
| LED_R_10 | OTHERS | BUS | 7 | 5 | 5 | 10 | 5 | 14 | 6 | 10 | 12 | 12 | 12 | 12 |  | 50 Ohms | TOP=L2:L3=L2/L4:L6=L5/L7:BOTTOM=L7 |
| LED_R_10 | OTHERS | BUS | 8 | 4.75 | 5 | 10 | 5 | 14 | 6 | 9.5 | 12 | 12 | 12 | 12 |  | 50 Ohms | TOP=L2:L3=L2/L4:L6=L5/L7:BOTTOM=L7 |
| LED_R_11 | OTHERS | BUS | 1 | 4.75 | 5 | 10 | 5 | 14 | 6 | 9.5 | 12 | 12 | 12 | 12 |  | 50 Ohms | TOP=L2:L3=L2/L4:L6=L5/L7:BOTTOM=L7 |
| LED_R_11 | OTHERS | BUS | 2 | 5 | 5 | 10 | 5 | 14 | 6 | 10 | 12 | 12 | 12 | 12 |  | 50 Ohms | TOP=L2:L3=L2/L4:L6=L5/L7:BOTTOM=L7 |
| LED_R_11 | OTHERS | BUS | 3 | 5 | 5 | 10 | 5 | 14 | 6 | 10 | 12 | 12 | 12 | 12 |  | 50 Ohms | TOP=L2:L3=L2/L4:L6=L5/L7:BOTTOM=L7 |
| LED_R_11 | OTHERS | BUS | 4 | 5 | 5 | 10 | 5 | 14 | 6 | 10 | 12 | 12 | 12 | 12 |  | 50 Ohms | TOP=L2:L3=L2/L4:L6=L5/L7:BOTTOM=L7 |
| LED_R_11 | OTHERS | BUS | 5 | 5 | 5 | 10 | 5 | 14 | 6 | 10 | 12 | 12 | 12 | 12 |  | 50 Ohms | TOP=L2:L3=L2/L4:L6=L5/L7:BOTTOM=L7 |
| LED_R_11 | OTHERS | BUS | 6 | 5 | 5 | 10 | 5 | 14 | 6 | 10 | 12 | 12 | 12 | 12 |  | 50 Ohms | TOP=L2:L3=L2/L4:L6=L5/L7:BOTTOM=L7 |
| LED_R_11 | OTHERS | BUS | 7 | 5 | 5 | 10 | 5 | 14 | 6 | 10 | 12 | 12 | 12 | 12 |  | 50 Ohms | TOP=L2:L3=L2/L4:L6=L5/L7:BOTTOM=L7 |
| LED_R_11 | OTHERS | BUS | 8 | 4.75 | 5 | 10 | 5 | 14 | 6 | 9.5 | 12 | 12 | 12 | 12 |  | 50 Ohms | TOP=L2:L3=L2/L4:L6=L5/L7:BOTTOM=L7 |
| LED_R_12 | OTHERS | BUS | 1 | 4.75 | 5 | 10 | 5 | 14 | 6 | 9.5 | 12 | 12 | 12 | 12 |  | 50 Ohms | TOP=L2:L3=L2/L4:L6=L5/L7:BOTTOM=L7 |
| LED_R_12 | OTHERS | BUS | 2 | 5 | 5 | 10 | 5 | 14 | 6 | 10 | 12 | 12 | 12 | 12 |  | 50 Ohms | TOP=L2:L3=L2/L4:L6=L5/L7:BOTTOM=L7 |
| LED_R_12 | OTHERS | BUS | 3 | 5 | 5 | 10 | 5 | 14 | 6 | 10 | 12 | 12 | 12 | 12 |  | 50 Ohms | TOP=L2:L3=L2/L4:L6=L5/L7:BOTTOM=L7 |
| LED_R_12 | OTHERS | BUS | 4 | 5 | 5 | 10 | 5 | 14 | 6 | 10 | 12 | 12 | 12 | 12 |  | 50 Ohms | TOP=L2:L3=L2/L4:L6=L5/L7:BOTTOM=L7 |
| LED_R_12 | OTHERS | BUS | 5 | 5 | 5 | 10 | 5 | 14 | 6 | 10 | 12 | 12 | 12 | 12 |  | 50 Ohms | TOP=L2:L3=L2/L4:L6=L5/L7:BOTTOM=L7 |
| LED_R_12 | OTHERS | BUS | 6 | 5 | 5 | 10 | 5 | 14 | 6 | 10 | 12 | 12 | 12 | 12 |  | 50 Ohms | TOP=L2:L3=L2/L4:L6=L5/L7:BOTTOM=L7 |
| LED_R_12 | OTHERS | BUS | 7 | 5 | 5 | 10 | 5 | 14 | 6 | 10 | 12 | 12 | 12 | 12 |  | 50 Ohms | TOP=L2:L3=L2/L4:L6=L5/L7:BOTTOM=L7 |
| LED_R_12 | OTHERS | BUS | 8 | 4.75 | 5 | 10 | 5 | 14 | 6 | 9.5 | 12 | 12 | 12 | 12 |  | 50 Ohms | TOP=L2:L3=L2/L4:L6=L5/L7:BOTTOM=L7 |
| LED_R_13 | OTHERS | BUS | 1 | 4.75 | 5 | 10 | 5 | 14 | 6 | 9.5 | 12 | 12 | 12 | 12 |  | 50 Ohms | TOP=L2:L3=L2/L4:L6=L5/L7:BOTTOM=L7 |
| LED_R_13 | OTHERS | BUS | 2 | 5 | 5 | 10 | 5 | 14 | 6 | 10 | 12 | 12 | 12 | 12 |  | 50 Ohms | TOP=L2:L3=L2/L4:L6=L5/L7:BOTTOM=L7 |
| LED_R_13 | OTHERS | BUS | 3 | 5 | 5 | 10 | 5 | 14 | 6 | 10 | 12 | 12 | 12 | 12 |  | 50 Ohms | TOP=L2:L3=L2/L4:L6=L5/L7:BOTTOM=L7 |
| LED_R_13 | OTHERS | BUS | 4 | 5 | 5 | 10 | 5 | 14 | 6 | 10 | 12 | 12 | 12 | 12 |  | 50 Ohms | TOP=L2:L3=L2/L4:L6=L5/L7:BOTTOM=L7 |
| LED_R_13 | OTHERS | BUS | 5 | 5 | 5 | 10 | 5 | 14 | 6 | 10 | 12 | 12 | 12 | 12 |  | 50 Ohms | TOP=L2:L3=L2/L4:L6=L5/L7:BOTTOM=L7 |
| LED_R_13 | OTHERS | BUS | 6 | 5 | 5 | 10 | 5 | 14 | 6 | 10 | 12 | 12 | 12 | 12 |  | 50 Ohms | TOP=L2:L3=L2/L4:L6=L5/L7:BOTTOM=L7 |
| LED_R_13 | OTHERS | BUS | 7 | 5 | 5 | 10 | 5 | 14 | 6 | 10 | 12 | 12 | 12 | 12 |  | 50 Ohms | TOP=L2:L3=L2/L4:L6=L5/L7:BOTTOM=L7 |
| LED_R_13 | OTHERS | BUS | 8 | 4.75 | 5 | 10 | 5 | 14 | 6 | 9.5 | 12 | 12 | 12 | 12 |  | 50 Ohms | TOP=L2:L3=L2/L4:L6=L5/L7:BOTTOM=L7 |
| LED_R_14 | OTHERS | BUS | 1 | 4.75 | 5 | 10 | 5 | 14 | 6 | 9.5 | 12 | 12 | 12 | 12 |  | 50 Ohms | TOP=L2:L3=L2/L4:L6=L5/L7:BOTTOM=L7 |
| LED_R_14 | OTHERS | BUS | 2 | 5 | 5 | 10 | 5 | 14 | 6 | 10 | 12 | 12 | 12 | 12 |  | 50 Ohms | TOP=L2:L3=L2/L4:L6=L5/L7:BOTTOM=L7 |
| LED_R_14 | OTHERS | BUS | 3 | 5 | 5 | 10 | 5 | 14 | 6 | 10 | 12 | 12 | 12 | 12 |  | 50 Ohms | TOP=L2:L3=L2/L4:L6=L5/L7:BOTTOM=L7 |
| LED_R_14 | OTHERS | BUS | 4 | 5 | 5 | 10 | 5 | 14 | 6 | 10 | 12 | 12 | 12 | 12 |  | 50 Ohms | TOP=L2:L3=L2/L4:L6=L5/L7:BOTTOM=L7 |
| LED_R_14 | OTHERS | BUS | 5 | 5 | 5 | 10 | 5 | 14 | 6 | 10 | 12 | 12 | 12 | 12 |  | 50 Ohms | TOP=L2:L3=L2/L4:L6=L5/L7:BOTTOM=L7 |
| LED_R_14 | OTHERS | BUS | 6 | 5 | 5 | 10 | 5 | 14 | 6 | 10 | 12 | 12 | 12 | 12 |  | 50 Ohms | TOP=L2:L3=L2/L4:L6=L5/L7:BOTTOM=L7 |
| LED_R_14 | OTHERS | BUS | 7 | 5 | 5 | 10 | 5 | 14 | 6 | 10 | 12 | 12 | 12 | 12 |  | 50 Ohms | TOP=L2:L3=L2/L4:L6=L5/L7:BOTTOM=L7 |
| LED_R_14 | OTHERS | BUS | 8 | 4.75 | 5 | 10 | 5 | 14 | 6 | 9.5 | 12 | 12 | 12 | 12 |  | 50 Ohms | TOP=L2:L3=L2/L4:L6=L5/L7:BOTTOM=L7 |
| LED_R_2 | OTHERS | BUS | 1 | 4.75 | 5 | 10 | 5 | 14 | 6 | 9.5 | 12 | 12 | 12 | 12 |  | 50 Ohms | TOP=L2:L3=L2/L4:L6=L5/L7:BOTTOM=L7 |
| LED_R_2 | OTHERS | BUS | 2 | 5 | 5 | 10 | 5 | 14 | 6 | 10 | 12 | 12 | 12 | 12 |  | 50 Ohms | TOP=L2:L3=L2/L4:L6=L5/L7:BOTTOM=L7 |
| LED_R_2 | OTHERS | BUS | 3 | 5 | 5 | 10 | 5 | 14 | 6 | 10 | 12 | 12 | 12 | 12 |  | 50 Ohms | TOP=L2:L3=L2/L4:L6=L5/L7:BOTTOM=L7 |
| LED_R_2 | OTHERS | BUS | 4 | 5 | 5 | 10 | 5 | 14 | 6 | 10 | 12 | 12 | 12 | 12 |  | 50 Ohms | TOP=L2:L3=L2/L4:L6=L5/L7:BOTTOM=L7 |
| LED_R_2 | OTHERS | BUS | 5 | 5 | 5 | 10 | 5 | 14 | 6 | 10 | 12 | 12 | 12 | 12 |  | 50 Ohms | TOP=L2:L3=L2/L4:L6=L5/L7:BOTTOM=L7 |
| LED_R_2 | OTHERS | BUS | 6 | 5 | 5 | 10 | 5 | 14 | 6 | 10 | 12 | 12 | 12 | 12 |  | 50 Ohms | TOP=L2:L3=L2/L4:L6=L5/L7:BOTTOM=L7 |
| LED_R_2 | OTHERS | BUS | 7 | 5 | 5 | 10 | 5 | 14 | 6 | 10 | 12 | 12 | 12 | 12 |  | 50 Ohms | TOP=L2:L3=L2/L4:L6=L5/L7:BOTTOM=L7 |
| LED_R_2 | OTHERS | BUS | 8 | 4.75 | 5 | 10 | 5 | 14 | 6 | 9.5 | 12 | 12 | 12 | 12 |  | 50 Ohms | TOP=L2:L3=L2/L4:L6=L5/L7:BOTTOM=L7 |
| LED_R_3 | OTHERS | BUS | 1 | 4.75 | 5 | 10 | 5 | 14 | 6 | 9.5 | 12 | 12 | 12 | 12 |  | 50 Ohms | TOP=L2:L3=L2/L4:L6=L5/L7:BOTTOM=L7 |
| LED_R_3 | OTHERS | BUS | 2 | 5 | 5 | 10 | 5 | 14 | 6 | 10 | 12 | 12 | 12 | 12 |  | 50 Ohms | TOP=L2:L3=L2/L4:L6=L5/L7:BOTTOM=L7 |
| LED_R_3 | OTHERS | BUS | 3 | 5 | 5 | 10 | 5 | 14 | 6 | 10 | 12 | 12 | 12 | 12 |  | 50 Ohms | TOP=L2:L3=L2/L4:L6=L5/L7:BOTTOM=L7 |
| LED_R_3 | OTHERS | BUS | 4 | 5 | 5 | 10 | 5 | 14 | 6 | 10 | 12 | 12 | 12 | 12 |  | 50 Ohms | TOP=L2:L3=L2/L4:L6=L5/L7:BOTTOM=L7 |
| LED_R_3 | OTHERS | BUS | 5 | 5 | 5 | 10 | 5 | 14 | 6 | 10 | 12 | 12 | 12 | 12 |  | 50 Ohms | TOP=L2:L3=L2/L4:L6=L5/L7:BOTTOM=L7 |
| LED_R_3 | OTHERS | BUS | 6 | 5 | 5 | 10 | 5 | 14 | 6 | 10 | 12 | 12 | 12 | 12 |  | 50 Ohms | TOP=L2:L3=L2/L4:L6=L5/L7:BOTTOM=L7 |
| LED_R_3 | OTHERS | BUS | 7 | 5 | 5 | 10 | 5 | 14 | 6 | 10 | 12 | 12 | 12 | 12 |  | 50 Ohms | TOP=L2:L3=L2/L4:L6=L5/L7:BOTTOM=L7 |
| LED_R_3 | OTHERS | BUS | 8 | 4.75 | 5 | 10 | 5 | 14 | 6 | 9.5 | 12 | 12 | 12 | 12 |  | 50 Ohms | TOP=L2:L3=L2/L4:L6=L5/L7:BOTTOM=L7 |
| LED_R_4 | OTHERS | BUS | 1 | 4.75 | 5 | 10 | 5 | 14 | 6 | 9.5 | 12 | 12 | 12 | 12 |  | 50 Ohms | TOP=L2:L3=L2/L4:L6=L5/L7:BOTTOM=L7 |
| LED_R_4 | OTHERS | BUS | 2 | 5 | 5 | 10 | 5 | 14 | 6 | 10 | 12 | 12 | 12 | 12 |  | 50 Ohms | TOP=L2:L3=L2/L4:L6=L5/L7:BOTTOM=L7 |
| LED_R_4 | OTHERS | BUS | 3 | 5 | 5 | 10 | 5 | 14 | 6 | 10 | 12 | 12 | 12 | 12 |  | 50 Ohms | TOP=L2:L3=L2/L4:L6=L5/L7:BOTTOM=L7 |
| LED_R_4 | OTHERS | BUS | 4 | 5 | 5 | 10 | 5 | 14 | 6 | 10 | 12 | 12 | 12 | 12 |  | 50 Ohms | TOP=L2:L3=L2/L4:L6=L5/L7:BOTTOM=L7 |
| LED_R_4 | OTHERS | BUS | 5 | 5 | 5 | 10 | 5 | 14 | 6 | 10 | 12 | 12 | 12 | 12 |  | 50 Ohms | TOP=L2:L3=L2/L4:L6=L5/L7:BOTTOM=L7 |
| LED_R_4 | OTHERS | BUS | 6 | 5 | 5 | 10 | 5 | 14 | 6 | 10 | 12 | 12 | 12 | 12 |  | 50 Ohms | TOP=L2:L3=L2/L4:L6=L5/L7:BOTTOM=L7 |
| LED_R_4 | OTHERS | BUS | 7 | 5 | 5 | 10 | 5 | 14 | 6 | 10 | 12 | 12 | 12 | 12 |  | 50 Ohms | TOP=L2:L3=L2/L4:L6=L5/L7:BOTTOM=L7 |
| LED_R_4 | OTHERS | BUS | 8 | 4.75 | 5 | 10 | 5 | 14 | 6 | 9.5 | 12 | 12 | 12 | 12 |  | 50 Ohms | TOP=L2:L3=L2/L4:L6=L5/L7:BOTTOM=L7 |
| LED_R_5 | OTHERS | BUS | 1 | 4.75 | 5 | 10 | 5 | 14 | 6 | 9.5 | 12 | 12 | 12 | 12 |  | 50 Ohms | TOP=L2:L3=L2/L4:L6=L5/L7:BOTTOM=L7 |
| LED_R_5 | OTHERS | BUS | 2 | 5 | 5 | 10 | 5 | 14 | 6 | 10 | 12 | 12 | 12 | 12 |  | 50 Ohms | TOP=L2:L3=L2/L4:L6=L5/L7:BOTTOM=L7 |
| LED_R_5 | OTHERS | BUS | 3 | 5 | 5 | 10 | 5 | 14 | 6 | 10 | 12 | 12 | 12 | 12 |  | 50 Ohms | TOP=L2:L3=L2/L4:L6=L5/L7:BOTTOM=L7 |
| LED_R_5 | OTHERS | BUS | 4 | 5 | 5 | 10 | 5 | 14 | 6 | 10 | 12 | 12 | 12 | 12 |  | 50 Ohms | TOP=L2:L3=L2/L4:L6=L5/L7:BOTTOM=L7 |
| LED_R_5 | OTHERS | BUS | 5 | 5 | 5 | 10 | 5 | 14 | 6 | 10 | 12 | 12 | 12 | 12 |  | 50 Ohms | TOP=L2:L3=L2/L4:L6=L5/L7:BOTTOM=L7 |
| LED_R_5 | OTHERS | BUS | 6 | 5 | 5 | 10 | 5 | 14 | 6 | 10 | 12 | 12 | 12 | 12 |  | 50 Ohms | TOP=L2:L3=L2/L4:L6=L5/L7:BOTTOM=L7 |
| LED_R_5 | OTHERS | BUS | 7 | 5 | 5 | 10 | 5 | 14 | 6 | 10 | 12 | 12 | 12 | 12 |  | 50 Ohms | TOP=L2:L3=L2/L4:L6=L5/L7:BOTTOM=L7 |
| LED_R_5 | OTHERS | BUS | 8 | 4.75 | 5 | 10 | 5 | 14 | 6 | 9.5 | 12 | 12 | 12 | 12 |  | 50 Ohms | TOP=L2:L3=L2/L4:L6=L5/L7:BOTTOM=L7 |
| LED_R_6 | OTHERS | BUS | 1 | 4.75 | 5 | 10 | 5 | 14 | 6 | 9.5 | 12 | 12 | 12 | 12 |  | 50 Ohms | TOP=L2:L3=L2/L4:L6=L5/L7:BOTTOM=L7 |
| LED_R_6 | OTHERS | BUS | 2 | 5 | 5 | 10 | 5 | 14 | 6 | 10 | 12 | 12 | 12 | 12 |  | 50 Ohms | TOP=L2:L3=L2/L4:L6=L5/L7:BOTTOM=L7 |
| LED_R_6 | OTHERS | BUS | 3 | 5 | 5 | 10 | 5 | 14 | 6 | 10 | 12 | 12 | 12 | 12 |  | 50 Ohms | TOP=L2:L3=L2/L4:L6=L5/L7:BOTTOM=L7 |
| LED_R_6 | OTHERS | BUS | 4 | 5 | 5 | 10 | 5 | 14 | 6 | 10 | 12 | 12 | 12 | 12 |  | 50 Ohms | TOP=L2:L3=L2/L4:L6=L5/L7:BOTTOM=L7 |
| LED_R_6 | OTHERS | BUS | 5 | 5 | 5 | 10 | 5 | 14 | 6 | 10 | 12 | 12 | 12 | 12 |  | 50 Ohms | TOP=L2:L3=L2/L4:L6=L5/L7:BOTTOM=L7 |
| LED_R_6 | OTHERS | BUS | 6 | 5 | 5 | 10 | 5 | 14 | 6 | 10 | 12 | 12 | 12 | 12 |  | 50 Ohms | TOP=L2:L3=L2/L4:L6=L5/L7:BOTTOM=L7 |
| LED_R_6 | OTHERS | BUS | 7 | 5 | 5 | 10 | 5 | 14 | 6 | 10 | 12 | 12 | 12 | 12 |  | 50 Ohms | TOP=L2:L3=L2/L4:L6=L5/L7:BOTTOM=L7 |
| LED_R_6 | OTHERS | BUS | 8 | 4.75 | 5 | 10 | 5 | 14 | 6 | 9.5 | 12 | 12 | 12 | 12 |  | 50 Ohms | TOP=L2:L3=L2/L4:L6=L5/L7:BOTTOM=L7 |
| LED_R_7 | OTHERS | BUS | 1 | 4.75 | 5 | 10 | 5 | 14 | 6 | 9.5 | 12 | 12 | 12 | 12 |  | 50 Ohms | TOP=L2:L3=L2/L4:L6=L5/L7:BOTTOM=L7 |
| LED_R_7 | OTHERS | BUS | 2 | 5 | 5 | 10 | 5 | 14 | 6 | 10 | 12 | 12 | 12 | 12 |  | 50 Ohms | TOP=L2:L3=L2/L4:L6=L5/L7:BOTTOM=L7 |
| LED_R_7 | OTHERS | BUS | 3 | 5 | 5 | 10 | 5 | 14 | 6 | 10 | 12 | 12 | 12 | 12 |  | 50 Ohms | TOP=L2:L3=L2/L4:L6=L5/L7:BOTTOM=L7 |
| LED_R_7 | OTHERS | BUS | 4 | 5 | 5 | 10 | 5 | 14 | 6 | 10 | 12 | 12 | 12 | 12 |  | 50 Ohms | TOP=L2:L3=L2/L4:L6=L5/L7:BOTTOM=L7 |
| LED_R_7 | OTHERS | BUS | 5 | 5 | 5 | 10 | 5 | 14 | 6 | 10 | 12 | 12 | 12 | 12 |  | 50 Ohms | TOP=L2:L3=L2/L4:L6=L5/L7:BOTTOM=L7 |
| LED_R_7 | OTHERS | BUS | 6 | 5 | 5 | 10 | 5 | 14 | 6 | 10 | 12 | 12 | 12 | 12 |  | 50 Ohms | TOP=L2:L3=L2/L4:L6=L5/L7:BOTTOM=L7 |
| LED_R_7 | OTHERS | BUS | 7 | 5 | 5 | 10 | 5 | 14 | 6 | 10 | 12 | 12 | 12 | 12 |  | 50 Ohms | TOP=L2:L3=L2/L4:L6=L5/L7:BOTTOM=L7 |
| LED_R_7 | OTHERS | BUS | 8 | 4.75 | 5 | 10 | 5 | 14 | 6 | 9.5 | 12 | 12 | 12 | 12 |  | 50 Ohms | TOP=L2:L3=L2/L4:L6=L5/L7:BOTTOM=L7 |
| LED_R_8 | OTHERS | BUS | 1 | 4.75 | 5 | 10 | 5 | 14 | 6 | 9.5 | 12 | 12 | 12 | 12 |  | 50 Ohms | TOP=L2:L3=L2/L4:L6=L5/L7:BOTTOM=L7 |
| LED_R_8 | OTHERS | BUS | 2 | 5 | 5 | 10 | 5 | 14 | 6 | 10 | 12 | 12 | 12 | 12 |  | 50 Ohms | TOP=L2:L3=L2/L4:L6=L5/L7:BOTTOM=L7 |
| LED_R_8 | OTHERS | BUS | 3 | 5 | 5 | 10 | 5 | 14 | 6 | 10 | 12 | 12 | 12 | 12 |  | 50 Ohms | TOP=L2:L3=L2/L4:L6=L5/L7:BOTTOM=L7 |
| LED_R_8 | OTHERS | BUS | 4 | 5 | 5 | 10 | 5 | 14 | 6 | 10 | 12 | 12 | 12 | 12 |  | 50 Ohms | TOP=L2:L3=L2/L4:L6=L5/L7:BOTTOM=L7 |
| LED_R_8 | OTHERS | BUS | 5 | 5 | 5 | 10 | 5 | 14 | 6 | 10 | 12 | 12 | 12 | 12 |  | 50 Ohms | TOP=L2:L3=L2/L4:L6=L5/L7:BOTTOM=L7 |
| LED_R_8 | OTHERS | BUS | 6 | 5 | 5 | 10 | 5 | 14 | 6 | 10 | 12 | 12 | 12 | 12 |  | 50 Ohms | TOP=L2:L3=L2/L4:L6=L5/L7:BOTTOM=L7 |
| LED_R_8 | OTHERS | BUS | 7 | 5 | 5 | 10 | 5 | 14 | 6 | 10 | 12 | 12 | 12 | 12 |  | 50 Ohms | TOP=L2:L3=L2/L4:L6=L5/L7:BOTTOM=L7 |
| LED_R_8 | OTHERS | BUS | 8 | 4.75 | 5 | 10 | 5 | 14 | 6 | 9.5 | 12 | 12 | 12 | 12 |  | 50 Ohms | TOP=L2:L3=L2/L4:L6=L5/L7:BOTTOM=L7 |
| LED_R_9 | OTHERS | BUS | 1 | 4.75 | 5 | 10 | 5 | 14 | 6 | 9.5 | 12 | 12 | 12 | 12 |  | 50 Ohms | TOP=L2:L3=L2/L4:L6=L5/L7:BOTTOM=L7 |
| LED_R_9 | OTHERS | BUS | 2 | 5 | 5 | 10 | 5 | 14 | 6 | 10 | 12 | 12 | 12 | 12 |  | 50 Ohms | TOP=L2:L3=L2/L4:L6=L5/L7:BOTTOM=L7 |
| LED_R_9 | OTHERS | BUS | 3 | 5 | 5 | 10 | 5 | 14 | 6 | 10 | 12 | 12 | 12 | 12 |  | 50 Ohms | TOP=L2:L3=L2/L4:L6=L5/L7:BOTTOM=L7 |
| LED_R_9 | OTHERS | BUS | 4 | 5 | 5 | 10 | 5 | 14 | 6 | 10 | 12 | 12 | 12 | 12 |  | 50 Ohms | TOP=L2:L3=L2/L4:L6=L5/L7:BOTTOM=L7 |
| LED_R_9 | OTHERS | BUS | 5 | 5 | 5 | 10 | 5 | 14 | 6 | 10 | 12 | 12 | 12 | 12 |  | 50 Ohms | TOP=L2:L3=L2/L4:L6=L5/L7:BOTTOM=L7 |
| LED_R_9 | OTHERS | BUS | 6 | 5 | 5 | 10 | 5 | 14 | 6 | 10 | 12 | 12 | 12 | 12 |  | 50 Ohms | TOP=L2:L3=L2/L4:L6=L5/L7:BOTTOM=L7 |
| LED_R_9 | OTHERS | BUS | 7 | 5 | 5 | 10 | 5 | 14 | 6 | 10 | 12 | 12 | 12 | 12 |  | 50 Ohms | TOP=L2:L3=L2/L4:L6=L5/L7:BOTTOM=L7 |
| LED_R_9 | OTHERS | BUS | 8 | 4.75 | 5 | 10 | 5 | 14 | 6 | 9.5 | 12 | 12 | 12 | 12 |  | 50 Ohms | TOP=L2:L3=L2/L4:L6=L5/L7:BOTTOM=L7 |
| LINK | OTHERS | BUS | 1 | 4.75 | 5 | 10 | 5 | 14 | 6 | 9.5 | 12 | 12 | 12 | 12 |  | 50 Ohms | TOP=L2:L3=L2/L4:L6=L5/L7:BOTTOM=L7 |
| LINK | OTHERS | BUS | 2 | 5 | 5 | 10 | 5 | 14 | 6 | 10 | 12 | 12 | 12 | 12 |  | 50 Ohms | TOP=L2:L3=L2/L4:L6=L5/L7:BOTTOM=L7 |
| LINK | OTHERS | BUS | 3 | 5 | 5 | 10 | 5 | 14 | 6 | 10 | 12 | 12 | 12 | 12 |  | 50 Ohms | TOP=L2:L3=L2/L4:L6=L5/L7:BOTTOM=L7 |
| LINK | OTHERS | BUS | 4 | 5 | 5 | 10 | 5 | 14 | 6 | 10 | 12 | 12 | 12 | 12 |  | 50 Ohms | TOP=L2:L3=L2/L4:L6=L5/L7:BOTTOM=L7 |
| LINK | OTHERS | BUS | 5 | 5 | 5 | 10 | 5 | 14 | 6 | 10 | 12 | 12 | 12 | 12 |  | 50 Ohms | TOP=L2:L3=L2/L4:L6=L5/L7:BOTTOM=L7 |
| LINK | OTHERS | BUS | 6 | 5 | 5 | 10 | 5 | 14 | 6 | 10 | 12 | 12 | 12 | 12 |  | 50 Ohms | TOP=L2:L3=L2/L4:L6=L5/L7:BOTTOM=L7 |
| LINK | OTHERS | BUS | 7 | 5 | 5 | 10 | 5 | 14 | 6 | 10 | 12 | 12 | 12 | 12 |  | 50 Ohms | TOP=L2:L3=L2/L4:L6=L5/L7:BOTTOM=L7 |
| LINK | OTHERS | BUS | 8 | 4.75 | 5 | 10 | 5 | 14 | 6 | 9.5 | 12 | 12 | 12 | 12 |  | 50 Ohms | TOP=L2:L3=L2/L4:L6=L5/L7:BOTTOM=L7 |
| LOW_HEX_0 | OTHERS | BUS | 1 | 4.75 | 5 | 10 | 5 | 14 | 6 | 9.5 | 12 | 12 | 12 | 12 |  | 50 Ohms | TOP=L2:L3=L2/L4:L6=L5/L7:BOTTOM=L7 |
| LOW_HEX_0 | OTHERS | BUS | 2 | 5 | 5 | 10 | 5 | 14 | 6 | 10 | 12 | 12 | 12 | 12 |  | 50 Ohms | TOP=L2:L3=L2/L4:L6=L5/L7:BOTTOM=L7 |
| LOW_HEX_0 | OTHERS | BUS | 3 | 5 | 5 | 10 | 5 | 14 | 6 | 10 | 12 | 12 | 12 | 12 |  | 50 Ohms | TOP=L2:L3=L2/L4:L6=L5/L7:BOTTOM=L7 |
| LOW_HEX_0 | OTHERS | BUS | 4 | 5 | 5 | 10 | 5 | 14 | 6 | 10 | 12 | 12 | 12 | 12 |  | 50 Ohms | TOP=L2:L3=L2/L4:L6=L5/L7:BOTTOM=L7 |
| LOW_HEX_0 | OTHERS | BUS | 5 | 5 | 5 | 10 | 5 | 14 | 6 | 10 | 12 | 12 | 12 | 12 |  | 50 Ohms | TOP=L2:L3=L2/L4:L6=L5/L7:BOTTOM=L7 |
| LOW_HEX_0 | OTHERS | BUS | 6 | 5 | 5 | 10 | 5 | 14 | 6 | 10 | 12 | 12 | 12 | 12 |  | 50 Ohms | TOP=L2:L3=L2/L4:L6=L5/L7:BOTTOM=L7 |
| LOW_HEX_0 | OTHERS | BUS | 7 | 5 | 5 | 10 | 5 | 14 | 6 | 10 | 12 | 12 | 12 | 12 |  | 50 Ohms | TOP=L2:L3=L2/L4:L6=L5/L7:BOTTOM=L7 |
| LOW_HEX_0 | OTHERS | BUS | 8 | 4.75 | 5 | 10 | 5 | 14 | 6 | 9.5 | 12 | 12 | 12 | 12 |  | 50 Ohms | TOP=L2:L3=L2/L4:L6=L5/L7:BOTTOM=L7 |
| LOW_HEX_1 | OTHERS | BUS | 1 | 4.75 | 5 | 10 | 5 | 14 | 6 | 9.5 | 12 | 12 | 12 | 12 |  | 50 Ohms | TOP=L2:L3=L2/L4:L6=L5/L7:BOTTOM=L7 |
| LOW_HEX_1 | OTHERS | BUS | 2 | 5 | 5 | 10 | 5 | 14 | 6 | 10 | 12 | 12 | 12 | 12 |  | 50 Ohms | TOP=L2:L3=L2/L4:L6=L5/L7:BOTTOM=L7 |
| LOW_HEX_1 | OTHERS | BUS | 3 | 5 | 5 | 10 | 5 | 14 | 6 | 10 | 12 | 12 | 12 | 12 |  | 50 Ohms | TOP=L2:L3=L2/L4:L6=L5/L7:BOTTOM=L7 |
| LOW_HEX_1 | OTHERS | BUS | 4 | 5 | 5 | 10 | 5 | 14 | 6 | 10 | 12 | 12 | 12 | 12 |  | 50 Ohms | TOP=L2:L3=L2/L4:L6=L5/L7:BOTTOM=L7 |
| LOW_HEX_1 | OTHERS | BUS | 5 | 5 | 5 | 10 | 5 | 14 | 6 | 10 | 12 | 12 | 12 | 12 |  | 50 Ohms | TOP=L2:L3=L2/L4:L6=L5/L7:BOTTOM=L7 |
| LOW_HEX_1 | OTHERS | BUS | 6 | 5 | 5 | 10 | 5 | 14 | 6 | 10 | 12 | 12 | 12 | 12 |  | 50 Ohms | TOP=L2:L3=L2/L4:L6=L5/L7:BOTTOM=L7 |
| LOW_HEX_1 | OTHERS | BUS | 7 | 5 | 5 | 10 | 5 | 14 | 6 | 10 | 12 | 12 | 12 | 12 |  | 50 Ohms | TOP=L2:L3=L2/L4:L6=L5/L7:BOTTOM=L7 |
| LOW_HEX_1 | OTHERS | BUS | 8 | 4.75 | 5 | 10 | 5 | 14 | 6 | 9.5 | 12 | 12 | 12 | 12 |  | 50 Ohms | TOP=L2:L3=L2/L4:L6=L5/L7:BOTTOM=L7 |
| LOW_HEX_2 | OTHERS | BUS | 1 | 4.75 | 5 | 10 | 5 | 14 | 6 | 9.5 | 12 | 12 | 12 | 12 |  | 50 Ohms | TOP=L2:L3=L2/L4:L6=L5/L7:BOTTOM=L7 |
| LOW_HEX_2 | OTHERS | BUS | 2 | 5 | 5 | 10 | 5 | 14 | 6 | 10 | 12 | 12 | 12 | 12 |  | 50 Ohms | TOP=L2:L3=L2/L4:L6=L5/L7:BOTTOM=L7 |
| LOW_HEX_2 | OTHERS | BUS | 3 | 5 | 5 | 10 | 5 | 14 | 6 | 10 | 12 | 12 | 12 | 12 |  | 50 Ohms | TOP=L2:L3=L2/L4:L6=L5/L7:BOTTOM=L7 |
| LOW_HEX_2 | OTHERS | BUS | 4 | 5 | 5 | 10 | 5 | 14 | 6 | 10 | 12 | 12 | 12 | 12 |  | 50 Ohms | TOP=L2:L3=L2/L4:L6=L5/L7:BOTTOM=L7 |
| LOW_HEX_2 | OTHERS | BUS | 5 | 5 | 5 | 10 | 5 | 14 | 6 | 10 | 12 | 12 | 12 | 12 |  | 50 Ohms | TOP=L2:L3=L2/L4:L6=L5/L7:BOTTOM=L7 |
| LOW_HEX_2 | OTHERS | BUS | 6 | 5 | 5 | 10 | 5 | 14 | 6 | 10 | 12 | 12 | 12 | 12 |  | 50 Ohms | TOP=L2:L3=L2/L4:L6=L5/L7:BOTTOM=L7 |
| LOW_HEX_2 | OTHERS | BUS | 7 | 5 | 5 | 10 | 5 | 14 | 6 | 10 | 12 | 12 | 12 | 12 |  | 50 Ohms | TOP=L2:L3=L2/L4:L6=L5/L7:BOTTOM=L7 |
| LOW_HEX_2 | OTHERS | BUS | 8 | 4.75 | 5 | 10 | 5 | 14 | 6 | 9.5 | 12 | 12 | 12 | 12 |  | 50 Ohms | TOP=L2:L3=L2/L4:L6=L5/L7:BOTTOM=L7 |
| LOW_HEX_3 | OTHERS | BUS | 1 | 4.75 | 5 | 10 | 5 | 14 | 6 | 9.5 | 12 | 12 | 12 | 12 |  | 50 Ohms | TOP=L2:L3=L2/L4:L6=L5/L7:BOTTOM=L7 |
| LOW_HEX_3 | OTHERS | BUS | 2 | 5 | 5 | 10 | 5 | 14 | 6 | 10 | 12 | 12 | 12 | 12 |  | 50 Ohms | TOP=L2:L3=L2/L4:L6=L5/L7:BOTTOM=L7 |
| LOW_HEX_3 | OTHERS | BUS | 3 | 5 | 5 | 10 | 5 | 14 | 6 | 10 | 12 | 12 | 12 | 12 |  | 50 Ohms | TOP=L2:L3=L2/L4:L6=L5/L7:BOTTOM=L7 |
| LOW_HEX_3 | OTHERS | BUS | 4 | 5 | 5 | 10 | 5 | 14 | 6 | 10 | 12 | 12 | 12 | 12 |  | 50 Ohms | TOP=L2:L3=L2/L4:L6=L5/L7:BOTTOM=L7 |
| LOW_HEX_3 | OTHERS | BUS | 5 | 5 | 5 | 10 | 5 | 14 | 6 | 10 | 12 | 12 | 12 | 12 |  | 50 Ohms | TOP=L2:L3=L2/L4:L6=L5/L7:BOTTOM=L7 |
| LOW_HEX_3 | OTHERS | BUS | 6 | 5 | 5 | 10 | 5 | 14 | 6 | 10 | 12 | 12 | 12 | 12 |  | 50 Ohms | TOP=L2:L3=L2/L4:L6=L5/L7:BOTTOM=L7 |
| LOW_HEX_3 | OTHERS | BUS | 7 | 5 | 5 | 10 | 5 | 14 | 6 | 10 | 12 | 12 | 12 | 12 |  | 50 Ohms | TOP=L2:L3=L2/L4:L6=L5/L7:BOTTOM=L7 |
| LOW_HEX_3 | OTHERS | BUS | 8 | 4.75 | 5 | 10 | 5 | 14 | 6 | 9.5 | 12 | 12 | 12 | 12 |  | 50 Ohms | TOP=L2:L3=L2/L4:L6=L5/L7:BOTTOM=L7 |
| MATED_P12V_EN | OTHERS | BUS | 1 | 4.75 | 5 | 10 | 5 | 14 | 6 | 9.5 | 12 | 12 | 12 | 12 |  | 50 Ohms | TOP=L2:L3=L2/L4:L6=L5/L7:BOTTOM=L7 |
| MATED_P12V_EN | OTHERS | BUS | 2 | 5 | 5 | 10 | 5 | 14 | 6 | 10 | 12 | 12 | 12 | 12 |  | 50 Ohms | TOP=L2:L3=L2/L4:L6=L5/L7:BOTTOM=L7 |
| MATED_P12V_EN | OTHERS | BUS | 3 | 5 | 5 | 10 | 5 | 14 | 6 | 10 | 12 | 12 | 12 | 12 |  | 50 Ohms | TOP=L2:L3=L2/L4:L6=L5/L7:BOTTOM=L7 |
| MATED_P12V_EN | OTHERS | BUS | 4 | 5 | 5 | 10 | 5 | 14 | 6 | 10 | 12 | 12 | 12 | 12 |  | 50 Ohms | TOP=L2:L3=L2/L4:L6=L5/L7:BOTTOM=L7 |
| MATED_P12V_EN | OTHERS | BUS | 5 | 5 | 5 | 10 | 5 | 14 | 6 | 10 | 12 | 12 | 12 | 12 |  | 50 Ohms | TOP=L2:L3=L2/L4:L6=L5/L7:BOTTOM=L7 |
| MATED_P12V_EN | OTHERS | BUS | 6 | 5 | 5 | 10 | 5 | 14 | 6 | 10 | 12 | 12 | 12 | 12 |  | 50 Ohms | TOP=L2:L3=L2/L4:L6=L5/L7:BOTTOM=L7 |
| MATED_P12V_EN | OTHERS | BUS | 7 | 5 | 5 | 10 | 5 | 14 | 6 | 10 | 12 | 12 | 12 | 12 |  | 50 Ohms | TOP=L2:L3=L2/L4:L6=L5/L7:BOTTOM=L7 |
| MATED_P12V_EN | OTHERS | BUS | 8 | 4.75 | 5 | 10 | 5 | 14 | 6 | 9.5 | 12 | 12 | 12 | 12 |  | 50 Ohms | TOP=L2:L3=L2/L4:L6=L5/L7:BOTTOM=L7 |
| MAX6654_ADD0 | OTHERS | BUS | 1 | 4.75 | 5 | 10 | 5 | 14 | 6 | 9.5 | 12 | 12 | 12 | 12 |  | 50 Ohms | TOP=L2:L3=L2/L4:L6=L5/L7:BOTTOM=L7 |
| MAX6654_ADD0 | OTHERS | BUS | 2 | 5 | 5 | 10 | 5 | 14 | 6 | 10 | 12 | 12 | 12 | 12 |  | 50 Ohms | TOP=L2:L3=L2/L4:L6=L5/L7:BOTTOM=L7 |
| MAX6654_ADD0 | OTHERS | BUS | 3 | 5 | 5 | 10 | 5 | 14 | 6 | 10 | 12 | 12 | 12 | 12 |  | 50 Ohms | TOP=L2:L3=L2/L4:L6=L5/L7:BOTTOM=L7 |
| MAX6654_ADD0 | OTHERS | BUS | 4 | 5 | 5 | 10 | 5 | 14 | 6 | 10 | 12 | 12 | 12 | 12 |  | 50 Ohms | TOP=L2:L3=L2/L4:L6=L5/L7:BOTTOM=L7 |
| MAX6654_ADD0 | OTHERS | BUS | 5 | 5 | 5 | 10 | 5 | 14 | 6 | 10 | 12 | 12 | 12 | 12 |  | 50 Ohms | TOP=L2:L3=L2/L4:L6=L5/L7:BOTTOM=L7 |
| MAX6654_ADD0 | OTHERS | BUS | 6 | 5 | 5 | 10 | 5 | 14 | 6 | 10 | 12 | 12 | 12 | 12 |  | 50 Ohms | TOP=L2:L3=L2/L4:L6=L5/L7:BOTTOM=L7 |
| MAX6654_ADD0 | OTHERS | BUS | 7 | 5 | 5 | 10 | 5 | 14 | 6 | 10 | 12 | 12 | 12 | 12 |  | 50 Ohms | TOP=L2:L3=L2/L4:L6=L5/L7:BOTTOM=L7 |
| MAX6654_ADD0 | OTHERS | BUS | 8 | 4.75 | 5 | 10 | 5 | 14 | 6 | 9.5 | 12 | 12 | 12 | 12 |  | 50 Ohms | TOP=L2:L3=L2/L4:L6=L5/L7:BOTTOM=L7 |
| MAX6654_ADD1 | OTHERS | BUS | 1 | 4.75 | 5 | 10 | 5 | 14 | 6 | 9.5 | 12 | 12 | 12 | 12 |  | 50 Ohms | TOP=L2:L3=L2/L4:L6=L5/L7:BOTTOM=L7 |
| MAX6654_ADD1 | OTHERS | BUS | 2 | 5 | 5 | 10 | 5 | 14 | 6 | 10 | 12 | 12 | 12 | 12 |  | 50 Ohms | TOP=L2:L3=L2/L4:L6=L5/L7:BOTTOM=L7 |
| MAX6654_ADD1 | OTHERS | BUS | 3 | 5 | 5 | 10 | 5 | 14 | 6 | 10 | 12 | 12 | 12 | 12 |  | 50 Ohms | TOP=L2:L3=L2/L4:L6=L5/L7:BOTTOM=L7 |
| MAX6654_ADD1 | OTHERS | BUS | 4 | 5 | 5 | 10 | 5 | 14 | 6 | 10 | 12 | 12 | 12 | 12 |  | 50 Ohms | TOP=L2:L3=L2/L4:L6=L5/L7:BOTTOM=L7 |
| MAX6654_ADD1 | OTHERS | BUS | 5 | 5 | 5 | 10 | 5 | 14 | 6 | 10 | 12 | 12 | 12 | 12 |  | 50 Ohms | TOP=L2:L3=L2/L4:L6=L5/L7:BOTTOM=L7 |
| MAX6654_ADD1 | OTHERS | BUS | 6 | 5 | 5 | 10 | 5 | 14 | 6 | 10 | 12 | 12 | 12 | 12 |  | 50 Ohms | TOP=L2:L3=L2/L4:L6=L5/L7:BOTTOM=L7 |
| MAX6654_ADD1 | OTHERS | BUS | 7 | 5 | 5 | 10 | 5 | 14 | 6 | 10 | 12 | 12 | 12 | 12 |  | 50 Ohms | TOP=L2:L3=L2/L4:L6=L5/L7:BOTTOM=L7 |
| MAX6654_ADD1 | OTHERS | BUS | 8 | 4.75 | 5 | 10 | 5 | 14 | 6 | 9.5 | 12 | 12 | 12 | 12 |  | 50 Ohms | TOP=L2:L3=L2/L4:L6=L5/L7:BOTTOM=L7 |
| MAX6654_ALERT# | OTHERS | BUS | 1 | 4.75 | 5 | 10 | 5 | 14 | 6 | 9.5 | 12 | 12 | 12 | 12 |  | 50 Ohms | TOP=L2:L3=L2/L4:L6=L5/L7:BOTTOM=L7 |
| MAX6654_ALERT# | OTHERS | BUS | 2 | 5 | 5 | 10 | 5 | 14 | 6 | 10 | 12 | 12 | 12 | 12 |  | 50 Ohms | TOP=L2:L3=L2/L4:L6=L5/L7:BOTTOM=L7 |
| MAX6654_ALERT# | OTHERS | BUS | 3 | 5 | 5 | 10 | 5 | 14 | 6 | 10 | 12 | 12 | 12 | 12 |  | 50 Ohms | TOP=L2:L3=L2/L4:L6=L5/L7:BOTTOM=L7 |
| MAX6654_ALERT# | OTHERS | BUS | 4 | 5 | 5 | 10 | 5 | 14 | 6 | 10 | 12 | 12 | 12 | 12 |  | 50 Ohms | TOP=L2:L3=L2/L4:L6=L5/L7:BOTTOM=L7 |
| MAX6654_ALERT# | OTHERS | BUS | 5 | 5 | 5 | 10 | 5 | 14 | 6 | 10 | 12 | 12 | 12 | 12 |  | 50 Ohms | TOP=L2:L3=L2/L4:L6=L5/L7:BOTTOM=L7 |
| MAX6654_ALERT# | OTHERS | BUS | 6 | 5 | 5 | 10 | 5 | 14 | 6 | 10 | 12 | 12 | 12 | 12 |  | 50 Ohms | TOP=L2:L3=L2/L4:L6=L5/L7:BOTTOM=L7 |
| MAX6654_ALERT# | OTHERS | BUS | 7 | 5 | 5 | 10 | 5 | 14 | 6 | 10 | 12 | 12 | 12 | 12 |  | 50 Ohms | TOP=L2:L3=L2/L4:L6=L5/L7:BOTTOM=L7 |
| MAX6654_ALERT# | OTHERS | BUS | 8 | 4.75 | 5 | 10 | 5 | 14 | 6 | 9.5 | 12 | 12 | 12 | 12 |  | 50 Ohms | TOP=L2:L3=L2/L4:L6=L5/L7:BOTTOM=L7 |
| MAX7311_TP301 | OTHERS | BUS | 1 | 4.75 | 5 | 10 | 5 | 14 | 6 | 9.5 | 12 | 12 | 12 | 12 |  | 50 Ohms | TOP=L2:L3=L2/L4:L6=L5/L7:BOTTOM=L7 |
| MAX7311_TP301 | OTHERS | BUS | 2 | 5 | 5 | 10 | 5 | 14 | 6 | 10 | 12 | 12 | 12 | 12 |  | 50 Ohms | TOP=L2:L3=L2/L4:L6=L5/L7:BOTTOM=L7 |
| MAX7311_TP301 | OTHERS | BUS | 3 | 5 | 5 | 10 | 5 | 14 | 6 | 10 | 12 | 12 | 12 | 12 |  | 50 Ohms | TOP=L2:L3=L2/L4:L6=L5/L7:BOTTOM=L7 |
| MAX7311_TP301 | OTHERS | BUS | 4 | 5 | 5 | 10 | 5 | 14 | 6 | 10 | 12 | 12 | 12 | 12 |  | 50 Ohms | TOP=L2:L3=L2/L4:L6=L5/L7:BOTTOM=L7 |
| MAX7311_TP301 | OTHERS | BUS | 5 | 5 | 5 | 10 | 5 | 14 | 6 | 10 | 12 | 12 | 12 | 12 |  | 50 Ohms | TOP=L2:L3=L2/L4:L6=L5/L7:BOTTOM=L7 |
| MAX7311_TP301 | OTHERS | BUS | 6 | 5 | 5 | 10 | 5 | 14 | 6 | 10 | 12 | 12 | 12 | 12 |  | 50 Ohms | TOP=L2:L3=L2/L4:L6=L5/L7:BOTTOM=L7 |
| MAX7311_TP301 | OTHERS | BUS | 7 | 5 | 5 | 10 | 5 | 14 | 6 | 10 | 12 | 12 | 12 | 12 |  | 50 Ohms | TOP=L2:L3=L2/L4:L6=L5/L7:BOTTOM=L7 |
| MAX7311_TP301 | OTHERS | BUS | 8 | 4.75 | 5 | 10 | 5 | 14 | 6 | 9.5 | 12 | 12 | 12 | 12 |  | 50 Ohms | TOP=L2:L3=L2/L4:L6=L5/L7:BOTTOM=L7 |
| MB0_12V_CTRL_GATE1 | OTHERS | BUS | 1 | 4.75 | 5 | 10 | 5 | 14 | 6 | 9.5 | 12 | 12 | 12 | 12 |  | 50 Ohms | TOP=L2:L3=L2/L4:L6=L5/L7:BOTTOM=L7 |
| MB0_12V_CTRL_GATE1 | OTHERS | BUS | 2 | 5 | 5 | 10 | 5 | 14 | 6 | 10 | 12 | 12 | 12 | 12 |  | 50 Ohms | TOP=L2:L3=L2/L4:L6=L5/L7:BOTTOM=L7 |
| MB0_12V_CTRL_GATE1 | OTHERS | BUS | 3 | 5 | 5 | 10 | 5 | 14 | 6 | 10 | 12 | 12 | 12 | 12 |  | 50 Ohms | TOP=L2:L3=L2/L4:L6=L5/L7:BOTTOM=L7 |
| MB0_12V_CTRL_GATE1 | OTHERS | BUS | 4 | 5 | 5 | 10 | 5 | 14 | 6 | 10 | 12 | 12 | 12 | 12 |  | 50 Ohms | TOP=L2:L3=L2/L4:L6=L5/L7:BOTTOM=L7 |
| MB0_12V_CTRL_GATE1 | OTHERS | BUS | 5 | 5 | 5 | 10 | 5 | 14 | 6 | 10 | 12 | 12 | 12 | 12 |  | 50 Ohms | TOP=L2:L3=L2/L4:L6=L5/L7:BOTTOM=L7 |
| MB0_12V_CTRL_GATE1 | OTHERS | BUS | 6 | 5 | 5 | 10 | 5 | 14 | 6 | 10 | 12 | 12 | 12 | 12 |  | 50 Ohms | TOP=L2:L3=L2/L4:L6=L5/L7:BOTTOM=L7 |
| MB0_12V_CTRL_GATE1 | OTHERS | BUS | 7 | 5 | 5 | 10 | 5 | 14 | 6 | 10 | 12 | 12 | 12 | 12 |  | 50 Ohms | TOP=L2:L3=L2/L4:L6=L5/L7:BOTTOM=L7 |
| MB0_12V_CTRL_GATE1 | OTHERS | BUS | 8 | 4.75 | 5 | 10 | 5 | 14 | 6 | 9.5 | 12 | 12 | 12 | 12 |  | 50 Ohms | TOP=L2:L3=L2/L4:L6=L5/L7:BOTTOM=L7 |
| MB0_CM_ADR1_R | OTHERS | BUS | 1 | 4.75 | 5 | 10 | 5 | 14 | 6 | 9.5 | 12 | 12 | 12 | 12 |  | 50 Ohms | TOP=L2:L3=L2/L4:L6=L5/L7:BOTTOM=L7 |
| MB0_CM_ADR1_R | OTHERS | BUS | 2 | 5 | 5 | 10 | 5 | 14 | 6 | 10 | 12 | 12 | 12 | 12 |  | 50 Ohms | TOP=L2:L3=L2/L4:L6=L5/L7:BOTTOM=L7 |
| MB0_CM_ADR1_R | OTHERS | BUS | 3 | 5 | 5 | 10 | 5 | 14 | 6 | 10 | 12 | 12 | 12 | 12 |  | 50 Ohms | TOP=L2:L3=L2/L4:L6=L5/L7:BOTTOM=L7 |
| MB0_CM_ADR1_R | OTHERS | BUS | 4 | 5 | 5 | 10 | 5 | 14 | 6 | 10 | 12 | 12 | 12 | 12 |  | 50 Ohms | TOP=L2:L3=L2/L4:L6=L5/L7:BOTTOM=L7 |
| MB0_CM_ADR1_R | OTHERS | BUS | 5 | 5 | 5 | 10 | 5 | 14 | 6 | 10 | 12 | 12 | 12 | 12 |  | 50 Ohms | TOP=L2:L3=L2/L4:L6=L5/L7:BOTTOM=L7 |
| MB0_CM_ADR1_R | OTHERS | BUS | 6 | 5 | 5 | 10 | 5 | 14 | 6 | 10 | 12 | 12 | 12 | 12 |  | 50 Ohms | TOP=L2:L3=L2/L4:L6=L5/L7:BOTTOM=L7 |
| MB0_CM_ADR1_R | OTHERS | BUS | 7 | 5 | 5 | 10 | 5 | 14 | 6 | 10 | 12 | 12 | 12 | 12 |  | 50 Ohms | TOP=L2:L3=L2/L4:L6=L5/L7:BOTTOM=L7 |
| MB0_CM_ADR1_R | OTHERS | BUS | 8 | 4.75 | 5 | 10 | 5 | 14 | 6 | 9.5 | 12 | 12 | 12 | 12 |  | 50 Ohms | TOP=L2:L3=L2/L4:L6=L5/L7:BOTTOM=L7 |
| MB0_CM_ADR2_R | OTHERS | BUS | 1 | 4.75 | 5 | 10 | 5 | 14 | 6 | 9.5 | 12 | 12 | 12 | 12 |  | 50 Ohms | TOP=L2:L3=L2/L4:L6=L5/L7:BOTTOM=L7 |
| MB0_CM_ADR2_R | OTHERS | BUS | 2 | 5 | 5 | 10 | 5 | 14 | 6 | 10 | 12 | 12 | 12 | 12 |  | 50 Ohms | TOP=L2:L3=L2/L4:L6=L5/L7:BOTTOM=L7 |
| MB0_CM_ADR2_R | OTHERS | BUS | 3 | 5 | 5 | 10 | 5 | 14 | 6 | 10 | 12 | 12 | 12 | 12 |  | 50 Ohms | TOP=L2:L3=L2/L4:L6=L5/L7:BOTTOM=L7 |
| MB0_CM_ADR2_R | OTHERS | BUS | 4 | 5 | 5 | 10 | 5 | 14 | 6 | 10 | 12 | 12 | 12 | 12 |  | 50 Ohms | TOP=L2:L3=L2/L4:L6=L5/L7:BOTTOM=L7 |
| MB0_CM_ADR2_R | OTHERS | BUS | 5 | 5 | 5 | 10 | 5 | 14 | 6 | 10 | 12 | 12 | 12 | 12 |  | 50 Ohms | TOP=L2:L3=L2/L4:L6=L5/L7:BOTTOM=L7 |
| MB0_CM_ADR2_R | OTHERS | BUS | 6 | 5 | 5 | 10 | 5 | 14 | 6 | 10 | 12 | 12 | 12 | 12 |  | 50 Ohms | TOP=L2:L3=L2/L4:L6=L5/L7:BOTTOM=L7 |
| MB0_CM_ADR2_R | OTHERS | BUS | 7 | 5 | 5 | 10 | 5 | 14 | 6 | 10 | 12 | 12 | 12 | 12 |  | 50 Ohms | TOP=L2:L3=L2/L4:L6=L5/L7:BOTTOM=L7 |
| MB0_CM_ADR2_R | OTHERS | BUS | 8 | 4.75 | 5 | 10 | 5 | 14 | 6 | 9.5 | 12 | 12 | 12 | 12 |  | 50 Ohms | TOP=L2:L3=L2/L4:L6=L5/L7:BOTTOM=L7 |
| MB0_CM_GATE | OTHERS | BUS | 1 | 4.75 | 5 | 10 | 5 | 14 | 6 | 9.5 | 12 | 12 | 12 | 12 |  | 50 Ohms | TOP=L2:L3=L2/L4:L6=L5/L7:BOTTOM=L7 |
| MB0_CM_GATE | OTHERS | BUS | 2 | 5 | 5 | 10 | 5 | 14 | 6 | 10 | 12 | 12 | 12 | 12 |  | 50 Ohms | TOP=L2:L3=L2/L4:L6=L5/L7:BOTTOM=L7 |
| MB0_CM_GATE | OTHERS | BUS | 3 | 5 | 5 | 10 | 5 | 14 | 6 | 10 | 12 | 12 | 12 | 12 |  | 50 Ohms | TOP=L2:L3=L2/L4:L6=L5/L7:BOTTOM=L7 |
| MB0_CM_GATE | OTHERS | BUS | 4 | 5 | 5 | 10 | 5 | 14 | 6 | 10 | 12 | 12 | 12 | 12 |  | 50 Ohms | TOP=L2:L3=L2/L4:L6=L5/L7:BOTTOM=L7 |
| MB0_CM_GATE | OTHERS | BUS | 5 | 5 | 5 | 10 | 5 | 14 | 6 | 10 | 12 | 12 | 12 | 12 |  | 50 Ohms | TOP=L2:L3=L2/L4:L6=L5/L7:BOTTOM=L7 |
| MB0_CM_GATE | OTHERS | BUS | 6 | 5 | 5 | 10 | 5 | 14 | 6 | 10 | 12 | 12 | 12 | 12 |  | 50 Ohms | TOP=L2:L3=L2/L4:L6=L5/L7:BOTTOM=L7 |
| MB0_CM_GATE | OTHERS | BUS | 7 | 5 | 5 | 10 | 5 | 14 | 6 | 10 | 12 | 12 | 12 | 12 |  | 50 Ohms | TOP=L2:L3=L2/L4:L6=L5/L7:BOTTOM=L7 |
| MB0_CM_GATE | OTHERS | BUS | 8 | 4.75 | 5 | 10 | 5 | 14 | 6 | 9.5 | 12 | 12 | 12 | 12 |  | 50 Ohms | TOP=L2:L3=L2/L4:L6=L5/L7:BOTTOM=L7 |
| MB0_CM_GATE_R | OTHERS | BUS | 1 | 4.75 | 5 | 10 | 5 | 14 | 6 | 9.5 | 12 | 12 | 12 | 12 |  | 50 Ohms | TOP=L2:L3=L2/L4:L6=L5/L7:BOTTOM=L7 |
| MB0_CM_GATE_R | OTHERS | BUS | 2 | 5 | 5 | 10 | 5 | 14 | 6 | 10 | 12 | 12 | 12 | 12 |  | 50 Ohms | TOP=L2:L3=L2/L4:L6=L5/L7:BOTTOM=L7 |
| MB0_CM_GATE_R | OTHERS | BUS | 3 | 5 | 5 | 10 | 5 | 14 | 6 | 10 | 12 | 12 | 12 | 12 |  | 50 Ohms | TOP=L2:L3=L2/L4:L6=L5/L7:BOTTOM=L7 |
| MB0_CM_GATE_R | OTHERS | BUS | 4 | 5 | 5 | 10 | 5 | 14 | 6 | 10 | 12 | 12 | 12 | 12 |  | 50 Ohms | TOP=L2:L3=L2/L4:L6=L5/L7:BOTTOM=L7 |
| MB0_CM_GATE_R | OTHERS | BUS | 5 | 5 | 5 | 10 | 5 | 14 | 6 | 10 | 12 | 12 | 12 | 12 |  | 50 Ohms | TOP=L2:L3=L2/L4:L6=L5/L7:BOTTOM=L7 |
| MB0_CM_GATE_R | OTHERS | BUS | 6 | 5 | 5 | 10 | 5 | 14 | 6 | 10 | 12 | 12 | 12 | 12 |  | 50 Ohms | TOP=L2:L3=L2/L4:L6=L5/L7:BOTTOM=L7 |
| MB0_CM_GATE_R | OTHERS | BUS | 7 | 5 | 5 | 10 | 5 | 14 | 6 | 10 | 12 | 12 | 12 | 12 |  | 50 Ohms | TOP=L2:L3=L2/L4:L6=L5/L7:BOTTOM=L7 |
| MB0_CM_GATE_R | OTHERS | BUS | 8 | 4.75 | 5 | 10 | 5 | 14 | 6 | 9.5 | 12 | 12 | 12 | 12 |  | 50 Ohms | TOP=L2:L3=L2/L4:L6=L5/L7:BOTTOM=L7 |
| MB0_CM_OV_R | OTHERS | BUS | 1 | 4.75 | 5 | 10 | 5 | 14 | 6 | 9.5 | 12 | 12 | 12 | 12 |  | 50 Ohms | TOP=L2:L3=L2/L4:L6=L5/L7:BOTTOM=L7 |
| MB0_CM_OV_R | OTHERS | BUS | 2 | 5 | 5 | 10 | 5 | 14 | 6 | 10 | 12 | 12 | 12 | 12 |  | 50 Ohms | TOP=L2:L3=L2/L4:L6=L5/L7:BOTTOM=L7 |
| MB0_CM_OV_R | OTHERS | BUS | 3 | 5 | 5 | 10 | 5 | 14 | 6 | 10 | 12 | 12 | 12 | 12 |  | 50 Ohms | TOP=L2:L3=L2/L4:L6=L5/L7:BOTTOM=L7 |
| MB0_CM_OV_R | OTHERS | BUS | 4 | 5 | 5 | 10 | 5 | 14 | 6 | 10 | 12 | 12 | 12 | 12 |  | 50 Ohms | TOP=L2:L3=L2/L4:L6=L5/L7:BOTTOM=L7 |
| MB0_CM_OV_R | OTHERS | BUS | 5 | 5 | 5 | 10 | 5 | 14 | 6 | 10 | 12 | 12 | 12 | 12 |  | 50 Ohms | TOP=L2:L3=L2/L4:L6=L5/L7:BOTTOM=L7 |
| MB0_CM_OV_R | OTHERS | BUS | 6 | 5 | 5 | 10 | 5 | 14 | 6 | 10 | 12 | 12 | 12 | 12 |  | 50 Ohms | TOP=L2:L3=L2/L4:L6=L5/L7:BOTTOM=L7 |
| MB0_CM_OV_R | OTHERS | BUS | 7 | 5 | 5 | 10 | 5 | 14 | 6 | 10 | 12 | 12 | 12 | 12 |  | 50 Ohms | TOP=L2:L3=L2/L4:L6=L5/L7:BOTTOM=L7 |
| MB0_CM_OV_R | OTHERS | BUS | 8 | 4.75 | 5 | 10 | 5 | 14 | 6 | 9.5 | 12 | 12 | 12 | 12 |  | 50 Ohms | TOP=L2:L3=L2/L4:L6=L5/L7:BOTTOM=L7 |
| MB0_CM_SENSE_N | OTHERS | BUS | 1 | 4.75 | 5 | 10 | 5 | 14 | 6 | 9.5 | 12 | 12 | 12 | 12 |  | 50 Ohms | TOP=L2:L3=L2/L4:L6=L5/L7:BOTTOM=L7 |
| MB0_CM_SENSE_N | OTHERS | BUS | 2 | 5 | 5 | 10 | 5 | 14 | 6 | 10 | 12 | 12 | 12 | 12 |  | 50 Ohms | TOP=L2:L3=L2/L4:L6=L5/L7:BOTTOM=L7 |
| MB0_CM_SENSE_N | OTHERS | BUS | 3 | 5 | 5 | 10 | 5 | 14 | 6 | 10 | 12 | 12 | 12 | 12 |  | 50 Ohms | TOP=L2:L3=L2/L4:L6=L5/L7:BOTTOM=L7 |
| MB0_CM_SENSE_N | OTHERS | BUS | 4 | 5 | 5 | 10 | 5 | 14 | 6 | 10 | 12 | 12 | 12 | 12 |  | 50 Ohms | TOP=L2:L3=L2/L4:L6=L5/L7:BOTTOM=L7 |
| MB0_CM_SENSE_N | OTHERS | BUS | 5 | 5 | 5 | 10 | 5 | 14 | 6 | 10 | 12 | 12 | 12 | 12 |  | 50 Ohms | TOP=L2:L3=L2/L4:L6=L5/L7:BOTTOM=L7 |
| MB0_CM_SENSE_N | OTHERS | BUS | 6 | 5 | 5 | 10 | 5 | 14 | 6 | 10 | 12 | 12 | 12 | 12 |  | 50 Ohms | TOP=L2:L3=L2/L4:L6=L5/L7:BOTTOM=L7 |
| MB0_CM_SENSE_N | OTHERS | BUS | 7 | 5 | 5 | 10 | 5 | 14 | 6 | 10 | 12 | 12 | 12 | 12 |  | 50 Ohms | TOP=L2:L3=L2/L4:L6=L5/L7:BOTTOM=L7 |
| MB0_CM_SENSE_N | OTHERS | BUS | 8 | 4.75 | 5 | 10 | 5 | 14 | 6 | 9.5 | 12 | 12 | 12 | 12 |  | 50 Ohms | TOP=L2:L3=L2/L4:L6=L5/L7:BOTTOM=L7 |
| MB0_CM_SENSE_P | OTHERS | BUS | 1 | 4.75 | 5 | 10 | 5 | 14 | 6 | 9.5 | 12 | 12 | 12 | 12 |  | 50 Ohms | TOP=L2:L3=L2/L4:L6=L5/L7:BOTTOM=L7 |
| MB0_CM_SENSE_P | OTHERS | BUS | 2 | 5 | 5 | 10 | 5 | 14 | 6 | 10 | 12 | 12 | 12 | 12 |  | 50 Ohms | TOP=L2:L3=L2/L4:L6=L5/L7:BOTTOM=L7 |
| MB0_CM_SENSE_P | OTHERS | BUS | 3 | 5 | 5 | 10 | 5 | 14 | 6 | 10 | 12 | 12 | 12 | 12 |  | 50 Ohms | TOP=L2:L3=L2/L4:L6=L5/L7:BOTTOM=L7 |
| MB0_CM_SENSE_P | OTHERS | BUS | 4 | 5 | 5 | 10 | 5 | 14 | 6 | 10 | 12 | 12 | 12 | 12 |  | 50 Ohms | TOP=L2:L3=L2/L4:L6=L5/L7:BOTTOM=L7 |
| MB0_CM_SENSE_P | OTHERS | BUS | 5 | 5 | 5 | 10 | 5 | 14 | 6 | 10 | 12 | 12 | 12 | 12 |  | 50 Ohms | TOP=L2:L3=L2/L4:L6=L5/L7:BOTTOM=L7 |
| MB0_CM_SENSE_P | OTHERS | BUS | 6 | 5 | 5 | 10 | 5 | 14 | 6 | 10 | 12 | 12 | 12 | 12 |  | 50 Ohms | TOP=L2:L3=L2/L4:L6=L5/L7:BOTTOM=L7 |
| MB0_CM_SENSE_P | OTHERS | BUS | 7 | 5 | 5 | 10 | 5 | 14 | 6 | 10 | 12 | 12 | 12 | 12 |  | 50 Ohms | TOP=L2:L3=L2/L4:L6=L5/L7:BOTTOM=L7 |
| MB0_CM_SENSE_P | OTHERS | BUS | 8 | 4.75 | 5 | 10 | 5 | 14 | 6 | 9.5 | 12 | 12 | 12 | 12 |  | 50 Ohms | TOP=L2:L3=L2/L4:L6=L5/L7:BOTTOM=L7 |
| MB0_CM_SENSE_R1_N | OTHERS | BUS | 1 | 4.75 | 5 | 10 | 5 | 14 | 6 | 9.5 | 12 | 12 | 12 | 12 |  | 50 Ohms | TOP=L2:L3=L2/L4:L6=L5/L7:BOTTOM=L7 |
| MB0_CM_SENSE_R1_N | OTHERS | BUS | 2 | 5 | 5 | 10 | 5 | 14 | 6 | 10 | 12 | 12 | 12 | 12 |  | 50 Ohms | TOP=L2:L3=L2/L4:L6=L5/L7:BOTTOM=L7 |
| MB0_CM_SENSE_R1_N | OTHERS | BUS | 3 | 5 | 5 | 10 | 5 | 14 | 6 | 10 | 12 | 12 | 12 | 12 |  | 50 Ohms | TOP=L2:L3=L2/L4:L6=L5/L7:BOTTOM=L7 |
| MB0_CM_SENSE_R1_N | OTHERS | BUS | 4 | 5 | 5 | 10 | 5 | 14 | 6 | 10 | 12 | 12 | 12 | 12 |  | 50 Ohms | TOP=L2:L3=L2/L4:L6=L5/L7:BOTTOM=L7 |
| MB0_CM_SENSE_R1_N | OTHERS | BUS | 5 | 5 | 5 | 10 | 5 | 14 | 6 | 10 | 12 | 12 | 12 | 12 |  | 50 Ohms | TOP=L2:L3=L2/L4:L6=L5/L7:BOTTOM=L7 |
| MB0_CM_SENSE_R1_N | OTHERS | BUS | 6 | 5 | 5 | 10 | 5 | 14 | 6 | 10 | 12 | 12 | 12 | 12 |  | 50 Ohms | TOP=L2:L3=L2/L4:L6=L5/L7:BOTTOM=L7 |
| MB0_CM_SENSE_R1_N | OTHERS | BUS | 7 | 5 | 5 | 10 | 5 | 14 | 6 | 10 | 12 | 12 | 12 | 12 |  | 50 Ohms | TOP=L2:L3=L2/L4:L6=L5/L7:BOTTOM=L7 |
| MB0_CM_SENSE_R1_N | OTHERS | BUS | 8 | 4.75 | 5 | 10 | 5 | 14 | 6 | 9.5 | 12 | 12 | 12 | 12 |  | 50 Ohms | TOP=L2:L3=L2/L4:L6=L5/L7:BOTTOM=L7 |
| MB0_CM_SENSE_R1_P | OTHERS | BUS | 1 | 4.75 | 5 | 10 | 5 | 14 | 6 | 9.5 | 12 | 12 | 12 | 12 |  | 50 Ohms | TOP=L2:L3=L2/L4:L6=L5/L7:BOTTOM=L7 |
| MB0_CM_SENSE_R1_P | OTHERS | BUS | 2 | 5 | 5 | 10 | 5 | 14 | 6 | 10 | 12 | 12 | 12 | 12 |  | 50 Ohms | TOP=L2:L3=L2/L4:L6=L5/L7:BOTTOM=L7 |
| MB0_CM_SENSE_R1_P | OTHERS | BUS | 3 | 5 | 5 | 10 | 5 | 14 | 6 | 10 | 12 | 12 | 12 | 12 |  | 50 Ohms | TOP=L2:L3=L2/L4:L6=L5/L7:BOTTOM=L7 |
| MB0_CM_SENSE_R1_P | OTHERS | BUS | 4 | 5 | 5 | 10 | 5 | 14 | 6 | 10 | 12 | 12 | 12 | 12 |  | 50 Ohms | TOP=L2:L3=L2/L4:L6=L5/L7:BOTTOM=L7 |
| MB0_CM_SENSE_R1_P | OTHERS | BUS | 5 | 5 | 5 | 10 | 5 | 14 | 6 | 10 | 12 | 12 | 12 | 12 |  | 50 Ohms | TOP=L2:L3=L2/L4:L6=L5/L7:BOTTOM=L7 |
| MB0_CM_SENSE_R1_P | OTHERS | BUS | 6 | 5 | 5 | 10 | 5 | 14 | 6 | 10 | 12 | 12 | 12 | 12 |  | 50 Ohms | TOP=L2:L3=L2/L4:L6=L5/L7:BOTTOM=L7 |
| MB0_CM_SENSE_R1_P | OTHERS | BUS | 7 | 5 | 5 | 10 | 5 | 14 | 6 | 10 | 12 | 12 | 12 | 12 |  | 50 Ohms | TOP=L2:L3=L2/L4:L6=L5/L7:BOTTOM=L7 |
| MB0_CM_SENSE_R1_P | OTHERS | BUS | 8 | 4.75 | 5 | 10 | 5 | 14 | 6 | 9.5 | 12 | 12 | 12 | 12 |  | 50 Ohms | TOP=L2:L3=L2/L4:L6=L5/L7:BOTTOM=L7 |
| MB0_CM_UV_R | OTHERS | BUS | 1 | 4.75 | 5 | 10 | 5 | 14 | 6 | 9.5 | 12 | 12 | 12 | 12 |  | 50 Ohms | TOP=L2:L3=L2/L4:L6=L5/L7:BOTTOM=L7 |
| MB0_CM_UV_R | OTHERS | BUS | 2 | 5 | 5 | 10 | 5 | 14 | 6 | 10 | 12 | 12 | 12 | 12 |  | 50 Ohms | TOP=L2:L3=L2/L4:L6=L5/L7:BOTTOM=L7 |
| MB0_CM_UV_R | OTHERS | BUS | 3 | 5 | 5 | 10 | 5 | 14 | 6 | 10 | 12 | 12 | 12 | 12 |  | 50 Ohms | TOP=L2:L3=L2/L4:L6=L5/L7:BOTTOM=L7 |
| MB0_CM_UV_R | OTHERS | BUS | 4 | 5 | 5 | 10 | 5 | 14 | 6 | 10 | 12 | 12 | 12 | 12 |  | 50 Ohms | TOP=L2:L3=L2/L4:L6=L5/L7:BOTTOM=L7 |
| MB0_CM_UV_R | OTHERS | BUS | 5 | 5 | 5 | 10 | 5 | 14 | 6 | 10 | 12 | 12 | 12 | 12 |  | 50 Ohms | TOP=L2:L3=L2/L4:L6=L5/L7:BOTTOM=L7 |
| MB0_CM_UV_R | OTHERS | BUS | 6 | 5 | 5 | 10 | 5 | 14 | 6 | 10 | 12 | 12 | 12 | 12 |  | 50 Ohms | TOP=L2:L3=L2/L4:L6=L5/L7:BOTTOM=L7 |
| MB0_CM_UV_R | OTHERS | BUS | 7 | 5 | 5 | 10 | 5 | 14 | 6 | 10 | 12 | 12 | 12 | 12 |  | 50 Ohms | TOP=L2:L3=L2/L4:L6=L5/L7:BOTTOM=L7 |
| MB0_CM_UV_R | OTHERS | BUS | 8 | 4.75 | 5 | 10 | 5 | 14 | 6 | 9.5 | 12 | 12 | 12 | 12 |  | 50 Ohms | TOP=L2:L3=L2/L4:L6=L5/L7:BOTTOM=L7 |
| MB0_CM_VOUT_R | OTHERS | BUS | 1 | 4.75 | 5 | 10 | 5 | 14 | 6 | 9.5 | 12 | 12 | 12 | 12 |  | 50 Ohms | TOP=L2:L3=L2/L4:L6=L5/L7:BOTTOM=L7 |
| MB0_CM_VOUT_R | OTHERS | BUS | 2 | 5 | 5 | 10 | 5 | 14 | 6 | 10 | 12 | 12 | 12 | 12 |  | 50 Ohms | TOP=L2:L3=L2/L4:L6=L5/L7:BOTTOM=L7 |
| MB0_CM_VOUT_R | OTHERS | BUS | 3 | 5 | 5 | 10 | 5 | 14 | 6 | 10 | 12 | 12 | 12 | 12 |  | 50 Ohms | TOP=L2:L3=L2/L4:L6=L5/L7:BOTTOM=L7 |
| MB0_CM_VOUT_R | OTHERS | BUS | 4 | 5 | 5 | 10 | 5 | 14 | 6 | 10 | 12 | 12 | 12 | 12 |  | 50 Ohms | TOP=L2:L3=L2/L4:L6=L5/L7:BOTTOM=L7 |
| MB0_CM_VOUT_R | OTHERS | BUS | 5 | 5 | 5 | 10 | 5 | 14 | 6 | 10 | 12 | 12 | 12 | 12 |  | 50 Ohms | TOP=L2:L3=L2/L4:L6=L5/L7:BOTTOM=L7 |
| MB0_CM_VOUT_R | OTHERS | BUS | 6 | 5 | 5 | 10 | 5 | 14 | 6 | 10 | 12 | 12 | 12 | 12 |  | 50 Ohms | TOP=L2:L3=L2/L4:L6=L5/L7:BOTTOM=L7 |
| MB0_CM_VOUT_R | OTHERS | BUS | 7 | 5 | 5 | 10 | 5 | 14 | 6 | 10 | 12 | 12 | 12 | 12 |  | 50 Ohms | TOP=L2:L3=L2/L4:L6=L5/L7:BOTTOM=L7 |
| MB0_CM_VOUT_R | OTHERS | BUS | 8 | 4.75 | 5 | 10 | 5 | 14 | 6 | 9.5 | 12 | 12 | 12 | 12 |  | 50 Ohms | TOP=L2:L3=L2/L4:L6=L5/L7:BOTTOM=L7 |
| MB0_HS_ENABLE | OTHERS | BUS | 1 | 4.75 | 5 | 10 | 5 | 14 | 6 | 9.5 | 12 | 12 | 12 | 12 |  | 50 Ohms | TOP=L2:L3=L2/L4:L6=L5/L7:BOTTOM=L7 |
| MB0_HS_ENABLE | OTHERS | BUS | 2 | 5 | 5 | 10 | 5 | 14 | 6 | 10 | 12 | 12 | 12 | 12 |  | 50 Ohms | TOP=L2:L3=L2/L4:L6=L5/L7:BOTTOM=L7 |
| MB0_HS_ENABLE | OTHERS | BUS | 3 | 5 | 5 | 10 | 5 | 14 | 6 | 10 | 12 | 12 | 12 | 12 |  | 50 Ohms | TOP=L2:L3=L2/L4:L6=L5/L7:BOTTOM=L7 |
| MB0_HS_ENABLE | OTHERS | BUS | 4 | 5 | 5 | 10 | 5 | 14 | 6 | 10 | 12 | 12 | 12 | 12 |  | 50 Ohms | TOP=L2:L3=L2/L4:L6=L5/L7:BOTTOM=L7 |
| MB0_HS_ENABLE | OTHERS | BUS | 5 | 5 | 5 | 10 | 5 | 14 | 6 | 10 | 12 | 12 | 12 | 12 |  | 50 Ohms | TOP=L2:L3=L2/L4:L6=L5/L7:BOTTOM=L7 |
| MB0_HS_ENABLE | OTHERS | BUS | 6 | 5 | 5 | 10 | 5 | 14 | 6 | 10 | 12 | 12 | 12 | 12 |  | 50 Ohms | TOP=L2:L3=L2/L4:L6=L5/L7:BOTTOM=L7 |
| MB0_HS_ENABLE | OTHERS | BUS | 7 | 5 | 5 | 10 | 5 | 14 | 6 | 10 | 12 | 12 | 12 | 12 |  | 50 Ohms | TOP=L2:L3=L2/L4:L6=L5/L7:BOTTOM=L7 |
| MB0_HS_ENABLE | OTHERS | BUS | 8 | 4.75 | 5 | 10 | 5 | 14 | 6 | 9.5 | 12 | 12 | 12 | 12 |  | 50 Ohms | TOP=L2:L3=L2/L4:L6=L5/L7:BOTTOM=L7 |
| MB0_ISET_R | OTHERS | BUS | 1 | 4.75 | 5 | 10 | 5 | 14 | 6 | 9.5 | 12 | 12 | 12 | 12 |  | 50 Ohms | TOP=L2:L3=L2/L4:L6=L5/L7:BOTTOM=L7 |
| MB0_ISET_R | OTHERS | BUS | 2 | 5 | 5 | 10 | 5 | 14 | 6 | 10 | 12 | 12 | 12 | 12 |  | 50 Ohms | TOP=L2:L3=L2/L4:L6=L5/L7:BOTTOM=L7 |
| MB0_ISET_R | OTHERS | BUS | 3 | 5 | 5 | 10 | 5 | 14 | 6 | 10 | 12 | 12 | 12 | 12 |  | 50 Ohms | TOP=L2:L3=L2/L4:L6=L5/L7:BOTTOM=L7 |
| MB0_ISET_R | OTHERS | BUS | 4 | 5 | 5 | 10 | 5 | 14 | 6 | 10 | 12 | 12 | 12 | 12 |  | 50 Ohms | TOP=L2:L3=L2/L4:L6=L5/L7:BOTTOM=L7 |
| MB0_ISET_R | OTHERS | BUS | 5 | 5 | 5 | 10 | 5 | 14 | 6 | 10 | 12 | 12 | 12 | 12 |  | 50 Ohms | TOP=L2:L3=L2/L4:L6=L5/L7:BOTTOM=L7 |
| MB0_ISET_R | OTHERS | BUS | 6 | 5 | 5 | 10 | 5 | 14 | 6 | 10 | 12 | 12 | 12 | 12 |  | 50 Ohms | TOP=L2:L3=L2/L4:L6=L5/L7:BOTTOM=L7 |
| MB0_ISET_R | OTHERS | BUS | 7 | 5 | 5 | 10 | 5 | 14 | 6 | 10 | 12 | 12 | 12 | 12 |  | 50 Ohms | TOP=L2:L3=L2/L4:L6=L5/L7:BOTTOM=L7 |
| MB0_ISET_R | OTHERS | BUS | 8 | 4.75 | 5 | 10 | 5 | 14 | 6 | 9.5 | 12 | 12 | 12 | 12 |  | 50 Ohms | TOP=L2:L3=L2/L4:L6=L5/L7:BOTTOM=L7 |
| MB0_ISTART_R | OTHERS | BUS | 1 | 4.75 | 5 | 10 | 5 | 14 | 6 | 9.5 | 12 | 12 | 12 | 12 |  | 50 Ohms | TOP=L2:L3=L2/L4:L6=L5/L7:BOTTOM=L7 |
| MB0_ISTART_R | OTHERS | BUS | 2 | 5 | 5 | 10 | 5 | 14 | 6 | 10 | 12 | 12 | 12 | 12 |  | 50 Ohms | TOP=L2:L3=L2/L4:L6=L5/L7:BOTTOM=L7 |
| MB0_ISTART_R | OTHERS | BUS | 3 | 5 | 5 | 10 | 5 | 14 | 6 | 10 | 12 | 12 | 12 | 12 |  | 50 Ohms | TOP=L2:L3=L2/L4:L6=L5/L7:BOTTOM=L7 |
| MB0_ISTART_R | OTHERS | BUS | 4 | 5 | 5 | 10 | 5 | 14 | 6 | 10 | 12 | 12 | 12 | 12 |  | 50 Ohms | TOP=L2:L3=L2/L4:L6=L5/L7:BOTTOM=L7 |
| MB0_ISTART_R | OTHERS | BUS | 5 | 5 | 5 | 10 | 5 | 14 | 6 | 10 | 12 | 12 | 12 | 12 |  | 50 Ohms | TOP=L2:L3=L2/L4:L6=L5/L7:BOTTOM=L7 |
| MB0_ISTART_R | OTHERS | BUS | 6 | 5 | 5 | 10 | 5 | 14 | 6 | 10 | 12 | 12 | 12 | 12 |  | 50 Ohms | TOP=L2:L3=L2/L4:L6=L5/L7:BOTTOM=L7 |
| MB0_ISTART_R | OTHERS | BUS | 7 | 5 | 5 | 10 | 5 | 14 | 6 | 10 | 12 | 12 | 12 | 12 |  | 50 Ohms | TOP=L2:L3=L2/L4:L6=L5/L7:BOTTOM=L7 |
| MB0_ISTART_R | OTHERS | BUS | 8 | 4.75 | 5 | 10 | 5 | 14 | 6 | 9.5 | 12 | 12 | 12 | 12 |  | 50 Ohms | TOP=L2:L3=L2/L4:L6=L5/L7:BOTTOM=L7 |
| MB0_P12V_PWGIN_R | OTHERS | BUS | 1 | 4.75 | 5 | 10 | 5 | 14 | 6 | 9.5 | 12 | 12 | 12 | 12 |  | 50 Ohms | TOP=L2:L3=L2/L4:L6=L5/L7:BOTTOM=L7 |
| MB0_P12V_PWGIN_R | OTHERS | BUS | 2 | 5 | 5 | 10 | 5 | 14 | 6 | 10 | 12 | 12 | 12 | 12 |  | 50 Ohms | TOP=L2:L3=L2/L4:L6=L5/L7:BOTTOM=L7 |
| MB0_P12V_PWGIN_R | OTHERS | BUS | 3 | 5 | 5 | 10 | 5 | 14 | 6 | 10 | 12 | 12 | 12 | 12 |  | 50 Ohms | TOP=L2:L3=L2/L4:L6=L5/L7:BOTTOM=L7 |
| MB0_P12V_PWGIN_R | OTHERS | BUS | 4 | 5 | 5 | 10 | 5 | 14 | 6 | 10 | 12 | 12 | 12 | 12 |  | 50 Ohms | TOP=L2:L3=L2/L4:L6=L5/L7:BOTTOM=L7 |
| MB0_P12V_PWGIN_R | OTHERS | BUS | 5 | 5 | 5 | 10 | 5 | 14 | 6 | 10 | 12 | 12 | 12 | 12 |  | 50 Ohms | TOP=L2:L3=L2/L4:L6=L5/L7:BOTTOM=L7 |
| MB0_P12V_PWGIN_R | OTHERS | BUS | 6 | 5 | 5 | 10 | 5 | 14 | 6 | 10 | 12 | 12 | 12 | 12 |  | 50 Ohms | TOP=L2:L3=L2/L4:L6=L5/L7:BOTTOM=L7 |
| MB0_P12V_PWGIN_R | OTHERS | BUS | 7 | 5 | 5 | 10 | 5 | 14 | 6 | 10 | 12 | 12 | 12 | 12 |  | 50 Ohms | TOP=L2:L3=L2/L4:L6=L5/L7:BOTTOM=L7 |
| MB0_P12V_PWGIN_R | OTHERS | BUS | 8 | 4.75 | 5 | 10 | 5 | 14 | 6 | 9.5 | 12 | 12 | 12 | 12 |  | 50 Ohms | TOP=L2:L3=L2/L4:L6=L5/L7:BOTTOM=L7 |
| MB0_P12V_PWRGOOD | OTHERS | BUS | 1 | 4.75 | 5 | 10 | 5 | 14 | 6 | 9.5 | 12 | 12 | 12 | 12 |  | 50 Ohms | TOP=L2:L3=L2/L4:L6=L5/L7:BOTTOM=L7 |
| MB0_P12V_PWRGOOD | OTHERS | BUS | 2 | 5 | 5 | 10 | 5 | 14 | 6 | 10 | 12 | 12 | 12 | 12 |  | 50 Ohms | TOP=L2:L3=L2/L4:L6=L5/L7:BOTTOM=L7 |
| MB0_P12V_PWRGOOD | OTHERS | BUS | 3 | 5 | 5 | 10 | 5 | 14 | 6 | 10 | 12 | 12 | 12 | 12 |  | 50 Ohms | TOP=L2:L3=L2/L4:L6=L5/L7:BOTTOM=L7 |
| MB0_P12V_PWRGOOD | OTHERS | BUS | 4 | 5 | 5 | 10 | 5 | 14 | 6 | 10 | 12 | 12 | 12 | 12 |  | 50 Ohms | TOP=L2:L3=L2/L4:L6=L5/L7:BOTTOM=L7 |
| MB0_P12V_PWRGOOD | OTHERS | BUS | 5 | 5 | 5 | 10 | 5 | 14 | 6 | 10 | 12 | 12 | 12 | 12 |  | 50 Ohms | TOP=L2:L3=L2/L4:L6=L5/L7:BOTTOM=L7 |
| MB0_P12V_PWRGOOD | OTHERS | BUS | 6 | 5 | 5 | 10 | 5 | 14 | 6 | 10 | 12 | 12 | 12 | 12 |  | 50 Ohms | TOP=L2:L3=L2/L4:L6=L5/L7:BOTTOM=L7 |
| MB0_P12V_PWRGOOD | OTHERS | BUS | 7 | 5 | 5 | 10 | 5 | 14 | 6 | 10 | 12 | 12 | 12 | 12 |  | 50 Ohms | TOP=L2:L3=L2/L4:L6=L5/L7:BOTTOM=L7 |
| MB0_P12V_PWRGOOD | OTHERS | BUS | 8 | 4.75 | 5 | 10 | 5 | 14 | 6 | 9.5 | 12 | 12 | 12 | 12 |  | 50 Ohms | TOP=L2:L3=L2/L4:L6=L5/L7:BOTTOM=L7 |
| MB0_PSET_R | OTHERS | BUS | 1 | 4.75 | 5 | 10 | 5 | 14 | 6 | 9.5 | 12 | 12 | 12 | 12 |  | 50 Ohms | TOP=L2:L3=L2/L4:L6=L5/L7:BOTTOM=L7 |
| MB0_PSET_R | OTHERS | BUS | 2 | 5 | 5 | 10 | 5 | 14 | 6 | 10 | 12 | 12 | 12 | 12 |  | 50 Ohms | TOP=L2:L3=L2/L4:L6=L5/L7:BOTTOM=L7 |
| MB0_PSET_R | OTHERS | BUS | 3 | 5 | 5 | 10 | 5 | 14 | 6 | 10 | 12 | 12 | 12 | 12 |  | 50 Ohms | TOP=L2:L3=L2/L4:L6=L5/L7:BOTTOM=L7 |
| MB0_PSET_R | OTHERS | BUS | 4 | 5 | 5 | 10 | 5 | 14 | 6 | 10 | 12 | 12 | 12 | 12 |  | 50 Ohms | TOP=L2:L3=L2/L4:L6=L5/L7:BOTTOM=L7 |
| MB0_PSET_R | OTHERS | BUS | 5 | 5 | 5 | 10 | 5 | 14 | 6 | 10 | 12 | 12 | 12 | 12 |  | 50 Ohms | TOP=L2:L3=L2/L4:L6=L5/L7:BOTTOM=L7 |
| MB0_PSET_R | OTHERS | BUS | 6 | 5 | 5 | 10 | 5 | 14 | 6 | 10 | 12 | 12 | 12 | 12 |  | 50 Ohms | TOP=L2:L3=L2/L4:L6=L5/L7:BOTTOM=L7 |
| MB0_PSET_R | OTHERS | BUS | 7 | 5 | 5 | 10 | 5 | 14 | 6 | 10 | 12 | 12 | 12 | 12 |  | 50 Ohms | TOP=L2:L3=L2/L4:L6=L5/L7:BOTTOM=L7 |
| MB0_PSET_R | OTHERS | BUS | 8 | 4.75 | 5 | 10 | 5 | 14 | 6 | 9.5 | 12 | 12 | 12 | 12 |  | 50 Ohms | TOP=L2:L3=L2/L4:L6=L5/L7:BOTTOM=L7 |
| MB0_RETRY_R | OTHERS | BUS | 1 | 4.75 | 5 | 10 | 5 | 14 | 6 | 9.5 | 12 | 12 | 12 | 12 |  | 50 Ohms | TOP=L2:L3=L2/L4:L6=L5/L7:BOTTOM=L7 |
| MB0_RETRY_R | OTHERS | BUS | 2 | 5 | 5 | 10 | 5 | 14 | 6 | 10 | 12 | 12 | 12 | 12 |  | 50 Ohms | TOP=L2:L3=L2/L4:L6=L5/L7:BOTTOM=L7 |
| MB0_RETRY_R | OTHERS | BUS | 3 | 5 | 5 | 10 | 5 | 14 | 6 | 10 | 12 | 12 | 12 | 12 |  | 50 Ohms | TOP=L2:L3=L2/L4:L6=L5/L7:BOTTOM=L7 |
| MB0_RETRY_R | OTHERS | BUS | 4 | 5 | 5 | 10 | 5 | 14 | 6 | 10 | 12 | 12 | 12 | 12 |  | 50 Ohms | TOP=L2:L3=L2/L4:L6=L5/L7:BOTTOM=L7 |
| MB0_RETRY_R | OTHERS | BUS | 5 | 5 | 5 | 10 | 5 | 14 | 6 | 10 | 12 | 12 | 12 | 12 |  | 50 Ohms | TOP=L2:L3=L2/L4:L6=L5/L7:BOTTOM=L7 |
| MB0_RETRY_R | OTHERS | BUS | 6 | 5 | 5 | 10 | 5 | 14 | 6 | 10 | 12 | 12 | 12 | 12 |  | 50 Ohms | TOP=L2:L3=L2/L4:L6=L5/L7:BOTTOM=L7 |
| MB0_RETRY_R | OTHERS | BUS | 7 | 5 | 5 | 10 | 5 | 14 | 6 | 10 | 12 | 12 | 12 | 12 |  | 50 Ohms | TOP=L2:L3=L2/L4:L6=L5/L7:BOTTOM=L7 |
| MB0_RETRY_R | OTHERS | BUS | 8 | 4.75 | 5 | 10 | 5 | 14 | 6 | 9.5 | 12 | 12 | 12 | 12 |  | 50 Ohms | TOP=L2:L3=L2/L4:L6=L5/L7:BOTTOM=L7 |
| MB0_SPISS_PD | OTHERS | BUS | 1 | 4.75 | 5 | 10 | 5 | 14 | 6 | 9.5 | 12 | 12 | 12 | 12 |  | 50 Ohms | TOP=L2:L3=L2/L4:L6=L5/L7:BOTTOM=L7 |
| MB0_SPISS_PD | OTHERS | BUS | 2 | 5 | 5 | 10 | 5 | 14 | 6 | 10 | 12 | 12 | 12 | 12 |  | 50 Ohms | TOP=L2:L3=L2/L4:L6=L5/L7:BOTTOM=L7 |
| MB0_SPISS_PD | OTHERS | BUS | 3 | 5 | 5 | 10 | 5 | 14 | 6 | 10 | 12 | 12 | 12 | 12 |  | 50 Ohms | TOP=L2:L3=L2/L4:L6=L5/L7:BOTTOM=L7 |
| MB0_SPISS_PD | OTHERS | BUS | 4 | 5 | 5 | 10 | 5 | 14 | 6 | 10 | 12 | 12 | 12 | 12 |  | 50 Ohms | TOP=L2:L3=L2/L4:L6=L5/L7:BOTTOM=L7 |
| MB0_SPISS_PD | OTHERS | BUS | 5 | 5 | 5 | 10 | 5 | 14 | 6 | 10 | 12 | 12 | 12 | 12 |  | 50 Ohms | TOP=L2:L3=L2/L4:L6=L5/L7:BOTTOM=L7 |
| MB0_SPISS_PD | OTHERS | BUS | 6 | 5 | 5 | 10 | 5 | 14 | 6 | 10 | 12 | 12 | 12 | 12 |  | 50 Ohms | TOP=L2:L3=L2/L4:L6=L5/L7:BOTTOM=L7 |
| MB0_SPISS_PD | OTHERS | BUS | 7 | 5 | 5 | 10 | 5 | 14 | 6 | 10 | 12 | 12 | 12 | 12 |  | 50 Ohms | TOP=L2:L3=L2/L4:L6=L5/L7:BOTTOM=L7 |
| MB0_SPISS_PD | OTHERS | BUS | 8 | 4.75 | 5 | 10 | 5 | 14 | 6 | 9.5 | 12 | 12 | 12 | 12 |  | 50 Ohms | TOP=L2:L3=L2/L4:L6=L5/L7:BOTTOM=L7 |
| MB0_TEMP | OTHERS | BUS | 1 | 4.75 | 5 | 10 | 5 | 14 | 6 | 9.5 | 12 | 12 | 12 | 12 |  | 50 Ohms | TOP=L2:L3=L2/L4:L6=L5/L7:BOTTOM=L7 |
| MB0_TEMP | OTHERS | BUS | 2 | 5 | 5 | 10 | 5 | 14 | 6 | 10 | 12 | 12 | 12 | 12 |  | 50 Ohms | TOP=L2:L3=L2/L4:L6=L5/L7:BOTTOM=L7 |
| MB0_TEMP | OTHERS | BUS | 3 | 5 | 5 | 10 | 5 | 14 | 6 | 10 | 12 | 12 | 12 | 12 |  | 50 Ohms | TOP=L2:L3=L2/L4:L6=L5/L7:BOTTOM=L7 |
| MB0_TEMP | OTHERS | BUS | 4 | 5 | 5 | 10 | 5 | 14 | 6 | 10 | 12 | 12 | 12 | 12 |  | 50 Ohms | TOP=L2:L3=L2/L4:L6=L5/L7:BOTTOM=L7 |
| MB0_TEMP | OTHERS | BUS | 5 | 5 | 5 | 10 | 5 | 14 | 6 | 10 | 12 | 12 | 12 | 12 |  | 50 Ohms | TOP=L2:L3=L2/L4:L6=L5/L7:BOTTOM=L7 |
| MB0_TEMP | OTHERS | BUS | 6 | 5 | 5 | 10 | 5 | 14 | 6 | 10 | 12 | 12 | 12 | 12 |  | 50 Ohms | TOP=L2:L3=L2/L4:L6=L5/L7:BOTTOM=L7 |
| MB0_TEMP | OTHERS | BUS | 7 | 5 | 5 | 10 | 5 | 14 | 6 | 10 | 12 | 12 | 12 | 12 |  | 50 Ohms | TOP=L2:L3=L2/L4:L6=L5/L7:BOTTOM=L7 |
| MB0_TEMP | OTHERS | BUS | 8 | 4.75 | 5 | 10 | 5 | 14 | 6 | 9.5 | 12 | 12 | 12 | 12 |  | 50 Ohms | TOP=L2:L3=L2/L4:L6=L5/L7:BOTTOM=L7 |
| MB0_TEMP_C | OTHERS | BUS | 1 | 4.75 | 5 | 10 | 5 | 14 | 6 | 9.5 | 12 | 12 | 12 | 12 |  | 50 Ohms | TOP=L2:L3=L2/L4:L6=L5/L7:BOTTOM=L7 |
| MB0_TEMP_C | OTHERS | BUS | 2 | 5 | 5 | 10 | 5 | 14 | 6 | 10 | 12 | 12 | 12 | 12 |  | 50 Ohms | TOP=L2:L3=L2/L4:L6=L5/L7:BOTTOM=L7 |
| MB0_TEMP_C | OTHERS | BUS | 3 | 5 | 5 | 10 | 5 | 14 | 6 | 10 | 12 | 12 | 12 | 12 |  | 50 Ohms | TOP=L2:L3=L2/L4:L6=L5/L7:BOTTOM=L7 |
| MB0_TEMP_C | OTHERS | BUS | 4 | 5 | 5 | 10 | 5 | 14 | 6 | 10 | 12 | 12 | 12 | 12 |  | 50 Ohms | TOP=L2:L3=L2/L4:L6=L5/L7:BOTTOM=L7 |
| MB0_TEMP_C | OTHERS | BUS | 5 | 5 | 5 | 10 | 5 | 14 | 6 | 10 | 12 | 12 | 12 | 12 |  | 50 Ohms | TOP=L2:L3=L2/L4:L6=L5/L7:BOTTOM=L7 |
| MB0_TEMP_C | OTHERS | BUS | 6 | 5 | 5 | 10 | 5 | 14 | 6 | 10 | 12 | 12 | 12 | 12 |  | 50 Ohms | TOP=L2:L3=L2/L4:L6=L5/L7:BOTTOM=L7 |
| MB0_TEMP_C | OTHERS | BUS | 7 | 5 | 5 | 10 | 5 | 14 | 6 | 10 | 12 | 12 | 12 | 12 |  | 50 Ohms | TOP=L2:L3=L2/L4:L6=L5/L7:BOTTOM=L7 |
| MB0_TEMP_C | OTHERS | BUS | 8 | 4.75 | 5 | 10 | 5 | 14 | 6 | 9.5 | 12 | 12 | 12 | 12 |  | 50 Ohms | TOP=L2:L3=L2/L4:L6=L5/L7:BOTTOM=L7 |
| MB0_TEMP_E | OTHERS | BUS | 1 | 4.75 | 5 | 10 | 5 | 14 | 6 | 9.5 | 12 | 12 | 12 | 12 |  | 50 Ohms | TOP=L2:L3=L2/L4:L6=L5/L7:BOTTOM=L7 |
| MB0_TEMP_E | OTHERS | BUS | 2 | 5 | 5 | 10 | 5 | 14 | 6 | 10 | 12 | 12 | 12 | 12 |  | 50 Ohms | TOP=L2:L3=L2/L4:L6=L5/L7:BOTTOM=L7 |
| MB0_TEMP_E | OTHERS | BUS | 3 | 5 | 5 | 10 | 5 | 14 | 6 | 10 | 12 | 12 | 12 | 12 |  | 50 Ohms | TOP=L2:L3=L2/L4:L6=L5/L7:BOTTOM=L7 |
| MB0_TEMP_E | OTHERS | BUS | 4 | 5 | 5 | 10 | 5 | 14 | 6 | 10 | 12 | 12 | 12 | 12 |  | 50 Ohms | TOP=L2:L3=L2/L4:L6=L5/L7:BOTTOM=L7 |
| MB0_TEMP_E | OTHERS | BUS | 5 | 5 | 5 | 10 | 5 | 14 | 6 | 10 | 12 | 12 | 12 | 12 |  | 50 Ohms | TOP=L2:L3=L2/L4:L6=L5/L7:BOTTOM=L7 |
| MB0_TEMP_E | OTHERS | BUS | 6 | 5 | 5 | 10 | 5 | 14 | 6 | 10 | 12 | 12 | 12 | 12 |  | 50 Ohms | TOP=L2:L3=L2/L4:L6=L5/L7:BOTTOM=L7 |
| MB0_TEMP_E | OTHERS | BUS | 7 | 5 | 5 | 10 | 5 | 14 | 6 | 10 | 12 | 12 | 12 | 12 |  | 50 Ohms | TOP=L2:L3=L2/L4:L6=L5/L7:BOTTOM=L7 |
| MB0_TEMP_E | OTHERS | BUS | 8 | 4.75 | 5 | 10 | 5 | 14 | 6 | 9.5 | 12 | 12 | 12 | 12 |  | 50 Ohms | TOP=L2:L3=L2/L4:L6=L5/L7:BOTTOM=L7 |
| MB0_TIME_R | OTHERS | BUS | 1 | 4.75 | 5 | 10 | 5 | 14 | 6 | 9.5 | 12 | 12 | 12 | 12 |  | 50 Ohms | TOP=L2:L3=L2/L4:L6=L5/L7:BOTTOM=L7 |
| MB0_TIME_R | OTHERS | BUS | 2 | 5 | 5 | 10 | 5 | 14 | 6 | 10 | 12 | 12 | 12 | 12 |  | 50 Ohms | TOP=L2:L3=L2/L4:L6=L5/L7:BOTTOM=L7 |
| MB0_TIME_R | OTHERS | BUS | 3 | 5 | 5 | 10 | 5 | 14 | 6 | 10 | 12 | 12 | 12 | 12 |  | 50 Ohms | TOP=L2:L3=L2/L4:L6=L5/L7:BOTTOM=L7 |
| MB0_TIME_R | OTHERS | BUS | 4 | 5 | 5 | 10 | 5 | 14 | 6 | 10 | 12 | 12 | 12 | 12 |  | 50 Ohms | TOP=L2:L3=L2/L4:L6=L5/L7:BOTTOM=L7 |
| MB0_TIME_R | OTHERS | BUS | 5 | 5 | 5 | 10 | 5 | 14 | 6 | 10 | 12 | 12 | 12 | 12 |  | 50 Ohms | TOP=L2:L3=L2/L4:L6=L5/L7:BOTTOM=L7 |
| MB0_TIME_R | OTHERS | BUS | 6 | 5 | 5 | 10 | 5 | 14 | 6 | 10 | 12 | 12 | 12 | 12 |  | 50 Ohms | TOP=L2:L3=L2/L4:L6=L5/L7:BOTTOM=L7 |
| MB0_TIME_R | OTHERS | BUS | 7 | 5 | 5 | 10 | 5 | 14 | 6 | 10 | 12 | 12 | 12 | 12 |  | 50 Ohms | TOP=L2:L3=L2/L4:L6=L5/L7:BOTTOM=L7 |
| MB0_TIME_R | OTHERS | BUS | 8 | 4.75 | 5 | 10 | 5 | 14 | 6 | 9.5 | 12 | 12 | 12 | 12 |  | 50 Ohms | TOP=L2:L3=L2/L4:L6=L5/L7:BOTTOM=L7 |
| MB0_VCAP_R | OTHERS | BUS | 1 | 4.75 | 5 | 10 | 5 | 14 | 6 | 9.5 | 12 | 12 | 12 | 12 |  | 50 Ohms | TOP=L2:L3=L2/L4:L6=L5/L7:BOTTOM=L7 |
| MB0_VCAP_R | OTHERS | BUS | 2 | 5 | 5 | 10 | 5 | 14 | 6 | 10 | 12 | 12 | 12 | 12 |  | 50 Ohms | TOP=L2:L3=L2/L4:L6=L5/L7:BOTTOM=L7 |
| MB0_VCAP_R | OTHERS | BUS | 3 | 5 | 5 | 10 | 5 | 14 | 6 | 10 | 12 | 12 | 12 | 12 |  | 50 Ohms | TOP=L2:L3=L2/L4:L6=L5/L7:BOTTOM=L7 |
| MB0_VCAP_R | OTHERS | BUS | 4 | 5 | 5 | 10 | 5 | 14 | 6 | 10 | 12 | 12 | 12 | 12 |  | 50 Ohms | TOP=L2:L3=L2/L4:L6=L5/L7:BOTTOM=L7 |
| MB0_VCAP_R | OTHERS | BUS | 5 | 5 | 5 | 10 | 5 | 14 | 6 | 10 | 12 | 12 | 12 | 12 |  | 50 Ohms | TOP=L2:L3=L2/L4:L6=L5/L7:BOTTOM=L7 |
| MB0_VCAP_R | OTHERS | BUS | 6 | 5 | 5 | 10 | 5 | 14 | 6 | 10 | 12 | 12 | 12 | 12 |  | 50 Ohms | TOP=L2:L3=L2/L4:L6=L5/L7:BOTTOM=L7 |
| MB0_VCAP_R | OTHERS | BUS | 7 | 5 | 5 | 10 | 5 | 14 | 6 | 10 | 12 | 12 | 12 | 12 |  | 50 Ohms | TOP=L2:L3=L2/L4:L6=L5/L7:BOTTOM=L7 |
| MB0_VCAP_R | OTHERS | BUS | 8 | 4.75 | 5 | 10 | 5 | 14 | 6 | 9.5 | 12 | 12 | 12 | 12 |  | 50 Ohms | TOP=L2:L3=L2/L4:L6=L5/L7:BOTTOM=L7 |
| MDC | OTHERS | BUS | 1 | 4.75 | 5 | 10 | 5 | 14 | 6 | 9.5 | 12 | 12 | 12 | 12 |  | 50 Ohms | TOP=L2:L3=L2/L4:L6=L5/L7:BOTTOM=L7 |
| MDC | OTHERS | BUS | 2 | 5 | 5 | 10 | 5 | 14 | 6 | 10 | 12 | 12 | 12 | 12 |  | 50 Ohms | TOP=L2:L3=L2/L4:L6=L5/L7:BOTTOM=L7 |
| MDC | OTHERS | BUS | 3 | 5 | 5 | 10 | 5 | 14 | 6 | 10 | 12 | 12 | 12 | 12 |  | 50 Ohms | TOP=L2:L3=L2/L4:L6=L5/L7:BOTTOM=L7 |
| MDC | OTHERS | BUS | 4 | 5 | 5 | 10 | 5 | 14 | 6 | 10 | 12 | 12 | 12 | 12 |  | 50 Ohms | TOP=L2:L3=L2/L4:L6=L5/L7:BOTTOM=L7 |
| MDC | OTHERS | BUS | 5 | 5 | 5 | 10 | 5 | 14 | 6 | 10 | 12 | 12 | 12 | 12 |  | 50 Ohms | TOP=L2:L3=L2/L4:L6=L5/L7:BOTTOM=L7 |
| MDC | OTHERS | BUS | 6 | 5 | 5 | 10 | 5 | 14 | 6 | 10 | 12 | 12 | 12 | 12 |  | 50 Ohms | TOP=L2:L3=L2/L4:L6=L5/L7:BOTTOM=L7 |
| MDC | OTHERS | BUS | 7 | 5 | 5 | 10 | 5 | 14 | 6 | 10 | 12 | 12 | 12 | 12 |  | 50 Ohms | TOP=L2:L3=L2/L4:L6=L5/L7:BOTTOM=L7 |
| MDC | OTHERS | BUS | 8 | 4.75 | 5 | 10 | 5 | 14 | 6 | 9.5 | 12 | 12 | 12 | 12 |  | 50 Ohms | TOP=L2:L3=L2/L4:L6=L5/L7:BOTTOM=L7 |
| MDIO | OTHERS | BUS | 1 | 4.75 | 5 | 10 | 5 | 14 | 6 | 9.5 | 12 | 12 | 12 | 12 |  | 50 Ohms | TOP=L2:L3=L2/L4:L6=L5/L7:BOTTOM=L7 |
| MDIO | OTHERS | BUS | 2 | 5 | 5 | 10 | 5 | 14 | 6 | 10 | 12 | 12 | 12 | 12 |  | 50 Ohms | TOP=L2:L3=L2/L4:L6=L5/L7:BOTTOM=L7 |
| MDIO | OTHERS | BUS | 3 | 5 | 5 | 10 | 5 | 14 | 6 | 10 | 12 | 12 | 12 | 12 |  | 50 Ohms | TOP=L2:L3=L2/L4:L6=L5/L7:BOTTOM=L7 |
| MDIO | OTHERS | BUS | 4 | 5 | 5 | 10 | 5 | 14 | 6 | 10 | 12 | 12 | 12 | 12 |  | 50 Ohms | TOP=L2:L3=L2/L4:L6=L5/L7:BOTTOM=L7 |
| MDIO | OTHERS | BUS | 5 | 5 | 5 | 10 | 5 | 14 | 6 | 10 | 12 | 12 | 12 | 12 |  | 50 Ohms | TOP=L2:L3=L2/L4:L6=L5/L7:BOTTOM=L7 |
| MDIO | OTHERS | BUS | 6 | 5 | 5 | 10 | 5 | 14 | 6 | 10 | 12 | 12 | 12 | 12 |  | 50 Ohms | TOP=L2:L3=L2/L4:L6=L5/L7:BOTTOM=L7 |
| MDIO | OTHERS | BUS | 7 | 5 | 5 | 10 | 5 | 14 | 6 | 10 | 12 | 12 | 12 | 12 |  | 50 Ohms | TOP=L2:L3=L2/L4:L6=L5/L7:BOTTOM=L7 |
| MDIO | OTHERS | BUS | 8 | 4.75 | 5 | 10 | 5 | 14 | 6 | 9.5 | 12 | 12 | 12 | 12 |  | 50 Ohms | TOP=L2:L3=L2/L4:L6=L5/L7:BOTTOM=L7 |
| MEMA_0 | OTHERS | BUS | 1 | 4.75 | 5 | 10 | 5 | 14 | 6 | 9.5 | 12 | 12 | 12 | 12 |  | 50 Ohms | TOP=L2:L3=L2/L4:L6=L5/L7:BOTTOM=L7 |
| MEMA_0 | OTHERS | BUS | 2 | 5 | 5 | 10 | 5 | 14 | 6 | 10 | 12 | 12 | 12 | 12 |  | 50 Ohms | TOP=L2:L3=L2/L4:L6=L5/L7:BOTTOM=L7 |
| MEMA_0 | OTHERS | BUS | 3 | 5 | 5 | 10 | 5 | 14 | 6 | 10 | 12 | 12 | 12 | 12 |  | 50 Ohms | TOP=L2:L3=L2/L4:L6=L5/L7:BOTTOM=L7 |
| MEMA_0 | OTHERS | BUS | 4 | 5 | 5 | 10 | 5 | 14 | 6 | 10 | 12 | 12 | 12 | 12 |  | 50 Ohms | TOP=L2:L3=L2/L4:L6=L5/L7:BOTTOM=L7 |
| MEMA_0 | OTHERS | BUS | 5 | 5 | 5 | 10 | 5 | 14 | 6 | 10 | 12 | 12 | 12 | 12 |  | 50 Ohms | TOP=L2:L3=L2/L4:L6=L5/L7:BOTTOM=L7 |
| MEMA_0 | OTHERS | BUS | 6 | 5 | 5 | 10 | 5 | 14 | 6 | 10 | 12 | 12 | 12 | 12 |  | 50 Ohms | TOP=L2:L3=L2/L4:L6=L5/L7:BOTTOM=L7 |
| MEMA_0 | OTHERS | BUS | 7 | 5 | 5 | 10 | 5 | 14 | 6 | 10 | 12 | 12 | 12 | 12 |  | 50 Ohms | TOP=L2:L3=L2/L4:L6=L5/L7:BOTTOM=L7 |
| MEMA_0 | OTHERS | BUS | 8 | 4.75 | 5 | 10 | 5 | 14 | 6 | 9.5 | 12 | 12 | 12 | 12 |  | 50 Ohms | TOP=L2:L3=L2/L4:L6=L5/L7:BOTTOM=L7 |
| MEMA_1 | OTHERS | BUS | 1 | 4.75 | 5 | 10 | 5 | 14 | 6 | 9.5 | 12 | 12 | 12 | 12 |  | 50 Ohms | TOP=L2:L3=L2/L4:L6=L5/L7:BOTTOM=L7 |
| MEMA_1 | OTHERS | BUS | 2 | 5 | 5 | 10 | 5 | 14 | 6 | 10 | 12 | 12 | 12 | 12 |  | 50 Ohms | TOP=L2:L3=L2/L4:L6=L5/L7:BOTTOM=L7 |
| MEMA_1 | OTHERS | BUS | 3 | 5 | 5 | 10 | 5 | 14 | 6 | 10 | 12 | 12 | 12 | 12 |  | 50 Ohms | TOP=L2:L3=L2/L4:L6=L5/L7:BOTTOM=L7 |
| MEMA_1 | OTHERS | BUS | 4 | 5 | 5 | 10 | 5 | 14 | 6 | 10 | 12 | 12 | 12 | 12 |  | 50 Ohms | TOP=L2:L3=L2/L4:L6=L5/L7:BOTTOM=L7 |
| MEMA_1 | OTHERS | BUS | 5 | 5 | 5 | 10 | 5 | 14 | 6 | 10 | 12 | 12 | 12 | 12 |  | 50 Ohms | TOP=L2:L3=L2/L4:L6=L5/L7:BOTTOM=L7 |
| MEMA_1 | OTHERS | BUS | 6 | 5 | 5 | 10 | 5 | 14 | 6 | 10 | 12 | 12 | 12 | 12 |  | 50 Ohms | TOP=L2:L3=L2/L4:L6=L5/L7:BOTTOM=L7 |
| MEMA_1 | OTHERS | BUS | 7 | 5 | 5 | 10 | 5 | 14 | 6 | 10 | 12 | 12 | 12 | 12 |  | 50 Ohms | TOP=L2:L3=L2/L4:L6=L5/L7:BOTTOM=L7 |
| MEMA_1 | OTHERS | BUS | 8 | 4.75 | 5 | 10 | 5 | 14 | 6 | 9.5 | 12 | 12 | 12 | 12 |  | 50 Ohms | TOP=L2:L3=L2/L4:L6=L5/L7:BOTTOM=L7 |
| MEMA_10 | OTHERS | BUS | 1 | 4.75 | 5 | 10 | 5 | 14 | 6 | 9.5 | 12 | 12 | 12 | 12 |  | 50 Ohms | TOP=L2:L3=L2/L4:L6=L5/L7:BOTTOM=L7 |
| MEMA_10 | OTHERS | BUS | 2 | 5 | 5 | 10 | 5 | 14 | 6 | 10 | 12 | 12 | 12 | 12 |  | 50 Ohms | TOP=L2:L3=L2/L4:L6=L5/L7:BOTTOM=L7 |
| MEMA_10 | OTHERS | BUS | 3 | 5 | 5 | 10 | 5 | 14 | 6 | 10 | 12 | 12 | 12 | 12 |  | 50 Ohms | TOP=L2:L3=L2/L4:L6=L5/L7:BOTTOM=L7 |
| MEMA_10 | OTHERS | BUS | 4 | 5 | 5 | 10 | 5 | 14 | 6 | 10 | 12 | 12 | 12 | 12 |  | 50 Ohms | TOP=L2:L3=L2/L4:L6=L5/L7:BOTTOM=L7 |
| MEMA_10 | OTHERS | BUS | 5 | 5 | 5 | 10 | 5 | 14 | 6 | 10 | 12 | 12 | 12 | 12 |  | 50 Ohms | TOP=L2:L3=L2/L4:L6=L5/L7:BOTTOM=L7 |
| MEMA_10 | OTHERS | BUS | 6 | 5 | 5 | 10 | 5 | 14 | 6 | 10 | 12 | 12 | 12 | 12 |  | 50 Ohms | TOP=L2:L3=L2/L4:L6=L5/L7:BOTTOM=L7 |
| MEMA_10 | OTHERS | BUS | 7 | 5 | 5 | 10 | 5 | 14 | 6 | 10 | 12 | 12 | 12 | 12 |  | 50 Ohms | TOP=L2:L3=L2/L4:L6=L5/L7:BOTTOM=L7 |
| MEMA_10 | OTHERS | BUS | 8 | 4.75 | 5 | 10 | 5 | 14 | 6 | 9.5 | 12 | 12 | 12 | 12 |  | 50 Ohms | TOP=L2:L3=L2/L4:L6=L5/L7:BOTTOM=L7 |
| MEMA_11 | OTHERS | BUS | 1 | 4.75 | 5 | 10 | 5 | 14 | 6 | 9.5 | 12 | 12 | 12 | 12 |  | 50 Ohms | TOP=L2:L3=L2/L4:L6=L5/L7:BOTTOM=L7 |
| MEMA_11 | OTHERS | BUS | 2 | 5 | 5 | 10 | 5 | 14 | 6 | 10 | 12 | 12 | 12 | 12 |  | 50 Ohms | TOP=L2:L3=L2/L4:L6=L5/L7:BOTTOM=L7 |
| MEMA_11 | OTHERS | BUS | 3 | 5 | 5 | 10 | 5 | 14 | 6 | 10 | 12 | 12 | 12 | 12 |  | 50 Ohms | TOP=L2:L3=L2/L4:L6=L5/L7:BOTTOM=L7 |
| MEMA_11 | OTHERS | BUS | 4 | 5 | 5 | 10 | 5 | 14 | 6 | 10 | 12 | 12 | 12 | 12 |  | 50 Ohms | TOP=L2:L3=L2/L4:L6=L5/L7:BOTTOM=L7 |
| MEMA_11 | OTHERS | BUS | 5 | 5 | 5 | 10 | 5 | 14 | 6 | 10 | 12 | 12 | 12 | 12 |  | 50 Ohms | TOP=L2:L3=L2/L4:L6=L5/L7:BOTTOM=L7 |
| MEMA_11 | OTHERS | BUS | 6 | 5 | 5 | 10 | 5 | 14 | 6 | 10 | 12 | 12 | 12 | 12 |  | 50 Ohms | TOP=L2:L3=L2/L4:L6=L5/L7:BOTTOM=L7 |
| MEMA_11 | OTHERS | BUS | 7 | 5 | 5 | 10 | 5 | 14 | 6 | 10 | 12 | 12 | 12 | 12 |  | 50 Ohms | TOP=L2:L3=L2/L4:L6=L5/L7:BOTTOM=L7 |
| MEMA_11 | OTHERS | BUS | 8 | 4.75 | 5 | 10 | 5 | 14 | 6 | 9.5 | 12 | 12 | 12 | 12 |  | 50 Ohms | TOP=L2:L3=L2/L4:L6=L5/L7:BOTTOM=L7 |
| MEMA_12 | OTHERS | BUS | 1 | 4.75 | 5 | 10 | 5 | 14 | 6 | 9.5 | 12 | 12 | 12 | 12 |  | 50 Ohms | TOP=L2:L3=L2/L4:L6=L5/L7:BOTTOM=L7 |
| MEMA_12 | OTHERS | BUS | 2 | 5 | 5 | 10 | 5 | 14 | 6 | 10 | 12 | 12 | 12 | 12 |  | 50 Ohms | TOP=L2:L3=L2/L4:L6=L5/L7:BOTTOM=L7 |
| MEMA_12 | OTHERS | BUS | 3 | 5 | 5 | 10 | 5 | 14 | 6 | 10 | 12 | 12 | 12 | 12 |  | 50 Ohms | TOP=L2:L3=L2/L4:L6=L5/L7:BOTTOM=L7 |
| MEMA_12 | OTHERS | BUS | 4 | 5 | 5 | 10 | 5 | 14 | 6 | 10 | 12 | 12 | 12 | 12 |  | 50 Ohms | TOP=L2:L3=L2/L4:L6=L5/L7:BOTTOM=L7 |
| MEMA_12 | OTHERS | BUS | 5 | 5 | 5 | 10 | 5 | 14 | 6 | 10 | 12 | 12 | 12 | 12 |  | 50 Ohms | TOP=L2:L3=L2/L4:L6=L5/L7:BOTTOM=L7 |
| MEMA_12 | OTHERS | BUS | 6 | 5 | 5 | 10 | 5 | 14 | 6 | 10 | 12 | 12 | 12 | 12 |  | 50 Ohms | TOP=L2:L3=L2/L4:L6=L5/L7:BOTTOM=L7 |
| MEMA_12 | OTHERS | BUS | 7 | 5 | 5 | 10 | 5 | 14 | 6 | 10 | 12 | 12 | 12 | 12 |  | 50 Ohms | TOP=L2:L3=L2/L4:L6=L5/L7:BOTTOM=L7 |
| MEMA_12 | OTHERS | BUS | 8 | 4.75 | 5 | 10 | 5 | 14 | 6 | 9.5 | 12 | 12 | 12 | 12 |  | 50 Ohms | TOP=L2:L3=L2/L4:L6=L5/L7:BOTTOM=L7 |
| MEMA_13 | OTHERS | BUS | 1 | 4.75 | 5 | 10 | 5 | 14 | 6 | 9.5 | 12 | 12 | 12 | 12 |  | 50 Ohms | TOP=L2:L3=L2/L4:L6=L5/L7:BOTTOM=L7 |
| MEMA_13 | OTHERS | BUS | 2 | 5 | 5 | 10 | 5 | 14 | 6 | 10 | 12 | 12 | 12 | 12 |  | 50 Ohms | TOP=L2:L3=L2/L4:L6=L5/L7:BOTTOM=L7 |
| MEMA_13 | OTHERS | BUS | 3 | 5 | 5 | 10 | 5 | 14 | 6 | 10 | 12 | 12 | 12 | 12 |  | 50 Ohms | TOP=L2:L3=L2/L4:L6=L5/L7:BOTTOM=L7 |
| MEMA_13 | OTHERS | BUS | 4 | 5 | 5 | 10 | 5 | 14 | 6 | 10 | 12 | 12 | 12 | 12 |  | 50 Ohms | TOP=L2:L3=L2/L4:L6=L5/L7:BOTTOM=L7 |
| MEMA_13 | OTHERS | BUS | 5 | 5 | 5 | 10 | 5 | 14 | 6 | 10 | 12 | 12 | 12 | 12 |  | 50 Ohms | TOP=L2:L3=L2/L4:L6=L5/L7:BOTTOM=L7 |
| MEMA_13 | OTHERS | BUS | 6 | 5 | 5 | 10 | 5 | 14 | 6 | 10 | 12 | 12 | 12 | 12 |  | 50 Ohms | TOP=L2:L3=L2/L4:L6=L5/L7:BOTTOM=L7 |
| MEMA_13 | OTHERS | BUS | 7 | 5 | 5 | 10 | 5 | 14 | 6 | 10 | 12 | 12 | 12 | 12 |  | 50 Ohms | TOP=L2:L3=L2/L4:L6=L5/L7:BOTTOM=L7 |
| MEMA_13 | OTHERS | BUS | 8 | 4.75 | 5 | 10 | 5 | 14 | 6 | 9.5 | 12 | 12 | 12 | 12 |  | 50 Ohms | TOP=L2:L3=L2/L4:L6=L5/L7:BOTTOM=L7 |
| MEMA_14 | OTHERS | BUS | 1 | 4.75 | 5 | 10 | 5 | 14 | 6 | 9.5 | 12 | 12 | 12 | 12 |  | 50 Ohms | TOP=L2:L3=L2/L4:L6=L5/L7:BOTTOM=L7 |
| MEMA_14 | OTHERS | BUS | 2 | 5 | 5 | 10 | 5 | 14 | 6 | 10 | 12 | 12 | 12 | 12 |  | 50 Ohms | TOP=L2:L3=L2/L4:L6=L5/L7:BOTTOM=L7 |
| MEMA_14 | OTHERS | BUS | 3 | 5 | 5 | 10 | 5 | 14 | 6 | 10 | 12 | 12 | 12 | 12 |  | 50 Ohms | TOP=L2:L3=L2/L4:L6=L5/L7:BOTTOM=L7 |
| MEMA_14 | OTHERS | BUS | 4 | 5 | 5 | 10 | 5 | 14 | 6 | 10 | 12 | 12 | 12 | 12 |  | 50 Ohms | TOP=L2:L3=L2/L4:L6=L5/L7:BOTTOM=L7 |
| MEMA_14 | OTHERS | BUS | 5 | 5 | 5 | 10 | 5 | 14 | 6 | 10 | 12 | 12 | 12 | 12 |  | 50 Ohms | TOP=L2:L3=L2/L4:L6=L5/L7:BOTTOM=L7 |
| MEMA_14 | OTHERS | BUS | 6 | 5 | 5 | 10 | 5 | 14 | 6 | 10 | 12 | 12 | 12 | 12 |  | 50 Ohms | TOP=L2:L3=L2/L4:L6=L5/L7:BOTTOM=L7 |
| MEMA_14 | OTHERS | BUS | 7 | 5 | 5 | 10 | 5 | 14 | 6 | 10 | 12 | 12 | 12 | 12 |  | 50 Ohms | TOP=L2:L3=L2/L4:L6=L5/L7:BOTTOM=L7 |
| MEMA_14 | OTHERS | BUS | 8 | 4.75 | 5 | 10 | 5 | 14 | 6 | 9.5 | 12 | 12 | 12 | 12 |  | 50 Ohms | TOP=L2:L3=L2/L4:L6=L5/L7:BOTTOM=L7 |
| MEMA_2 | OTHERS | BUS | 1 | 4.75 | 5 | 10 | 5 | 14 | 6 | 9.5 | 12 | 12 | 12 | 12 |  | 50 Ohms | TOP=L2:L3=L2/L4:L6=L5/L7:BOTTOM=L7 |
| MEMA_2 | OTHERS | BUS | 2 | 5 | 5 | 10 | 5 | 14 | 6 | 10 | 12 | 12 | 12 | 12 |  | 50 Ohms | TOP=L2:L3=L2/L4:L6=L5/L7:BOTTOM=L7 |
| MEMA_2 | OTHERS | BUS | 3 | 5 | 5 | 10 | 5 | 14 | 6 | 10 | 12 | 12 | 12 | 12 |  | 50 Ohms | TOP=L2:L3=L2/L4:L6=L5/L7:BOTTOM=L7 |
| MEMA_2 | OTHERS | BUS | 4 | 5 | 5 | 10 | 5 | 14 | 6 | 10 | 12 | 12 | 12 | 12 |  | 50 Ohms | TOP=L2:L3=L2/L4:L6=L5/L7:BOTTOM=L7 |
| MEMA_2 | OTHERS | BUS | 5 | 5 | 5 | 10 | 5 | 14 | 6 | 10 | 12 | 12 | 12 | 12 |  | 50 Ohms | TOP=L2:L3=L2/L4:L6=L5/L7:BOTTOM=L7 |
| MEMA_2 | OTHERS | BUS | 6 | 5 | 5 | 10 | 5 | 14 | 6 | 10 | 12 | 12 | 12 | 12 |  | 50 Ohms | TOP=L2:L3=L2/L4:L6=L5/L7:BOTTOM=L7 |
| MEMA_2 | OTHERS | BUS | 7 | 5 | 5 | 10 | 5 | 14 | 6 | 10 | 12 | 12 | 12 | 12 |  | 50 Ohms | TOP=L2:L3=L2/L4:L6=L5/L7:BOTTOM=L7 |
| MEMA_2 | OTHERS | BUS | 8 | 4.75 | 5 | 10 | 5 | 14 | 6 | 9.5 | 12 | 12 | 12 | 12 |  | 50 Ohms | TOP=L2:L3=L2/L4:L6=L5/L7:BOTTOM=L7 |
| MEMA_3 | OTHERS | BUS | 1 | 4.75 | 5 | 10 | 5 | 14 | 6 | 9.5 | 12 | 12 | 12 | 12 |  | 50 Ohms | TOP=L2:L3=L2/L4:L6=L5/L7:BOTTOM=L7 |
| MEMA_3 | OTHERS | BUS | 2 | 5 | 5 | 10 | 5 | 14 | 6 | 10 | 12 | 12 | 12 | 12 |  | 50 Ohms | TOP=L2:L3=L2/L4:L6=L5/L7:BOTTOM=L7 |
| MEMA_3 | OTHERS | BUS | 3 | 5 | 5 | 10 | 5 | 14 | 6 | 10 | 12 | 12 | 12 | 12 |  | 50 Ohms | TOP=L2:L3=L2/L4:L6=L5/L7:BOTTOM=L7 |
| MEMA_3 | OTHERS | BUS | 4 | 5 | 5 | 10 | 5 | 14 | 6 | 10 | 12 | 12 | 12 | 12 |  | 50 Ohms | TOP=L2:L3=L2/L4:L6=L5/L7:BOTTOM=L7 |
| MEMA_3 | OTHERS | BUS | 5 | 5 | 5 | 10 | 5 | 14 | 6 | 10 | 12 | 12 | 12 | 12 |  | 50 Ohms | TOP=L2:L3=L2/L4:L6=L5/L7:BOTTOM=L7 |
| MEMA_3 | OTHERS | BUS | 6 | 5 | 5 | 10 | 5 | 14 | 6 | 10 | 12 | 12 | 12 | 12 |  | 50 Ohms | TOP=L2:L3=L2/L4:L6=L5/L7:BOTTOM=L7 |
| MEMA_3 | OTHERS | BUS | 7 | 5 | 5 | 10 | 5 | 14 | 6 | 10 | 12 | 12 | 12 | 12 |  | 50 Ohms | TOP=L2:L3=L2/L4:L6=L5/L7:BOTTOM=L7 |
| MEMA_3 | OTHERS | BUS | 8 | 4.75 | 5 | 10 | 5 | 14 | 6 | 9.5 | 12 | 12 | 12 | 12 |  | 50 Ohms | TOP=L2:L3=L2/L4:L6=L5/L7:BOTTOM=L7 |
| MEMA_4 | OTHERS | BUS | 1 | 4.75 | 5 | 10 | 5 | 14 | 6 | 9.5 | 12 | 12 | 12 | 12 |  | 50 Ohms | TOP=L2:L3=L2/L4:L6=L5/L7:BOTTOM=L7 |
| MEMA_4 | OTHERS | BUS | 2 | 5 | 5 | 10 | 5 | 14 | 6 | 10 | 12 | 12 | 12 | 12 |  | 50 Ohms | TOP=L2:L3=L2/L4:L6=L5/L7:BOTTOM=L7 |
| MEMA_4 | OTHERS | BUS | 3 | 5 | 5 | 10 | 5 | 14 | 6 | 10 | 12 | 12 | 12 | 12 |  | 50 Ohms | TOP=L2:L3=L2/L4:L6=L5/L7:BOTTOM=L7 |
| MEMA_4 | OTHERS | BUS | 4 | 5 | 5 | 10 | 5 | 14 | 6 | 10 | 12 | 12 | 12 | 12 |  | 50 Ohms | TOP=L2:L3=L2/L4:L6=L5/L7:BOTTOM=L7 |
| MEMA_4 | OTHERS | BUS | 5 | 5 | 5 | 10 | 5 | 14 | 6 | 10 | 12 | 12 | 12 | 12 |  | 50 Ohms | TOP=L2:L3=L2/L4:L6=L5/L7:BOTTOM=L7 |
| MEMA_4 | OTHERS | BUS | 6 | 5 | 5 | 10 | 5 | 14 | 6 | 10 | 12 | 12 | 12 | 12 |  | 50 Ohms | TOP=L2:L3=L2/L4:L6=L5/L7:BOTTOM=L7 |
| MEMA_4 | OTHERS | BUS | 7 | 5 | 5 | 10 | 5 | 14 | 6 | 10 | 12 | 12 | 12 | 12 |  | 50 Ohms | TOP=L2:L3=L2/L4:L6=L5/L7:BOTTOM=L7 |
| MEMA_4 | OTHERS | BUS | 8 | 4.75 | 5 | 10 | 5 | 14 | 6 | 9.5 | 12 | 12 | 12 | 12 |  | 50 Ohms | TOP=L2:L3=L2/L4:L6=L5/L7:BOTTOM=L7 |
| MEMA_5 | OTHERS | BUS | 1 | 4.75 | 5 | 10 | 5 | 14 | 6 | 9.5 | 12 | 12 | 12 | 12 |  | 50 Ohms | TOP=L2:L3=L2/L4:L6=L5/L7:BOTTOM=L7 |
| MEMA_5 | OTHERS | BUS | 2 | 5 | 5 | 10 | 5 | 14 | 6 | 10 | 12 | 12 | 12 | 12 |  | 50 Ohms | TOP=L2:L3=L2/L4:L6=L5/L7:BOTTOM=L7 |
| MEMA_5 | OTHERS | BUS | 3 | 5 | 5 | 10 | 5 | 14 | 6 | 10 | 12 | 12 | 12 | 12 |  | 50 Ohms | TOP=L2:L3=L2/L4:L6=L5/L7:BOTTOM=L7 |
| MEMA_5 | OTHERS | BUS | 4 | 5 | 5 | 10 | 5 | 14 | 6 | 10 | 12 | 12 | 12 | 12 |  | 50 Ohms | TOP=L2:L3=L2/L4:L6=L5/L7:BOTTOM=L7 |
| MEMA_5 | OTHERS | BUS | 5 | 5 | 5 | 10 | 5 | 14 | 6 | 10 | 12 | 12 | 12 | 12 |  | 50 Ohms | TOP=L2:L3=L2/L4:L6=L5/L7:BOTTOM=L7 |
| MEMA_5 | OTHERS | BUS | 6 | 5 | 5 | 10 | 5 | 14 | 6 | 10 | 12 | 12 | 12 | 12 |  | 50 Ohms | TOP=L2:L3=L2/L4:L6=L5/L7:BOTTOM=L7 |
| MEMA_5 | OTHERS | BUS | 7 | 5 | 5 | 10 | 5 | 14 | 6 | 10 | 12 | 12 | 12 | 12 |  | 50 Ohms | TOP=L2:L3=L2/L4:L6=L5/L7:BOTTOM=L7 |
| MEMA_5 | OTHERS | BUS | 8 | 4.75 | 5 | 10 | 5 | 14 | 6 | 9.5 | 12 | 12 | 12 | 12 |  | 50 Ohms | TOP=L2:L3=L2/L4:L6=L5/L7:BOTTOM=L7 |
| MEMA_6 | OTHERS | BUS | 1 | 4.75 | 5 | 10 | 5 | 14 | 6 | 9.5 | 12 | 12 | 12 | 12 |  | 50 Ohms | TOP=L2:L3=L2/L4:L6=L5/L7:BOTTOM=L7 |
| MEMA_6 | OTHERS | BUS | 2 | 5 | 5 | 10 | 5 | 14 | 6 | 10 | 12 | 12 | 12 | 12 |  | 50 Ohms | TOP=L2:L3=L2/L4:L6=L5/L7:BOTTOM=L7 |
| MEMA_6 | OTHERS | BUS | 3 | 5 | 5 | 10 | 5 | 14 | 6 | 10 | 12 | 12 | 12 | 12 |  | 50 Ohms | TOP=L2:L3=L2/L4:L6=L5/L7:BOTTOM=L7 |
| MEMA_6 | OTHERS | BUS | 4 | 5 | 5 | 10 | 5 | 14 | 6 | 10 | 12 | 12 | 12 | 12 |  | 50 Ohms | TOP=L2:L3=L2/L4:L6=L5/L7:BOTTOM=L7 |
| MEMA_6 | OTHERS | BUS | 5 | 5 | 5 | 10 | 5 | 14 | 6 | 10 | 12 | 12 | 12 | 12 |  | 50 Ohms | TOP=L2:L3=L2/L4:L6=L5/L7:BOTTOM=L7 |
| MEMA_6 | OTHERS | BUS | 6 | 5 | 5 | 10 | 5 | 14 | 6 | 10 | 12 | 12 | 12 | 12 |  | 50 Ohms | TOP=L2:L3=L2/L4:L6=L5/L7:BOTTOM=L7 |
| MEMA_6 | OTHERS | BUS | 7 | 5 | 5 | 10 | 5 | 14 | 6 | 10 | 12 | 12 | 12 | 12 |  | 50 Ohms | TOP=L2:L3=L2/L4:L6=L5/L7:BOTTOM=L7 |
| MEMA_6 | OTHERS | BUS | 8 | 4.75 | 5 | 10 | 5 | 14 | 6 | 9.5 | 12 | 12 | 12 | 12 |  | 50 Ohms | TOP=L2:L3=L2/L4:L6=L5/L7:BOTTOM=L7 |
| MEMA_7 | OTHERS | BUS | 1 | 4.75 | 5 | 10 | 5 | 14 | 6 | 9.5 | 12 | 12 | 12 | 12 |  | 50 Ohms | TOP=L2:L3=L2/L4:L6=L5/L7:BOTTOM=L7 |
| MEMA_7 | OTHERS | BUS | 2 | 5 | 5 | 10 | 5 | 14 | 6 | 10 | 12 | 12 | 12 | 12 |  | 50 Ohms | TOP=L2:L3=L2/L4:L6=L5/L7:BOTTOM=L7 |
| MEMA_7 | OTHERS | BUS | 3 | 5 | 5 | 10 | 5 | 14 | 6 | 10 | 12 | 12 | 12 | 12 |  | 50 Ohms | TOP=L2:L3=L2/L4:L6=L5/L7:BOTTOM=L7 |
| MEMA_7 | OTHERS | BUS | 4 | 5 | 5 | 10 | 5 | 14 | 6 | 10 | 12 | 12 | 12 | 12 |  | 50 Ohms | TOP=L2:L3=L2/L4:L6=L5/L7:BOTTOM=L7 |
| MEMA_7 | OTHERS | BUS | 5 | 5 | 5 | 10 | 5 | 14 | 6 | 10 | 12 | 12 | 12 | 12 |  | 50 Ohms | TOP=L2:L3=L2/L4:L6=L5/L7:BOTTOM=L7 |
| MEMA_7 | OTHERS | BUS | 6 | 5 | 5 | 10 | 5 | 14 | 6 | 10 | 12 | 12 | 12 | 12 |  | 50 Ohms | TOP=L2:L3=L2/L4:L6=L5/L7:BOTTOM=L7 |
| MEMA_7 | OTHERS | BUS | 7 | 5 | 5 | 10 | 5 | 14 | 6 | 10 | 12 | 12 | 12 | 12 |  | 50 Ohms | TOP=L2:L3=L2/L4:L6=L5/L7:BOTTOM=L7 |
| MEMA_7 | OTHERS | BUS | 8 | 4.75 | 5 | 10 | 5 | 14 | 6 | 9.5 | 12 | 12 | 12 | 12 |  | 50 Ohms | TOP=L2:L3=L2/L4:L6=L5/L7:BOTTOM=L7 |
| MEMA_8 | OTHERS | BUS | 1 | 4.75 | 5 | 10 | 5 | 14 | 6 | 9.5 | 12 | 12 | 12 | 12 |  | 50 Ohms | TOP=L2:L3=L2/L4:L6=L5/L7:BOTTOM=L7 |
| MEMA_8 | OTHERS | BUS | 2 | 5 | 5 | 10 | 5 | 14 | 6 | 10 | 12 | 12 | 12 | 12 |  | 50 Ohms | TOP=L2:L3=L2/L4:L6=L5/L7:BOTTOM=L7 |
| MEMA_8 | OTHERS | BUS | 3 | 5 | 5 | 10 | 5 | 14 | 6 | 10 | 12 | 12 | 12 | 12 |  | 50 Ohms | TOP=L2:L3=L2/L4:L6=L5/L7:BOTTOM=L7 |
| MEMA_8 | OTHERS | BUS | 4 | 5 | 5 | 10 | 5 | 14 | 6 | 10 | 12 | 12 | 12 | 12 |  | 50 Ohms | TOP=L2:L3=L2/L4:L6=L5/L7:BOTTOM=L7 |
| MEMA_8 | OTHERS | BUS | 5 | 5 | 5 | 10 | 5 | 14 | 6 | 10 | 12 | 12 | 12 | 12 |  | 50 Ohms | TOP=L2:L3=L2/L4:L6=L5/L7:BOTTOM=L7 |
| MEMA_8 | OTHERS | BUS | 6 | 5 | 5 | 10 | 5 | 14 | 6 | 10 | 12 | 12 | 12 | 12 |  | 50 Ohms | TOP=L2:L3=L2/L4:L6=L5/L7:BOTTOM=L7 |
| MEMA_8 | OTHERS | BUS | 7 | 5 | 5 | 10 | 5 | 14 | 6 | 10 | 12 | 12 | 12 | 12 |  | 50 Ohms | TOP=L2:L3=L2/L4:L6=L5/L7:BOTTOM=L7 |
| MEMA_8 | OTHERS | BUS | 8 | 4.75 | 5 | 10 | 5 | 14 | 6 | 9.5 | 12 | 12 | 12 | 12 |  | 50 Ohms | TOP=L2:L3=L2/L4:L6=L5/L7:BOTTOM=L7 |
| MEMA_9 | OTHERS | BUS | 1 | 4.75 | 5 | 10 | 5 | 14 | 6 | 9.5 | 12 | 12 | 12 | 12 |  | 50 Ohms | TOP=L2:L3=L2/L4:L6=L5/L7:BOTTOM=L7 |
| MEMA_9 | OTHERS | BUS | 2 | 5 | 5 | 10 | 5 | 14 | 6 | 10 | 12 | 12 | 12 | 12 |  | 50 Ohms | TOP=L2:L3=L2/L4:L6=L5/L7:BOTTOM=L7 |
| MEMA_9 | OTHERS | BUS | 3 | 5 | 5 | 10 | 5 | 14 | 6 | 10 | 12 | 12 | 12 | 12 |  | 50 Ohms | TOP=L2:L3=L2/L4:L6=L5/L7:BOTTOM=L7 |
| MEMA_9 | OTHERS | BUS | 4 | 5 | 5 | 10 | 5 | 14 | 6 | 10 | 12 | 12 | 12 | 12 |  | 50 Ohms | TOP=L2:L3=L2/L4:L6=L5/L7:BOTTOM=L7 |
| MEMA_9 | OTHERS | BUS | 5 | 5 | 5 | 10 | 5 | 14 | 6 | 10 | 12 | 12 | 12 | 12 |  | 50 Ohms | TOP=L2:L3=L2/L4:L6=L5/L7:BOTTOM=L7 |
| MEMA_9 | OTHERS | BUS | 6 | 5 | 5 | 10 | 5 | 14 | 6 | 10 | 12 | 12 | 12 | 12 |  | 50 Ohms | TOP=L2:L3=L2/L4:L6=L5/L7:BOTTOM=L7 |
| MEMA_9 | OTHERS | BUS | 7 | 5 | 5 | 10 | 5 | 14 | 6 | 10 | 12 | 12 | 12 | 12 |  | 50 Ohms | TOP=L2:L3=L2/L4:L6=L5/L7:BOTTOM=L7 |
| MEMA_9 | OTHERS | BUS | 8 | 4.75 | 5 | 10 | 5 | 14 | 6 | 9.5 | 12 | 12 | 12 | 12 |  | 50 Ohms | TOP=L2:L3=L2/L4:L6=L5/L7:BOTTOM=L7 |
| MEMBA_0 | OTHERS | BUS | 1 | 4.75 | 5 | 10 | 5 | 14 | 6 | 9.5 | 12 | 12 | 12 | 12 |  | 50 Ohms | TOP=L2:L3=L2/L4:L6=L5/L7:BOTTOM=L7 |
| MEMBA_0 | OTHERS | BUS | 2 | 5 | 5 | 10 | 5 | 14 | 6 | 10 | 12 | 12 | 12 | 12 |  | 50 Ohms | TOP=L2:L3=L2/L4:L6=L5/L7:BOTTOM=L7 |
| MEMBA_0 | OTHERS | BUS | 3 | 5 | 5 | 10 | 5 | 14 | 6 | 10 | 12 | 12 | 12 | 12 |  | 50 Ohms | TOP=L2:L3=L2/L4:L6=L5/L7:BOTTOM=L7 |
| MEMBA_0 | OTHERS | BUS | 4 | 5 | 5 | 10 | 5 | 14 | 6 | 10 | 12 | 12 | 12 | 12 |  | 50 Ohms | TOP=L2:L3=L2/L4:L6=L5/L7:BOTTOM=L7 |
| MEMBA_0 | OTHERS | BUS | 5 | 5 | 5 | 10 | 5 | 14 | 6 | 10 | 12 | 12 | 12 | 12 |  | 50 Ohms | TOP=L2:L3=L2/L4:L6=L5/L7:BOTTOM=L7 |
| MEMBA_0 | OTHERS | BUS | 6 | 5 | 5 | 10 | 5 | 14 | 6 | 10 | 12 | 12 | 12 | 12 |  | 50 Ohms | TOP=L2:L3=L2/L4:L6=L5/L7:BOTTOM=L7 |
| MEMBA_0 | OTHERS | BUS | 7 | 5 | 5 | 10 | 5 | 14 | 6 | 10 | 12 | 12 | 12 | 12 |  | 50 Ohms | TOP=L2:L3=L2/L4:L6=L5/L7:BOTTOM=L7 |
| MEMBA_0 | OTHERS | BUS | 8 | 4.75 | 5 | 10 | 5 | 14 | 6 | 9.5 | 12 | 12 | 12 | 12 |  | 50 Ohms | TOP=L2:L3=L2/L4:L6=L5/L7:BOTTOM=L7 |
| MEMBA_1 | OTHERS | BUS | 1 | 4.75 | 5 | 10 | 5 | 14 | 6 | 9.5 | 12 | 12 | 12 | 12 |  | 50 Ohms | TOP=L2:L3=L2/L4:L6=L5/L7:BOTTOM=L7 |
| MEMBA_1 | OTHERS | BUS | 2 | 5 | 5 | 10 | 5 | 14 | 6 | 10 | 12 | 12 | 12 | 12 |  | 50 Ohms | TOP=L2:L3=L2/L4:L6=L5/L7:BOTTOM=L7 |
| MEMBA_1 | OTHERS | BUS | 3 | 5 | 5 | 10 | 5 | 14 | 6 | 10 | 12 | 12 | 12 | 12 |  | 50 Ohms | TOP=L2:L3=L2/L4:L6=L5/L7:BOTTOM=L7 |
| MEMBA_1 | OTHERS | BUS | 4 | 5 | 5 | 10 | 5 | 14 | 6 | 10 | 12 | 12 | 12 | 12 |  | 50 Ohms | TOP=L2:L3=L2/L4:L6=L5/L7:BOTTOM=L7 |
| MEMBA_1 | OTHERS | BUS | 5 | 5 | 5 | 10 | 5 | 14 | 6 | 10 | 12 | 12 | 12 | 12 |  | 50 Ohms | TOP=L2:L3=L2/L4:L6=L5/L7:BOTTOM=L7 |
| MEMBA_1 | OTHERS | BUS | 6 | 5 | 5 | 10 | 5 | 14 | 6 | 10 | 12 | 12 | 12 | 12 |  | 50 Ohms | TOP=L2:L3=L2/L4:L6=L5/L7:BOTTOM=L7 |
| MEMBA_1 | OTHERS | BUS | 7 | 5 | 5 | 10 | 5 | 14 | 6 | 10 | 12 | 12 | 12 | 12 |  | 50 Ohms | TOP=L2:L3=L2/L4:L6=L5/L7:BOTTOM=L7 |
| MEMBA_1 | OTHERS | BUS | 8 | 4.75 | 5 | 10 | 5 | 14 | 6 | 9.5 | 12 | 12 | 12 | 12 |  | 50 Ohms | TOP=L2:L3=L2/L4:L6=L5/L7:BOTTOM=L7 |
| MEMBA_2 | OTHERS | BUS | 1 | 4.75 | 5 | 10 | 5 | 14 | 6 | 9.5 | 12 | 12 | 12 | 12 |  | 50 Ohms | TOP=L2:L3=L2/L4:L6=L5/L7:BOTTOM=L7 |
| MEMBA_2 | OTHERS | BUS | 2 | 5 | 5 | 10 | 5 | 14 | 6 | 10 | 12 | 12 | 12 | 12 |  | 50 Ohms | TOP=L2:L3=L2/L4:L6=L5/L7:BOTTOM=L7 |
| MEMBA_2 | OTHERS | BUS | 3 | 5 | 5 | 10 | 5 | 14 | 6 | 10 | 12 | 12 | 12 | 12 |  | 50 Ohms | TOP=L2:L3=L2/L4:L6=L5/L7:BOTTOM=L7 |
| MEMBA_2 | OTHERS | BUS | 4 | 5 | 5 | 10 | 5 | 14 | 6 | 10 | 12 | 12 | 12 | 12 |  | 50 Ohms | TOP=L2:L3=L2/L4:L6=L5/L7:BOTTOM=L7 |
| MEMBA_2 | OTHERS | BUS | 5 | 5 | 5 | 10 | 5 | 14 | 6 | 10 | 12 | 12 | 12 | 12 |  | 50 Ohms | TOP=L2:L3=L2/L4:L6=L5/L7:BOTTOM=L7 |
| MEMBA_2 | OTHERS | BUS | 6 | 5 | 5 | 10 | 5 | 14 | 6 | 10 | 12 | 12 | 12 | 12 |  | 50 Ohms | TOP=L2:L3=L2/L4:L6=L5/L7:BOTTOM=L7 |
| MEMBA_2 | OTHERS | BUS | 7 | 5 | 5 | 10 | 5 | 14 | 6 | 10 | 12 | 12 | 12 | 12 |  | 50 Ohms | TOP=L2:L3=L2/L4:L6=L5/L7:BOTTOM=L7 |
| MEMBA_2 | OTHERS | BUS | 8 | 4.75 | 5 | 10 | 5 | 14 | 6 | 9.5 | 12 | 12 | 12 | 12 |  | 50 Ohms | TOP=L2:L3=L2/L4:L6=L5/L7:BOTTOM=L7 |
| MEMCASN | OTHERS | BUS | 1 | 4.75 | 5 | 10 | 5 | 14 | 6 | 9.5 | 12 | 12 | 12 | 12 |  | 50 Ohms | TOP=L2:L3=L2/L4:L6=L5/L7:BOTTOM=L7 |
| MEMCASN | OTHERS | BUS | 2 | 5 | 5 | 10 | 5 | 14 | 6 | 10 | 12 | 12 | 12 | 12 |  | 50 Ohms | TOP=L2:L3=L2/L4:L6=L5/L7:BOTTOM=L7 |
| MEMCASN | OTHERS | BUS | 3 | 5 | 5 | 10 | 5 | 14 | 6 | 10 | 12 | 12 | 12 | 12 |  | 50 Ohms | TOP=L2:L3=L2/L4:L6=L5/L7:BOTTOM=L7 |
| MEMCASN | OTHERS | BUS | 4 | 5 | 5 | 10 | 5 | 14 | 6 | 10 | 12 | 12 | 12 | 12 |  | 50 Ohms | TOP=L2:L3=L2/L4:L6=L5/L7:BOTTOM=L7 |
| MEMCASN | OTHERS | BUS | 5 | 5 | 5 | 10 | 5 | 14 | 6 | 10 | 12 | 12 | 12 | 12 |  | 50 Ohms | TOP=L2:L3=L2/L4:L6=L5/L7:BOTTOM=L7 |
| MEMCASN | OTHERS | BUS | 6 | 5 | 5 | 10 | 5 | 14 | 6 | 10 | 12 | 12 | 12 | 12 |  | 50 Ohms | TOP=L2:L3=L2/L4:L6=L5/L7:BOTTOM=L7 |
| MEMCASN | OTHERS | BUS | 7 | 5 | 5 | 10 | 5 | 14 | 6 | 10 | 12 | 12 | 12 | 12 |  | 50 Ohms | TOP=L2:L3=L2/L4:L6=L5/L7:BOTTOM=L7 |
| MEMCASN | OTHERS | BUS | 8 | 4.75 | 5 | 10 | 5 | 14 | 6 | 9.5 | 12 | 12 | 12 | 12 |  | 50 Ohms | TOP=L2:L3=L2/L4:L6=L5/L7:BOTTOM=L7 |
| MEMCKE | OTHERS | BUS | 1 | 4.75 | 5 | 10 | 5 | 14 | 6 | 9.5 | 12 | 12 | 12 | 12 |  | 50 Ohms | TOP=L2:L3=L2/L4:L6=L5/L7:BOTTOM=L7 |
| MEMCKE | OTHERS | BUS | 2 | 5 | 5 | 10 | 5 | 14 | 6 | 10 | 12 | 12 | 12 | 12 |  | 50 Ohms | TOP=L2:L3=L2/L4:L6=L5/L7:BOTTOM=L7 |
| MEMCKE | OTHERS | BUS | 3 | 5 | 5 | 10 | 5 | 14 | 6 | 10 | 12 | 12 | 12 | 12 |  | 50 Ohms | TOP=L2:L3=L2/L4:L6=L5/L7:BOTTOM=L7 |
| MEMCKE | OTHERS | BUS | 4 | 5 | 5 | 10 | 5 | 14 | 6 | 10 | 12 | 12 | 12 | 12 |  | 50 Ohms | TOP=L2:L3=L2/L4:L6=L5/L7:BOTTOM=L7 |
| MEMCKE | OTHERS | BUS | 5 | 5 | 5 | 10 | 5 | 14 | 6 | 10 | 12 | 12 | 12 | 12 |  | 50 Ohms | TOP=L2:L3=L2/L4:L6=L5/L7:BOTTOM=L7 |
| MEMCKE | OTHERS | BUS | 6 | 5 | 5 | 10 | 5 | 14 | 6 | 10 | 12 | 12 | 12 | 12 |  | 50 Ohms | TOP=L2:L3=L2/L4:L6=L5/L7:BOTTOM=L7 |
| MEMCKE | OTHERS | BUS | 7 | 5 | 5 | 10 | 5 | 14 | 6 | 10 | 12 | 12 | 12 | 12 |  | 50 Ohms | TOP=L2:L3=L2/L4:L6=L5/L7:BOTTOM=L7 |
| MEMCKE | OTHERS | BUS | 8 | 4.75 | 5 | 10 | 5 | 14 | 6 | 9.5 | 12 | 12 | 12 | 12 |  | 50 Ohms | TOP=L2:L3=L2/L4:L6=L5/L7:BOTTOM=L7 |
| MEMCSN | OTHERS | BUS | 1 | 4.75 | 5 | 10 | 5 | 14 | 6 | 9.5 | 12 | 12 | 12 | 12 |  | 50 Ohms | TOP=L2:L3=L2/L4:L6=L5/L7:BOTTOM=L7 |
| MEMCSN | OTHERS | BUS | 2 | 5 | 5 | 10 | 5 | 14 | 6 | 10 | 12 | 12 | 12 | 12 |  | 50 Ohms | TOP=L2:L3=L2/L4:L6=L5/L7:BOTTOM=L7 |
| MEMCSN | OTHERS | BUS | 3 | 5 | 5 | 10 | 5 | 14 | 6 | 10 | 12 | 12 | 12 | 12 |  | 50 Ohms | TOP=L2:L3=L2/L4:L6=L5/L7:BOTTOM=L7 |
| MEMCSN | OTHERS | BUS | 4 | 5 | 5 | 10 | 5 | 14 | 6 | 10 | 12 | 12 | 12 | 12 |  | 50 Ohms | TOP=L2:L3=L2/L4:L6=L5/L7:BOTTOM=L7 |
| MEMCSN | OTHERS | BUS | 5 | 5 | 5 | 10 | 5 | 14 | 6 | 10 | 12 | 12 | 12 | 12 |  | 50 Ohms | TOP=L2:L3=L2/L4:L6=L5/L7:BOTTOM=L7 |
| MEMCSN | OTHERS | BUS | 6 | 5 | 5 | 10 | 5 | 14 | 6 | 10 | 12 | 12 | 12 | 12 |  | 50 Ohms | TOP=L2:L3=L2/L4:L6=L5/L7:BOTTOM=L7 |
| MEMCSN | OTHERS | BUS | 7 | 5 | 5 | 10 | 5 | 14 | 6 | 10 | 12 | 12 | 12 | 12 |  | 50 Ohms | TOP=L2:L3=L2/L4:L6=L5/L7:BOTTOM=L7 |
| MEMCSN | OTHERS | BUS | 8 | 4.75 | 5 | 10 | 5 | 14 | 6 | 9.5 | 12 | 12 | 12 | 12 |  | 50 Ohms | TOP=L2:L3=L2/L4:L6=L5/L7:BOTTOM=L7 |
| MEMDM_0 | OTHERS | BUS | 1 | 4.75 | 5 | 10 | 5 | 14 | 6 | 9.5 | 12 | 12 | 12 | 12 |  | 50 Ohms | TOP=L2:L3=L2/L4:L6=L5/L7:BOTTOM=L7 |
| MEMDM_0 | OTHERS | BUS | 2 | 5 | 5 | 10 | 5 | 14 | 6 | 10 | 12 | 12 | 12 | 12 |  | 50 Ohms | TOP=L2:L3=L2/L4:L6=L5/L7:BOTTOM=L7 |
| MEMDM_0 | OTHERS | BUS | 3 | 5 | 5 | 10 | 5 | 14 | 6 | 10 | 12 | 12 | 12 | 12 |  | 50 Ohms | TOP=L2:L3=L2/L4:L6=L5/L7:BOTTOM=L7 |
| MEMDM_0 | OTHERS | BUS | 4 | 5 | 5 | 10 | 5 | 14 | 6 | 10 | 12 | 12 | 12 | 12 |  | 50 Ohms | TOP=L2:L3=L2/L4:L6=L5/L7:BOTTOM=L7 |
| MEMDM_0 | OTHERS | BUS | 5 | 5 | 5 | 10 | 5 | 14 | 6 | 10 | 12 | 12 | 12 | 12 |  | 50 Ohms | TOP=L2:L3=L2/L4:L6=L5/L7:BOTTOM=L7 |
| MEMDM_0 | OTHERS | BUS | 6 | 5 | 5 | 10 | 5 | 14 | 6 | 10 | 12 | 12 | 12 | 12 |  | 50 Ohms | TOP=L2:L3=L2/L4:L6=L5/L7:BOTTOM=L7 |
| MEMDM_0 | OTHERS | BUS | 7 | 5 | 5 | 10 | 5 | 14 | 6 | 10 | 12 | 12 | 12 | 12 |  | 50 Ohms | TOP=L2:L3=L2/L4:L6=L5/L7:BOTTOM=L7 |
| MEMDM_0 | OTHERS | BUS | 8 | 4.75 | 5 | 10 | 5 | 14 | 6 | 9.5 | 12 | 12 | 12 | 12 |  | 50 Ohms | TOP=L2:L3=L2/L4:L6=L5/L7:BOTTOM=L7 |
| MEMDM_1 | OTHERS | BUS | 1 | 4.75 | 5 | 10 | 5 | 14 | 6 | 9.5 | 12 | 12 | 12 | 12 |  | 50 Ohms | TOP=L2:L3=L2/L4:L6=L5/L7:BOTTOM=L7 |
| MEMDM_1 | OTHERS | BUS | 2 | 5 | 5 | 10 | 5 | 14 | 6 | 10 | 12 | 12 | 12 | 12 |  | 50 Ohms | TOP=L2:L3=L2/L4:L6=L5/L7:BOTTOM=L7 |
| MEMDM_1 | OTHERS | BUS | 3 | 5 | 5 | 10 | 5 | 14 | 6 | 10 | 12 | 12 | 12 | 12 |  | 50 Ohms | TOP=L2:L3=L2/L4:L6=L5/L7:BOTTOM=L7 |
| MEMDM_1 | OTHERS | BUS | 4 | 5 | 5 | 10 | 5 | 14 | 6 | 10 | 12 | 12 | 12 | 12 |  | 50 Ohms | TOP=L2:L3=L2/L4:L6=L5/L7:BOTTOM=L7 |
| MEMDM_1 | OTHERS | BUS | 5 | 5 | 5 | 10 | 5 | 14 | 6 | 10 | 12 | 12 | 12 | 12 |  | 50 Ohms | TOP=L2:L3=L2/L4:L6=L5/L7:BOTTOM=L7 |
| MEMDM_1 | OTHERS | BUS | 6 | 5 | 5 | 10 | 5 | 14 | 6 | 10 | 12 | 12 | 12 | 12 |  | 50 Ohms | TOP=L2:L3=L2/L4:L6=L5/L7:BOTTOM=L7 |
| MEMDM_1 | OTHERS | BUS | 7 | 5 | 5 | 10 | 5 | 14 | 6 | 10 | 12 | 12 | 12 | 12 |  | 50 Ohms | TOP=L2:L3=L2/L4:L6=L5/L7:BOTTOM=L7 |
| MEMDM_1 | OTHERS | BUS | 8 | 4.75 | 5 | 10 | 5 | 14 | 6 | 9.5 | 12 | 12 | 12 | 12 |  | 50 Ohms | TOP=L2:L3=L2/L4:L6=L5/L7:BOTTOM=L7 |
| MEMDQ_0 | OTHERS | BUS | 1 | 4.75 | 5 | 10 | 5 | 14 | 6 | 9.5 | 12 | 12 | 12 | 12 |  | 50 Ohms | TOP=L2:L3=L2/L4:L6=L5/L7:BOTTOM=L7 |
| MEMDQ_0 | OTHERS | BUS | 2 | 5 | 5 | 10 | 5 | 14 | 6 | 10 | 12 | 12 | 12 | 12 |  | 50 Ohms | TOP=L2:L3=L2/L4:L6=L5/L7:BOTTOM=L7 |
| MEMDQ_0 | OTHERS | BUS | 3 | 5 | 5 | 10 | 5 | 14 | 6 | 10 | 12 | 12 | 12 | 12 |  | 50 Ohms | TOP=L2:L3=L2/L4:L6=L5/L7:BOTTOM=L7 |
| MEMDQ_0 | OTHERS | BUS | 4 | 5 | 5 | 10 | 5 | 14 | 6 | 10 | 12 | 12 | 12 | 12 |  | 50 Ohms | TOP=L2:L3=L2/L4:L6=L5/L7:BOTTOM=L7 |
| MEMDQ_0 | OTHERS | BUS | 5 | 5 | 5 | 10 | 5 | 14 | 6 | 10 | 12 | 12 | 12 | 12 |  | 50 Ohms | TOP=L2:L3=L2/L4:L6=L5/L7:BOTTOM=L7 |
| MEMDQ_0 | OTHERS | BUS | 6 | 5 | 5 | 10 | 5 | 14 | 6 | 10 | 12 | 12 | 12 | 12 |  | 50 Ohms | TOP=L2:L3=L2/L4:L6=L5/L7:BOTTOM=L7 |
| MEMDQ_0 | OTHERS | BUS | 7 | 5 | 5 | 10 | 5 | 14 | 6 | 10 | 12 | 12 | 12 | 12 |  | 50 Ohms | TOP=L2:L3=L2/L4:L6=L5/L7:BOTTOM=L7 |
| MEMDQ_0 | OTHERS | BUS | 8 | 4.75 | 5 | 10 | 5 | 14 | 6 | 9.5 | 12 | 12 | 12 | 12 |  | 50 Ohms | TOP=L2:L3=L2/L4:L6=L5/L7:BOTTOM=L7 |
| MEMDQ_1 | OTHERS | BUS | 1 | 4.75 | 5 | 10 | 5 | 14 | 6 | 9.5 | 12 | 12 | 12 | 12 |  | 50 Ohms | TOP=L2:L3=L2/L4:L6=L5/L7:BOTTOM=L7 |
| MEMDQ_1 | OTHERS | BUS | 2 | 5 | 5 | 10 | 5 | 14 | 6 | 10 | 12 | 12 | 12 | 12 |  | 50 Ohms | TOP=L2:L3=L2/L4:L6=L5/L7:BOTTOM=L7 |
| MEMDQ_1 | OTHERS | BUS | 3 | 5 | 5 | 10 | 5 | 14 | 6 | 10 | 12 | 12 | 12 | 12 |  | 50 Ohms | TOP=L2:L3=L2/L4:L6=L5/L7:BOTTOM=L7 |
| MEMDQ_1 | OTHERS | BUS | 4 | 5 | 5 | 10 | 5 | 14 | 6 | 10 | 12 | 12 | 12 | 12 |  | 50 Ohms | TOP=L2:L3=L2/L4:L6=L5/L7:BOTTOM=L7 |
| MEMDQ_1 | OTHERS | BUS | 5 | 5 | 5 | 10 | 5 | 14 | 6 | 10 | 12 | 12 | 12 | 12 |  | 50 Ohms | TOP=L2:L3=L2/L4:L6=L5/L7:BOTTOM=L7 |
| MEMDQ_1 | OTHERS | BUS | 6 | 5 | 5 | 10 | 5 | 14 | 6 | 10 | 12 | 12 | 12 | 12 |  | 50 Ohms | TOP=L2:L3=L2/L4:L6=L5/L7:BOTTOM=L7 |
| MEMDQ_1 | OTHERS | BUS | 7 | 5 | 5 | 10 | 5 | 14 | 6 | 10 | 12 | 12 | 12 | 12 |  | 50 Ohms | TOP=L2:L3=L2/L4:L6=L5/L7:BOTTOM=L7 |
| MEMDQ_1 | OTHERS | BUS | 8 | 4.75 | 5 | 10 | 5 | 14 | 6 | 9.5 | 12 | 12 | 12 | 12 |  | 50 Ohms | TOP=L2:L3=L2/L4:L6=L5/L7:BOTTOM=L7 |
| MEMDQ_10 | OTHERS | BUS | 1 | 4.75 | 5 | 10 | 5 | 14 | 6 | 9.5 | 12 | 12 | 12 | 12 |  | 50 Ohms | TOP=L2:L3=L2/L4:L6=L5/L7:BOTTOM=L7 |
| MEMDQ_10 | OTHERS | BUS | 2 | 5 | 5 | 10 | 5 | 14 | 6 | 10 | 12 | 12 | 12 | 12 |  | 50 Ohms | TOP=L2:L3=L2/L4:L6=L5/L7:BOTTOM=L7 |
| MEMDQ_10 | OTHERS | BUS | 3 | 5 | 5 | 10 | 5 | 14 | 6 | 10 | 12 | 12 | 12 | 12 |  | 50 Ohms | TOP=L2:L3=L2/L4:L6=L5/L7:BOTTOM=L7 |
| MEMDQ_10 | OTHERS | BUS | 4 | 5 | 5 | 10 | 5 | 14 | 6 | 10 | 12 | 12 | 12 | 12 |  | 50 Ohms | TOP=L2:L3=L2/L4:L6=L5/L7:BOTTOM=L7 |
| MEMDQ_10 | OTHERS | BUS | 5 | 5 | 5 | 10 | 5 | 14 | 6 | 10 | 12 | 12 | 12 | 12 |  | 50 Ohms | TOP=L2:L3=L2/L4:L6=L5/L7:BOTTOM=L7 |
| MEMDQ_10 | OTHERS | BUS | 6 | 5 | 5 | 10 | 5 | 14 | 6 | 10 | 12 | 12 | 12 | 12 |  | 50 Ohms | TOP=L2:L3=L2/L4:L6=L5/L7:BOTTOM=L7 |
| MEMDQ_10 | OTHERS | BUS | 7 | 5 | 5 | 10 | 5 | 14 | 6 | 10 | 12 | 12 | 12 | 12 |  | 50 Ohms | TOP=L2:L3=L2/L4:L6=L5/L7:BOTTOM=L7 |
| MEMDQ_10 | OTHERS | BUS | 8 | 4.75 | 5 | 10 | 5 | 14 | 6 | 9.5 | 12 | 12 | 12 | 12 |  | 50 Ohms | TOP=L2:L3=L2/L4:L6=L5/L7:BOTTOM=L7 |
| MEMDQ_11 | OTHERS | BUS | 1 | 4.75 | 5 | 10 | 5 | 14 | 6 | 9.5 | 12 | 12 | 12 | 12 |  | 50 Ohms | TOP=L2:L3=L2/L4:L6=L5/L7:BOTTOM=L7 |
| MEMDQ_11 | OTHERS | BUS | 2 | 5 | 5 | 10 | 5 | 14 | 6 | 10 | 12 | 12 | 12 | 12 |  | 50 Ohms | TOP=L2:L3=L2/L4:L6=L5/L7:BOTTOM=L7 |
| MEMDQ_11 | OTHERS | BUS | 3 | 5 | 5 | 10 | 5 | 14 | 6 | 10 | 12 | 12 | 12 | 12 |  | 50 Ohms | TOP=L2:L3=L2/L4:L6=L5/L7:BOTTOM=L7 |
| MEMDQ_11 | OTHERS | BUS | 4 | 5 | 5 | 10 | 5 | 14 | 6 | 10 | 12 | 12 | 12 | 12 |  | 50 Ohms | TOP=L2:L3=L2/L4:L6=L5/L7:BOTTOM=L7 |
| MEMDQ_11 | OTHERS | BUS | 5 | 5 | 5 | 10 | 5 | 14 | 6 | 10 | 12 | 12 | 12 | 12 |  | 50 Ohms | TOP=L2:L3=L2/L4:L6=L5/L7:BOTTOM=L7 |
| MEMDQ_11 | OTHERS | BUS | 6 | 5 | 5 | 10 | 5 | 14 | 6 | 10 | 12 | 12 | 12 | 12 |  | 50 Ohms | TOP=L2:L3=L2/L4:L6=L5/L7:BOTTOM=L7 |
| MEMDQ_11 | OTHERS | BUS | 7 | 5 | 5 | 10 | 5 | 14 | 6 | 10 | 12 | 12 | 12 | 12 |  | 50 Ohms | TOP=L2:L3=L2/L4:L6=L5/L7:BOTTOM=L7 |
| MEMDQ_11 | OTHERS | BUS | 8 | 4.75 | 5 | 10 | 5 | 14 | 6 | 9.5 | 12 | 12 | 12 | 12 |  | 50 Ohms | TOP=L2:L3=L2/L4:L6=L5/L7:BOTTOM=L7 |
| MEMDQ_12 | OTHERS | BUS | 1 | 4.75 | 5 | 10 | 5 | 14 | 6 | 9.5 | 12 | 12 | 12 | 12 |  | 50 Ohms | TOP=L2:L3=L2/L4:L6=L5/L7:BOTTOM=L7 |
| MEMDQ_12 | OTHERS | BUS | 2 | 5 | 5 | 10 | 5 | 14 | 6 | 10 | 12 | 12 | 12 | 12 |  | 50 Ohms | TOP=L2:L3=L2/L4:L6=L5/L7:BOTTOM=L7 |
| MEMDQ_12 | OTHERS | BUS | 3 | 5 | 5 | 10 | 5 | 14 | 6 | 10 | 12 | 12 | 12 | 12 |  | 50 Ohms | TOP=L2:L3=L2/L4:L6=L5/L7:BOTTOM=L7 |
| MEMDQ_12 | OTHERS | BUS | 4 | 5 | 5 | 10 | 5 | 14 | 6 | 10 | 12 | 12 | 12 | 12 |  | 50 Ohms | TOP=L2:L3=L2/L4:L6=L5/L7:BOTTOM=L7 |
| MEMDQ_12 | OTHERS | BUS | 5 | 5 | 5 | 10 | 5 | 14 | 6 | 10 | 12 | 12 | 12 | 12 |  | 50 Ohms | TOP=L2:L3=L2/L4:L6=L5/L7:BOTTOM=L7 |
| MEMDQ_12 | OTHERS | BUS | 6 | 5 | 5 | 10 | 5 | 14 | 6 | 10 | 12 | 12 | 12 | 12 |  | 50 Ohms | TOP=L2:L3=L2/L4:L6=L5/L7:BOTTOM=L7 |
| MEMDQ_12 | OTHERS | BUS | 7 | 5 | 5 | 10 | 5 | 14 | 6 | 10 | 12 | 12 | 12 | 12 |  | 50 Ohms | TOP=L2:L3=L2/L4:L6=L5/L7:BOTTOM=L7 |
| MEMDQ_12 | OTHERS | BUS | 8 | 4.75 | 5 | 10 | 5 | 14 | 6 | 9.5 | 12 | 12 | 12 | 12 |  | 50 Ohms | TOP=L2:L3=L2/L4:L6=L5/L7:BOTTOM=L7 |
| MEMDQ_13 | OTHERS | BUS | 1 | 4.75 | 5 | 10 | 5 | 14 | 6 | 9.5 | 12 | 12 | 12 | 12 |  | 50 Ohms | TOP=L2:L3=L2/L4:L6=L5/L7:BOTTOM=L7 |
| MEMDQ_13 | OTHERS | BUS | 2 | 5 | 5 | 10 | 5 | 14 | 6 | 10 | 12 | 12 | 12 | 12 |  | 50 Ohms | TOP=L2:L3=L2/L4:L6=L5/L7:BOTTOM=L7 |
| MEMDQ_13 | OTHERS | BUS | 3 | 5 | 5 | 10 | 5 | 14 | 6 | 10 | 12 | 12 | 12 | 12 |  | 50 Ohms | TOP=L2:L3=L2/L4:L6=L5/L7:BOTTOM=L7 |
| MEMDQ_13 | OTHERS | BUS | 4 | 5 | 5 | 10 | 5 | 14 | 6 | 10 | 12 | 12 | 12 | 12 |  | 50 Ohms | TOP=L2:L3=L2/L4:L6=L5/L7:BOTTOM=L7 |
| MEMDQ_13 | OTHERS | BUS | 5 | 5 | 5 | 10 | 5 | 14 | 6 | 10 | 12 | 12 | 12 | 12 |  | 50 Ohms | TOP=L2:L3=L2/L4:L6=L5/L7:BOTTOM=L7 |
| MEMDQ_13 | OTHERS | BUS | 6 | 5 | 5 | 10 | 5 | 14 | 6 | 10 | 12 | 12 | 12 | 12 |  | 50 Ohms | TOP=L2:L3=L2/L4:L6=L5/L7:BOTTOM=L7 |
| MEMDQ_13 | OTHERS | BUS | 7 | 5 | 5 | 10 | 5 | 14 | 6 | 10 | 12 | 12 | 12 | 12 |  | 50 Ohms | TOP=L2:L3=L2/L4:L6=L5/L7:BOTTOM=L7 |
| MEMDQ_13 | OTHERS | BUS | 8 | 4.75 | 5 | 10 | 5 | 14 | 6 | 9.5 | 12 | 12 | 12 | 12 |  | 50 Ohms | TOP=L2:L3=L2/L4:L6=L5/L7:BOTTOM=L7 |
| MEMDQ_14 | OTHERS | BUS | 1 | 4.75 | 5 | 10 | 5 | 14 | 6 | 9.5 | 12 | 12 | 12 | 12 |  | 50 Ohms | TOP=L2:L3=L2/L4:L6=L5/L7:BOTTOM=L7 |
| MEMDQ_14 | OTHERS | BUS | 2 | 5 | 5 | 10 | 5 | 14 | 6 | 10 | 12 | 12 | 12 | 12 |  | 50 Ohms | TOP=L2:L3=L2/L4:L6=L5/L7:BOTTOM=L7 |
| MEMDQ_14 | OTHERS | BUS | 3 | 5 | 5 | 10 | 5 | 14 | 6 | 10 | 12 | 12 | 12 | 12 |  | 50 Ohms | TOP=L2:L3=L2/L4:L6=L5/L7:BOTTOM=L7 |
| MEMDQ_14 | OTHERS | BUS | 4 | 5 | 5 | 10 | 5 | 14 | 6 | 10 | 12 | 12 | 12 | 12 |  | 50 Ohms | TOP=L2:L3=L2/L4:L6=L5/L7:BOTTOM=L7 |
| MEMDQ_14 | OTHERS | BUS | 5 | 5 | 5 | 10 | 5 | 14 | 6 | 10 | 12 | 12 | 12 | 12 |  | 50 Ohms | TOP=L2:L3=L2/L4:L6=L5/L7:BOTTOM=L7 |
| MEMDQ_14 | OTHERS | BUS | 6 | 5 | 5 | 10 | 5 | 14 | 6 | 10 | 12 | 12 | 12 | 12 |  | 50 Ohms | TOP=L2:L3=L2/L4:L6=L5/L7:BOTTOM=L7 |
| MEMDQ_14 | OTHERS | BUS | 7 | 5 | 5 | 10 | 5 | 14 | 6 | 10 | 12 | 12 | 12 | 12 |  | 50 Ohms | TOP=L2:L3=L2/L4:L6=L5/L7:BOTTOM=L7 |
| MEMDQ_14 | OTHERS | BUS | 8 | 4.75 | 5 | 10 | 5 | 14 | 6 | 9.5 | 12 | 12 | 12 | 12 |  | 50 Ohms | TOP=L2:L3=L2/L4:L6=L5/L7:BOTTOM=L7 |
| MEMDQ_15 | OTHERS | BUS | 1 | 4.75 | 5 | 10 | 5 | 14 | 6 | 9.5 | 12 | 12 | 12 | 12 |  | 50 Ohms | TOP=L2:L3=L2/L4:L6=L5/L7:BOTTOM=L7 |
| MEMDQ_15 | OTHERS | BUS | 2 | 5 | 5 | 10 | 5 | 14 | 6 | 10 | 12 | 12 | 12 | 12 |  | 50 Ohms | TOP=L2:L3=L2/L4:L6=L5/L7:BOTTOM=L7 |
| MEMDQ_15 | OTHERS | BUS | 3 | 5 | 5 | 10 | 5 | 14 | 6 | 10 | 12 | 12 | 12 | 12 |  | 50 Ohms | TOP=L2:L3=L2/L4:L6=L5/L7:BOTTOM=L7 |
| MEMDQ_15 | OTHERS | BUS | 4 | 5 | 5 | 10 | 5 | 14 | 6 | 10 | 12 | 12 | 12 | 12 |  | 50 Ohms | TOP=L2:L3=L2/L4:L6=L5/L7:BOTTOM=L7 |
| MEMDQ_15 | OTHERS | BUS | 5 | 5 | 5 | 10 | 5 | 14 | 6 | 10 | 12 | 12 | 12 | 12 |  | 50 Ohms | TOP=L2:L3=L2/L4:L6=L5/L7:BOTTOM=L7 |
| MEMDQ_15 | OTHERS | BUS | 6 | 5 | 5 | 10 | 5 | 14 | 6 | 10 | 12 | 12 | 12 | 12 |  | 50 Ohms | TOP=L2:L3=L2/L4:L6=L5/L7:BOTTOM=L7 |
| MEMDQ_15 | OTHERS | BUS | 7 | 5 | 5 | 10 | 5 | 14 | 6 | 10 | 12 | 12 | 12 | 12 |  | 50 Ohms | TOP=L2:L3=L2/L4:L6=L5/L7:BOTTOM=L7 |
| MEMDQ_15 | OTHERS | BUS | 8 | 4.75 | 5 | 10 | 5 | 14 | 6 | 9.5 | 12 | 12 | 12 | 12 |  | 50 Ohms | TOP=L2:L3=L2/L4:L6=L5/L7:BOTTOM=L7 |
| MEMDQ_2 | OTHERS | BUS | 1 | 4.75 | 5 | 10 | 5 | 14 | 6 | 9.5 | 12 | 12 | 12 | 12 |  | 50 Ohms | TOP=L2:L3=L2/L4:L6=L5/L7:BOTTOM=L7 |
| MEMDQ_2 | OTHERS | BUS | 2 | 5 | 5 | 10 | 5 | 14 | 6 | 10 | 12 | 12 | 12 | 12 |  | 50 Ohms | TOP=L2:L3=L2/L4:L6=L5/L7:BOTTOM=L7 |
| MEMDQ_2 | OTHERS | BUS | 3 | 5 | 5 | 10 | 5 | 14 | 6 | 10 | 12 | 12 | 12 | 12 |  | 50 Ohms | TOP=L2:L3=L2/L4:L6=L5/L7:BOTTOM=L7 |
| MEMDQ_2 | OTHERS | BUS | 4 | 5 | 5 | 10 | 5 | 14 | 6 | 10 | 12 | 12 | 12 | 12 |  | 50 Ohms | TOP=L2:L3=L2/L4:L6=L5/L7:BOTTOM=L7 |
| MEMDQ_2 | OTHERS | BUS | 5 | 5 | 5 | 10 | 5 | 14 | 6 | 10 | 12 | 12 | 12 | 12 |  | 50 Ohms | TOP=L2:L3=L2/L4:L6=L5/L7:BOTTOM=L7 |
| MEMDQ_2 | OTHERS | BUS | 6 | 5 | 5 | 10 | 5 | 14 | 6 | 10 | 12 | 12 | 12 | 12 |  | 50 Ohms | TOP=L2:L3=L2/L4:L6=L5/L7:BOTTOM=L7 |
| MEMDQ_2 | OTHERS | BUS | 7 | 5 | 5 | 10 | 5 | 14 | 6 | 10 | 12 | 12 | 12 | 12 |  | 50 Ohms | TOP=L2:L3=L2/L4:L6=L5/L7:BOTTOM=L7 |
| MEMDQ_2 | OTHERS | BUS | 8 | 4.75 | 5 | 10 | 5 | 14 | 6 | 9.5 | 12 | 12 | 12 | 12 |  | 50 Ohms | TOP=L2:L3=L2/L4:L6=L5/L7:BOTTOM=L7 |
| MEMDQ_3 | OTHERS | BUS | 1 | 4.75 | 5 | 10 | 5 | 14 | 6 | 9.5 | 12 | 12 | 12 | 12 |  | 50 Ohms | TOP=L2:L3=L2/L4:L6=L5/L7:BOTTOM=L7 |
| MEMDQ_3 | OTHERS | BUS | 2 | 5 | 5 | 10 | 5 | 14 | 6 | 10 | 12 | 12 | 12 | 12 |  | 50 Ohms | TOP=L2:L3=L2/L4:L6=L5/L7:BOTTOM=L7 |
| MEMDQ_3 | OTHERS | BUS | 3 | 5 | 5 | 10 | 5 | 14 | 6 | 10 | 12 | 12 | 12 | 12 |  | 50 Ohms | TOP=L2:L3=L2/L4:L6=L5/L7:BOTTOM=L7 |
| MEMDQ_3 | OTHERS | BUS | 4 | 5 | 5 | 10 | 5 | 14 | 6 | 10 | 12 | 12 | 12 | 12 |  | 50 Ohms | TOP=L2:L3=L2/L4:L6=L5/L7:BOTTOM=L7 |
| MEMDQ_3 | OTHERS | BUS | 5 | 5 | 5 | 10 | 5 | 14 | 6 | 10 | 12 | 12 | 12 | 12 |  | 50 Ohms | TOP=L2:L3=L2/L4:L6=L5/L7:BOTTOM=L7 |
| MEMDQ_3 | OTHERS | BUS | 6 | 5 | 5 | 10 | 5 | 14 | 6 | 10 | 12 | 12 | 12 | 12 |  | 50 Ohms | TOP=L2:L3=L2/L4:L6=L5/L7:BOTTOM=L7 |
| MEMDQ_3 | OTHERS | BUS | 7 | 5 | 5 | 10 | 5 | 14 | 6 | 10 | 12 | 12 | 12 | 12 |  | 50 Ohms | TOP=L2:L3=L2/L4:L6=L5/L7:BOTTOM=L7 |
| MEMDQ_3 | OTHERS | BUS | 8 | 4.75 | 5 | 10 | 5 | 14 | 6 | 9.5 | 12 | 12 | 12 | 12 |  | 50 Ohms | TOP=L2:L3=L2/L4:L6=L5/L7:BOTTOM=L7 |
| MEMDQ_4 | OTHERS | BUS | 1 | 4.75 | 5 | 10 | 5 | 14 | 6 | 9.5 | 12 | 12 | 12 | 12 |  | 50 Ohms | TOP=L2:L3=L2/L4:L6=L5/L7:BOTTOM=L7 |
| MEMDQ_4 | OTHERS | BUS | 2 | 5 | 5 | 10 | 5 | 14 | 6 | 10 | 12 | 12 | 12 | 12 |  | 50 Ohms | TOP=L2:L3=L2/L4:L6=L5/L7:BOTTOM=L7 |
| MEMDQ_4 | OTHERS | BUS | 3 | 5 | 5 | 10 | 5 | 14 | 6 | 10 | 12 | 12 | 12 | 12 |  | 50 Ohms | TOP=L2:L3=L2/L4:L6=L5/L7:BOTTOM=L7 |
| MEMDQ_4 | OTHERS | BUS | 4 | 5 | 5 | 10 | 5 | 14 | 6 | 10 | 12 | 12 | 12 | 12 |  | 50 Ohms | TOP=L2:L3=L2/L4:L6=L5/L7:BOTTOM=L7 |
| MEMDQ_4 | OTHERS | BUS | 5 | 5 | 5 | 10 | 5 | 14 | 6 | 10 | 12 | 12 | 12 | 12 |  | 50 Ohms | TOP=L2:L3=L2/L4:L6=L5/L7:BOTTOM=L7 |
| MEMDQ_4 | OTHERS | BUS | 6 | 5 | 5 | 10 | 5 | 14 | 6 | 10 | 12 | 12 | 12 | 12 |  | 50 Ohms | TOP=L2:L3=L2/L4:L6=L5/L7:BOTTOM=L7 |
| MEMDQ_4 | OTHERS | BUS | 7 | 5 | 5 | 10 | 5 | 14 | 6 | 10 | 12 | 12 | 12 | 12 |  | 50 Ohms | TOP=L2:L3=L2/L4:L6=L5/L7:BOTTOM=L7 |
| MEMDQ_4 | OTHERS | BUS | 8 | 4.75 | 5 | 10 | 5 | 14 | 6 | 9.5 | 12 | 12 | 12 | 12 |  | 50 Ohms | TOP=L2:L3=L2/L4:L6=L5/L7:BOTTOM=L7 |
| MEMDQ_5 | OTHERS | BUS | 1 | 4.75 | 5 | 10 | 5 | 14 | 6 | 9.5 | 12 | 12 | 12 | 12 |  | 50 Ohms | TOP=L2:L3=L2/L4:L6=L5/L7:BOTTOM=L7 |
| MEMDQ_5 | OTHERS | BUS | 2 | 5 | 5 | 10 | 5 | 14 | 6 | 10 | 12 | 12 | 12 | 12 |  | 50 Ohms | TOP=L2:L3=L2/L4:L6=L5/L7:BOTTOM=L7 |
| MEMDQ_5 | OTHERS | BUS | 3 | 5 | 5 | 10 | 5 | 14 | 6 | 10 | 12 | 12 | 12 | 12 |  | 50 Ohms | TOP=L2:L3=L2/L4:L6=L5/L7:BOTTOM=L7 |
| MEMDQ_5 | OTHERS | BUS | 4 | 5 | 5 | 10 | 5 | 14 | 6 | 10 | 12 | 12 | 12 | 12 |  | 50 Ohms | TOP=L2:L3=L2/L4:L6=L5/L7:BOTTOM=L7 |
| MEMDQ_5 | OTHERS | BUS | 5 | 5 | 5 | 10 | 5 | 14 | 6 | 10 | 12 | 12 | 12 | 12 |  | 50 Ohms | TOP=L2:L3=L2/L4:L6=L5/L7:BOTTOM=L7 |
| MEMDQ_5 | OTHERS | BUS | 6 | 5 | 5 | 10 | 5 | 14 | 6 | 10 | 12 | 12 | 12 | 12 |  | 50 Ohms | TOP=L2:L3=L2/L4:L6=L5/L7:BOTTOM=L7 |
| MEMDQ_5 | OTHERS | BUS | 7 | 5 | 5 | 10 | 5 | 14 | 6 | 10 | 12 | 12 | 12 | 12 |  | 50 Ohms | TOP=L2:L3=L2/L4:L6=L5/L7:BOTTOM=L7 |
| MEMDQ_5 | OTHERS | BUS | 8 | 4.75 | 5 | 10 | 5 | 14 | 6 | 9.5 | 12 | 12 | 12 | 12 |  | 50 Ohms | TOP=L2:L3=L2/L4:L6=L5/L7:BOTTOM=L7 |
| MEMDQ_6 | OTHERS | BUS | 1 | 4.75 | 5 | 10 | 5 | 14 | 6 | 9.5 | 12 | 12 | 12 | 12 |  | 50 Ohms | TOP=L2:L3=L2/L4:L6=L5/L7:BOTTOM=L7 |
| MEMDQ_6 | OTHERS | BUS | 2 | 5 | 5 | 10 | 5 | 14 | 6 | 10 | 12 | 12 | 12 | 12 |  | 50 Ohms | TOP=L2:L3=L2/L4:L6=L5/L7:BOTTOM=L7 |
| MEMDQ_6 | OTHERS | BUS | 3 | 5 | 5 | 10 | 5 | 14 | 6 | 10 | 12 | 12 | 12 | 12 |  | 50 Ohms | TOP=L2:L3=L2/L4:L6=L5/L7:BOTTOM=L7 |
| MEMDQ_6 | OTHERS | BUS | 4 | 5 | 5 | 10 | 5 | 14 | 6 | 10 | 12 | 12 | 12 | 12 |  | 50 Ohms | TOP=L2:L3=L2/L4:L6=L5/L7:BOTTOM=L7 |
| MEMDQ_6 | OTHERS | BUS | 5 | 5 | 5 | 10 | 5 | 14 | 6 | 10 | 12 | 12 | 12 | 12 |  | 50 Ohms | TOP=L2:L3=L2/L4:L6=L5/L7:BOTTOM=L7 |
| MEMDQ_6 | OTHERS | BUS | 6 | 5 | 5 | 10 | 5 | 14 | 6 | 10 | 12 | 12 | 12 | 12 |  | 50 Ohms | TOP=L2:L3=L2/L4:L6=L5/L7:BOTTOM=L7 |
| MEMDQ_6 | OTHERS | BUS | 7 | 5 | 5 | 10 | 5 | 14 | 6 | 10 | 12 | 12 | 12 | 12 |  | 50 Ohms | TOP=L2:L3=L2/L4:L6=L5/L7:BOTTOM=L7 |
| MEMDQ_6 | OTHERS | BUS | 8 | 4.75 | 5 | 10 | 5 | 14 | 6 | 9.5 | 12 | 12 | 12 | 12 |  | 50 Ohms | TOP=L2:L3=L2/L4:L6=L5/L7:BOTTOM=L7 |
| MEMDQ_7 | OTHERS | BUS | 1 | 4.75 | 5 | 10 | 5 | 14 | 6 | 9.5 | 12 | 12 | 12 | 12 |  | 50 Ohms | TOP=L2:L3=L2/L4:L6=L5/L7:BOTTOM=L7 |
| MEMDQ_7 | OTHERS | BUS | 2 | 5 | 5 | 10 | 5 | 14 | 6 | 10 | 12 | 12 | 12 | 12 |  | 50 Ohms | TOP=L2:L3=L2/L4:L6=L5/L7:BOTTOM=L7 |
| MEMDQ_7 | OTHERS | BUS | 3 | 5 | 5 | 10 | 5 | 14 | 6 | 10 | 12 | 12 | 12 | 12 |  | 50 Ohms | TOP=L2:L3=L2/L4:L6=L5/L7:BOTTOM=L7 |
| MEMDQ_7 | OTHERS | BUS | 4 | 5 | 5 | 10 | 5 | 14 | 6 | 10 | 12 | 12 | 12 | 12 |  | 50 Ohms | TOP=L2:L3=L2/L4:L6=L5/L7:BOTTOM=L7 |
| MEMDQ_7 | OTHERS | BUS | 5 | 5 | 5 | 10 | 5 | 14 | 6 | 10 | 12 | 12 | 12 | 12 |  | 50 Ohms | TOP=L2:L3=L2/L4:L6=L5/L7:BOTTOM=L7 |
| MEMDQ_7 | OTHERS | BUS | 6 | 5 | 5 | 10 | 5 | 14 | 6 | 10 | 12 | 12 | 12 | 12 |  | 50 Ohms | TOP=L2:L3=L2/L4:L6=L5/L7:BOTTOM=L7 |
| MEMDQ_7 | OTHERS | BUS | 7 | 5 | 5 | 10 | 5 | 14 | 6 | 10 | 12 | 12 | 12 | 12 |  | 50 Ohms | TOP=L2:L3=L2/L4:L6=L5/L7:BOTTOM=L7 |
| MEMDQ_7 | OTHERS | BUS | 8 | 4.75 | 5 | 10 | 5 | 14 | 6 | 9.5 | 12 | 12 | 12 | 12 |  | 50 Ohms | TOP=L2:L3=L2/L4:L6=L5/L7:BOTTOM=L7 |
| MEMDQ_8 | OTHERS | BUS | 1 | 4.75 | 5 | 10 | 5 | 14 | 6 | 9.5 | 12 | 12 | 12 | 12 |  | 50 Ohms | TOP=L2:L3=L2/L4:L6=L5/L7:BOTTOM=L7 |
| MEMDQ_8 | OTHERS | BUS | 2 | 5 | 5 | 10 | 5 | 14 | 6 | 10 | 12 | 12 | 12 | 12 |  | 50 Ohms | TOP=L2:L3=L2/L4:L6=L5/L7:BOTTOM=L7 |
| MEMDQ_8 | OTHERS | BUS | 3 | 5 | 5 | 10 | 5 | 14 | 6 | 10 | 12 | 12 | 12 | 12 |  | 50 Ohms | TOP=L2:L3=L2/L4:L6=L5/L7:BOTTOM=L7 |
| MEMDQ_8 | OTHERS | BUS | 4 | 5 | 5 | 10 | 5 | 14 | 6 | 10 | 12 | 12 | 12 | 12 |  | 50 Ohms | TOP=L2:L3=L2/L4:L6=L5/L7:BOTTOM=L7 |
| MEMDQ_8 | OTHERS | BUS | 5 | 5 | 5 | 10 | 5 | 14 | 6 | 10 | 12 | 12 | 12 | 12 |  | 50 Ohms | TOP=L2:L3=L2/L4:L6=L5/L7:BOTTOM=L7 |
| MEMDQ_8 | OTHERS | BUS | 6 | 5 | 5 | 10 | 5 | 14 | 6 | 10 | 12 | 12 | 12 | 12 |  | 50 Ohms | TOP=L2:L3=L2/L4:L6=L5/L7:BOTTOM=L7 |
| MEMDQ_8 | OTHERS | BUS | 7 | 5 | 5 | 10 | 5 | 14 | 6 | 10 | 12 | 12 | 12 | 12 |  | 50 Ohms | TOP=L2:L3=L2/L4:L6=L5/L7:BOTTOM=L7 |
| MEMDQ_8 | OTHERS | BUS | 8 | 4.75 | 5 | 10 | 5 | 14 | 6 | 9.5 | 12 | 12 | 12 | 12 |  | 50 Ohms | TOP=L2:L3=L2/L4:L6=L5/L7:BOTTOM=L7 |
| MEMDQ_9 | OTHERS | BUS | 1 | 4.75 | 5 | 10 | 5 | 14 | 6 | 9.5 | 12 | 12 | 12 | 12 |  | 50 Ohms | TOP=L2:L3=L2/L4:L6=L5/L7:BOTTOM=L7 |
| MEMDQ_9 | OTHERS | BUS | 2 | 5 | 5 | 10 | 5 | 14 | 6 | 10 | 12 | 12 | 12 | 12 |  | 50 Ohms | TOP=L2:L3=L2/L4:L6=L5/L7:BOTTOM=L7 |
| MEMDQ_9 | OTHERS | BUS | 3 | 5 | 5 | 10 | 5 | 14 | 6 | 10 | 12 | 12 | 12 | 12 |  | 50 Ohms | TOP=L2:L3=L2/L4:L6=L5/L7:BOTTOM=L7 |
| MEMDQ_9 | OTHERS | BUS | 4 | 5 | 5 | 10 | 5 | 14 | 6 | 10 | 12 | 12 | 12 | 12 |  | 50 Ohms | TOP=L2:L3=L2/L4:L6=L5/L7:BOTTOM=L7 |
| MEMDQ_9 | OTHERS | BUS | 5 | 5 | 5 | 10 | 5 | 14 | 6 | 10 | 12 | 12 | 12 | 12 |  | 50 Ohms | TOP=L2:L3=L2/L4:L6=L5/L7:BOTTOM=L7 |
| MEMDQ_9 | OTHERS | BUS | 6 | 5 | 5 | 10 | 5 | 14 | 6 | 10 | 12 | 12 | 12 | 12 |  | 50 Ohms | TOP=L2:L3=L2/L4:L6=L5/L7:BOTTOM=L7 |
| MEMDQ_9 | OTHERS | BUS | 7 | 5 | 5 | 10 | 5 | 14 | 6 | 10 | 12 | 12 | 12 | 12 |  | 50 Ohms | TOP=L2:L3=L2/L4:L6=L5/L7:BOTTOM=L7 |
| MEMDQ_9 | OTHERS | BUS | 8 | 4.75 | 5 | 10 | 5 | 14 | 6 | 9.5 | 12 | 12 | 12 | 12 |  | 50 Ohms | TOP=L2:L3=L2/L4:L6=L5/L7:BOTTOM=L7 |
| MEMODT | OTHERS | BUS | 1 | 4.75 | 5 | 10 | 5 | 14 | 6 | 9.5 | 12 | 12 | 12 | 12 |  | 50 Ohms | TOP=L2:L3=L2/L4:L6=L5/L7:BOTTOM=L7 |
| MEMODT | OTHERS | BUS | 2 | 5 | 5 | 10 | 5 | 14 | 6 | 10 | 12 | 12 | 12 | 12 |  | 50 Ohms | TOP=L2:L3=L2/L4:L6=L5/L7:BOTTOM=L7 |
| MEMODT | OTHERS | BUS | 3 | 5 | 5 | 10 | 5 | 14 | 6 | 10 | 12 | 12 | 12 | 12 |  | 50 Ohms | TOP=L2:L3=L2/L4:L6=L5/L7:BOTTOM=L7 |
| MEMODT | OTHERS | BUS | 4 | 5 | 5 | 10 | 5 | 14 | 6 | 10 | 12 | 12 | 12 | 12 |  | 50 Ohms | TOP=L2:L3=L2/L4:L6=L5/L7:BOTTOM=L7 |
| MEMODT | OTHERS | BUS | 5 | 5 | 5 | 10 | 5 | 14 | 6 | 10 | 12 | 12 | 12 | 12 |  | 50 Ohms | TOP=L2:L3=L2/L4:L6=L5/L7:BOTTOM=L7 |
| MEMODT | OTHERS | BUS | 6 | 5 | 5 | 10 | 5 | 14 | 6 | 10 | 12 | 12 | 12 | 12 |  | 50 Ohms | TOP=L2:L3=L2/L4:L6=L5/L7:BOTTOM=L7 |
| MEMODT | OTHERS | BUS | 7 | 5 | 5 | 10 | 5 | 14 | 6 | 10 | 12 | 12 | 12 | 12 |  | 50 Ohms | TOP=L2:L3=L2/L4:L6=L5/L7:BOTTOM=L7 |
| MEMODT | OTHERS | BUS | 8 | 4.75 | 5 | 10 | 5 | 14 | 6 | 9.5 | 12 | 12 | 12 | 12 |  | 50 Ohms | TOP=L2:L3=L2/L4:L6=L5/L7:BOTTOM=L7 |
| MEMRASN | OTHERS | BUS | 1 | 4.75 | 5 | 10 | 5 | 14 | 6 | 9.5 | 12 | 12 | 12 | 12 |  | 50 Ohms | TOP=L2:L3=L2/L4:L6=L5/L7:BOTTOM=L7 |
| MEMRASN | OTHERS | BUS | 2 | 5 | 5 | 10 | 5 | 14 | 6 | 10 | 12 | 12 | 12 | 12 |  | 50 Ohms | TOP=L2:L3=L2/L4:L6=L5/L7:BOTTOM=L7 |
| MEMRASN | OTHERS | BUS | 3 | 5 | 5 | 10 | 5 | 14 | 6 | 10 | 12 | 12 | 12 | 12 |  | 50 Ohms | TOP=L2:L3=L2/L4:L6=L5/L7:BOTTOM=L7 |
| MEMRASN | OTHERS | BUS | 4 | 5 | 5 | 10 | 5 | 14 | 6 | 10 | 12 | 12 | 12 | 12 |  | 50 Ohms | TOP=L2:L3=L2/L4:L6=L5/L7:BOTTOM=L7 |
| MEMRASN | OTHERS | BUS | 5 | 5 | 5 | 10 | 5 | 14 | 6 | 10 | 12 | 12 | 12 | 12 |  | 50 Ohms | TOP=L2:L3=L2/L4:L6=L5/L7:BOTTOM=L7 |
| MEMRASN | OTHERS | BUS | 6 | 5 | 5 | 10 | 5 | 14 | 6 | 10 | 12 | 12 | 12 | 12 |  | 50 Ohms | TOP=L2:L3=L2/L4:L6=L5/L7:BOTTOM=L7 |
| MEMRASN | OTHERS | BUS | 7 | 5 | 5 | 10 | 5 | 14 | 6 | 10 | 12 | 12 | 12 | 12 |  | 50 Ohms | TOP=L2:L3=L2/L4:L6=L5/L7:BOTTOM=L7 |
| MEMRASN | OTHERS | BUS | 8 | 4.75 | 5 | 10 | 5 | 14 | 6 | 9.5 | 12 | 12 | 12 | 12 |  | 50 Ohms | TOP=L2:L3=L2/L4:L6=L5/L7:BOTTOM=L7 |
| MEMWEN | OTHERS | BUS | 1 | 4.75 | 5 | 10 | 5 | 14 | 6 | 9.5 | 12 | 12 | 12 | 12 |  | 50 Ohms | TOP=L2:L3=L2/L4:L6=L5/L7:BOTTOM=L7 |
| MEMWEN | OTHERS | BUS | 2 | 5 | 5 | 10 | 5 | 14 | 6 | 10 | 12 | 12 | 12 | 12 |  | 50 Ohms | TOP=L2:L3=L2/L4:L6=L5/L7:BOTTOM=L7 |
| MEMWEN | OTHERS | BUS | 3 | 5 | 5 | 10 | 5 | 14 | 6 | 10 | 12 | 12 | 12 | 12 |  | 50 Ohms | TOP=L2:L3=L2/L4:L6=L5/L7:BOTTOM=L7 |
| MEMWEN | OTHERS | BUS | 4 | 5 | 5 | 10 | 5 | 14 | 6 | 10 | 12 | 12 | 12 | 12 |  | 50 Ohms | TOP=L2:L3=L2/L4:L6=L5/L7:BOTTOM=L7 |
| MEMWEN | OTHERS | BUS | 5 | 5 | 5 | 10 | 5 | 14 | 6 | 10 | 12 | 12 | 12 | 12 |  | 50 Ohms | TOP=L2:L3=L2/L4:L6=L5/L7:BOTTOM=L7 |
| MEMWEN | OTHERS | BUS | 6 | 5 | 5 | 10 | 5 | 14 | 6 | 10 | 12 | 12 | 12 | 12 |  | 50 Ohms | TOP=L2:L3=L2/L4:L6=L5/L7:BOTTOM=L7 |
| MEMWEN | OTHERS | BUS | 7 | 5 | 5 | 10 | 5 | 14 | 6 | 10 | 12 | 12 | 12 | 12 |  | 50 Ohms | TOP=L2:L3=L2/L4:L6=L5/L7:BOTTOM=L7 |
| MEMWEN | OTHERS | BUS | 8 | 4.75 | 5 | 10 | 5 | 14 | 6 | 9.5 | 12 | 12 | 12 | 12 |  | 50 Ohms | TOP=L2:L3=L2/L4:L6=L5/L7:BOTTOM=L7 |
| MINISAS_CN15_A_I2C_INT# | OTHERS | BUS | 1 | 4.75 | 5 | 10 | 5 | 14 | 6 | 9.5 | 12 | 12 | 12 | 12 |  | 50 Ohms | TOP=L2:L3=L2/L4:L6=L5/L7:BOTTOM=L7 |
| MINISAS_CN15_A_I2C_INT# | OTHERS | BUS | 2 | 5 | 5 | 10 | 5 | 14 | 6 | 10 | 12 | 12 | 12 | 12 |  | 50 Ohms | TOP=L2:L3=L2/L4:L6=L5/L7:BOTTOM=L7 |
| MINISAS_CN15_A_I2C_INT# | OTHERS | BUS | 3 | 5 | 5 | 10 | 5 | 14 | 6 | 10 | 12 | 12 | 12 | 12 |  | 50 Ohms | TOP=L2:L3=L2/L4:L6=L5/L7:BOTTOM=L7 |
| MINISAS_CN15_A_I2C_INT# | OTHERS | BUS | 4 | 5 | 5 | 10 | 5 | 14 | 6 | 10 | 12 | 12 | 12 | 12 |  | 50 Ohms | TOP=L2:L3=L2/L4:L6=L5/L7:BOTTOM=L7 |
| MINISAS_CN15_A_I2C_INT# | OTHERS | BUS | 5 | 5 | 5 | 10 | 5 | 14 | 6 | 10 | 12 | 12 | 12 | 12 |  | 50 Ohms | TOP=L2:L3=L2/L4:L6=L5/L7:BOTTOM=L7 |
| MINISAS_CN15_A_I2C_INT# | OTHERS | BUS | 6 | 5 | 5 | 10 | 5 | 14 | 6 | 10 | 12 | 12 | 12 | 12 |  | 50 Ohms | TOP=L2:L3=L2/L4:L6=L5/L7:BOTTOM=L7 |
| MINISAS_CN15_A_I2C_INT# | OTHERS | BUS | 7 | 5 | 5 | 10 | 5 | 14 | 6 | 10 | 12 | 12 | 12 | 12 |  | 50 Ohms | TOP=L2:L3=L2/L4:L6=L5/L7:BOTTOM=L7 |
| MINISAS_CN15_A_I2C_INT# | OTHERS | BUS | 8 | 4.75 | 5 | 10 | 5 | 14 | 6 | 9.5 | 12 | 12 | 12 | 12 |  | 50 Ohms | TOP=L2:L3=L2/L4:L6=L5/L7:BOTTOM=L7 |
| MINISAS_CN15_B_I2C_INT# | OTHERS | BUS | 1 | 4.75 | 5 | 10 | 5 | 14 | 6 | 9.5 | 12 | 12 | 12 | 12 |  | 50 Ohms | TOP=L2:L3=L2/L4:L6=L5/L7:BOTTOM=L7 |
| MINISAS_CN15_B_I2C_INT# | OTHERS | BUS | 2 | 5 | 5 | 10 | 5 | 14 | 6 | 10 | 12 | 12 | 12 | 12 |  | 50 Ohms | TOP=L2:L3=L2/L4:L6=L5/L7:BOTTOM=L7 |
| MINISAS_CN15_B_I2C_INT# | OTHERS | BUS | 3 | 5 | 5 | 10 | 5 | 14 | 6 | 10 | 12 | 12 | 12 | 12 |  | 50 Ohms | TOP=L2:L3=L2/L4:L6=L5/L7:BOTTOM=L7 |
| MINISAS_CN15_B_I2C_INT# | OTHERS | BUS | 4 | 5 | 5 | 10 | 5 | 14 | 6 | 10 | 12 | 12 | 12 | 12 |  | 50 Ohms | TOP=L2:L3=L2/L4:L6=L5/L7:BOTTOM=L7 |
| MINISAS_CN15_B_I2C_INT# | OTHERS | BUS | 5 | 5 | 5 | 10 | 5 | 14 | 6 | 10 | 12 | 12 | 12 | 12 |  | 50 Ohms | TOP=L2:L3=L2/L4:L6=L5/L7:BOTTOM=L7 |
| MINISAS_CN15_B_I2C_INT# | OTHERS | BUS | 6 | 5 | 5 | 10 | 5 | 14 | 6 | 10 | 12 | 12 | 12 | 12 |  | 50 Ohms | TOP=L2:L3=L2/L4:L6=L5/L7:BOTTOM=L7 |
| MINISAS_CN15_B_I2C_INT# | OTHERS | BUS | 7 | 5 | 5 | 10 | 5 | 14 | 6 | 10 | 12 | 12 | 12 | 12 |  | 50 Ohms | TOP=L2:L3=L2/L4:L6=L5/L7:BOTTOM=L7 |
| MINISAS_CN15_B_I2C_INT# | OTHERS | BUS | 8 | 4.75 | 5 | 10 | 5 | 14 | 6 | 9.5 | 12 | 12 | 12 | 12 |  | 50 Ohms | TOP=L2:L3=L2/L4:L6=L5/L7:BOTTOM=L7 |
| MINISAS_CN15_C_I2C_INT# | OTHERS | BUS | 1 | 4.75 | 5 | 10 | 5 | 14 | 6 | 9.5 | 12 | 12 | 12 | 12 |  | 50 Ohms | TOP=L2:L3=L2/L4:L6=L5/L7:BOTTOM=L7 |
| MINISAS_CN15_C_I2C_INT# | OTHERS | BUS | 2 | 5 | 5 | 10 | 5 | 14 | 6 | 10 | 12 | 12 | 12 | 12 |  | 50 Ohms | TOP=L2:L3=L2/L4:L6=L5/L7:BOTTOM=L7 |
| MINISAS_CN15_C_I2C_INT# | OTHERS | BUS | 3 | 5 | 5 | 10 | 5 | 14 | 6 | 10 | 12 | 12 | 12 | 12 |  | 50 Ohms | TOP=L2:L3=L2/L4:L6=L5/L7:BOTTOM=L7 |
| MINISAS_CN15_C_I2C_INT# | OTHERS | BUS | 4 | 5 | 5 | 10 | 5 | 14 | 6 | 10 | 12 | 12 | 12 | 12 |  | 50 Ohms | TOP=L2:L3=L2/L4:L6=L5/L7:BOTTOM=L7 |
| MINISAS_CN15_C_I2C_INT# | OTHERS | BUS | 5 | 5 | 5 | 10 | 5 | 14 | 6 | 10 | 12 | 12 | 12 | 12 |  | 50 Ohms | TOP=L2:L3=L2/L4:L6=L5/L7:BOTTOM=L7 |
| MINISAS_CN15_C_I2C_INT# | OTHERS | BUS | 6 | 5 | 5 | 10 | 5 | 14 | 6 | 10 | 12 | 12 | 12 | 12 |  | 50 Ohms | TOP=L2:L3=L2/L4:L6=L5/L7:BOTTOM=L7 |
| MINISAS_CN15_C_I2C_INT# | OTHERS | BUS | 7 | 5 | 5 | 10 | 5 | 14 | 6 | 10 | 12 | 12 | 12 | 12 |  | 50 Ohms | TOP=L2:L3=L2/L4:L6=L5/L7:BOTTOM=L7 |
| MINISAS_CN15_C_I2C_INT# | OTHERS | BUS | 8 | 4.75 | 5 | 10 | 5 | 14 | 6 | 9.5 | 12 | 12 | 12 | 12 |  | 50 Ohms | TOP=L2:L3=L2/L4:L6=L5/L7:BOTTOM=L7 |
| MINISAS_CN15_D_I2C_INT# | OTHERS | BUS | 1 | 4.75 | 5 | 10 | 5 | 14 | 6 | 9.5 | 12 | 12 | 12 | 12 |  | 50 Ohms | TOP=L2:L3=L2/L4:L6=L5/L7:BOTTOM=L7 |
| MINISAS_CN15_D_I2C_INT# | OTHERS | BUS | 2 | 5 | 5 | 10 | 5 | 14 | 6 | 10 | 12 | 12 | 12 | 12 |  | 50 Ohms | TOP=L2:L3=L2/L4:L6=L5/L7:BOTTOM=L7 |
| MINISAS_CN15_D_I2C_INT# | OTHERS | BUS | 3 | 5 | 5 | 10 | 5 | 14 | 6 | 10 | 12 | 12 | 12 | 12 |  | 50 Ohms | TOP=L2:L3=L2/L4:L6=L5/L7:BOTTOM=L7 |
| MINISAS_CN15_D_I2C_INT# | OTHERS | BUS | 4 | 5 | 5 | 10 | 5 | 14 | 6 | 10 | 12 | 12 | 12 | 12 |  | 50 Ohms | TOP=L2:L3=L2/L4:L6=L5/L7:BOTTOM=L7 |
| MINISAS_CN15_D_I2C_INT# | OTHERS | BUS | 5 | 5 | 5 | 10 | 5 | 14 | 6 | 10 | 12 | 12 | 12 | 12 |  | 50 Ohms | TOP=L2:L3=L2/L4:L6=L5/L7:BOTTOM=L7 |
| MINISAS_CN15_D_I2C_INT# | OTHERS | BUS | 6 | 5 | 5 | 10 | 5 | 14 | 6 | 10 | 12 | 12 | 12 | 12 |  | 50 Ohms | TOP=L2:L3=L2/L4:L6=L5/L7:BOTTOM=L7 |
| MINISAS_CN15_D_I2C_INT# | OTHERS | BUS | 7 | 5 | 5 | 10 | 5 | 14 | 6 | 10 | 12 | 12 | 12 | 12 |  | 50 Ohms | TOP=L2:L3=L2/L4:L6=L5/L7:BOTTOM=L7 |
| MINISAS_CN15_D_I2C_INT# | OTHERS | BUS | 8 | 4.75 | 5 | 10 | 5 | 14 | 6 | 9.5 | 12 | 12 | 12 | 12 |  | 50 Ohms | TOP=L2:L3=L2/L4:L6=L5/L7:BOTTOM=L7 |
| MINISAS_CN16_A_I2C_INT# | OTHERS | BUS | 1 | 4.75 | 5 | 10 | 5 | 14 | 6 | 9.5 | 12 | 12 | 12 | 12 |  | 50 Ohms | TOP=L2:L3=L2/L4:L6=L5/L7:BOTTOM=L7 |
| MINISAS_CN16_A_I2C_INT# | OTHERS | BUS | 2 | 5 | 5 | 10 | 5 | 14 | 6 | 10 | 12 | 12 | 12 | 12 |  | 50 Ohms | TOP=L2:L3=L2/L4:L6=L5/L7:BOTTOM=L7 |
| MINISAS_CN16_A_I2C_INT# | OTHERS | BUS | 3 | 5 | 5 | 10 | 5 | 14 | 6 | 10 | 12 | 12 | 12 | 12 |  | 50 Ohms | TOP=L2:L3=L2/L4:L6=L5/L7:BOTTOM=L7 |
| MINISAS_CN16_A_I2C_INT# | OTHERS | BUS | 4 | 5 | 5 | 10 | 5 | 14 | 6 | 10 | 12 | 12 | 12 | 12 |  | 50 Ohms | TOP=L2:L3=L2/L4:L6=L5/L7:BOTTOM=L7 |
| MINISAS_CN16_A_I2C_INT# | OTHERS | BUS | 5 | 5 | 5 | 10 | 5 | 14 | 6 | 10 | 12 | 12 | 12 | 12 |  | 50 Ohms | TOP=L2:L3=L2/L4:L6=L5/L7:BOTTOM=L7 |
| MINISAS_CN16_A_I2C_INT# | OTHERS | BUS | 6 | 5 | 5 | 10 | 5 | 14 | 6 | 10 | 12 | 12 | 12 | 12 |  | 50 Ohms | TOP=L2:L3=L2/L4:L6=L5/L7:BOTTOM=L7 |
| MINISAS_CN16_A_I2C_INT# | OTHERS | BUS | 7 | 5 | 5 | 10 | 5 | 14 | 6 | 10 | 12 | 12 | 12 | 12 |  | 50 Ohms | TOP=L2:L3=L2/L4:L6=L5/L7:BOTTOM=L7 |
| MINISAS_CN16_A_I2C_INT# | OTHERS | BUS | 8 | 4.75 | 5 | 10 | 5 | 14 | 6 | 9.5 | 12 | 12 | 12 | 12 |  | 50 Ohms | TOP=L2:L3=L2/L4:L6=L5/L7:BOTTOM=L7 |
| MINISAS_CN16_B_I2C_INT# | OTHERS | BUS | 1 | 4.75 | 5 | 10 | 5 | 14 | 6 | 9.5 | 12 | 12 | 12 | 12 |  | 50 Ohms | TOP=L2:L3=L2/L4:L6=L5/L7:BOTTOM=L7 |
| MINISAS_CN16_B_I2C_INT# | OTHERS | BUS | 2 | 5 | 5 | 10 | 5 | 14 | 6 | 10 | 12 | 12 | 12 | 12 |  | 50 Ohms | TOP=L2:L3=L2/L4:L6=L5/L7:BOTTOM=L7 |
| MINISAS_CN16_B_I2C_INT# | OTHERS | BUS | 3 | 5 | 5 | 10 | 5 | 14 | 6 | 10 | 12 | 12 | 12 | 12 |  | 50 Ohms | TOP=L2:L3=L2/L4:L6=L5/L7:BOTTOM=L7 |
| MINISAS_CN16_B_I2C_INT# | OTHERS | BUS | 4 | 5 | 5 | 10 | 5 | 14 | 6 | 10 | 12 | 12 | 12 | 12 |  | 50 Ohms | TOP=L2:L3=L2/L4:L6=L5/L7:BOTTOM=L7 |
| MINISAS_CN16_B_I2C_INT# | OTHERS | BUS | 5 | 5 | 5 | 10 | 5 | 14 | 6 | 10 | 12 | 12 | 12 | 12 |  | 50 Ohms | TOP=L2:L3=L2/L4:L6=L5/L7:BOTTOM=L7 |
| MINISAS_CN16_B_I2C_INT# | OTHERS | BUS | 6 | 5 | 5 | 10 | 5 | 14 | 6 | 10 | 12 | 12 | 12 | 12 |  | 50 Ohms | TOP=L2:L3=L2/L4:L6=L5/L7:BOTTOM=L7 |
| MINISAS_CN16_B_I2C_INT# | OTHERS | BUS | 7 | 5 | 5 | 10 | 5 | 14 | 6 | 10 | 12 | 12 | 12 | 12 |  | 50 Ohms | TOP=L2:L3=L2/L4:L6=L5/L7:BOTTOM=L7 |
| MINISAS_CN16_B_I2C_INT# | OTHERS | BUS | 8 | 4.75 | 5 | 10 | 5 | 14 | 6 | 9.5 | 12 | 12 | 12 | 12 |  | 50 Ohms | TOP=L2:L3=L2/L4:L6=L5/L7:BOTTOM=L7 |
| MINISAS_CN16_C_I2C_INT# | OTHERS | BUS | 1 | 4.75 | 5 | 10 | 5 | 14 | 6 | 9.5 | 12 | 12 | 12 | 12 |  | 50 Ohms | TOP=L2:L3=L2/L4:L6=L5/L7:BOTTOM=L7 |
| MINISAS_CN16_C_I2C_INT# | OTHERS | BUS | 2 | 5 | 5 | 10 | 5 | 14 | 6 | 10 | 12 | 12 | 12 | 12 |  | 50 Ohms | TOP=L2:L3=L2/L4:L6=L5/L7:BOTTOM=L7 |
| MINISAS_CN16_C_I2C_INT# | OTHERS | BUS | 3 | 5 | 5 | 10 | 5 | 14 | 6 | 10 | 12 | 12 | 12 | 12 |  | 50 Ohms | TOP=L2:L3=L2/L4:L6=L5/L7:BOTTOM=L7 |
| MINISAS_CN16_C_I2C_INT# | OTHERS | BUS | 4 | 5 | 5 | 10 | 5 | 14 | 6 | 10 | 12 | 12 | 12 | 12 |  | 50 Ohms | TOP=L2:L3=L2/L4:L6=L5/L7:BOTTOM=L7 |
| MINISAS_CN16_C_I2C_INT# | OTHERS | BUS | 5 | 5 | 5 | 10 | 5 | 14 | 6 | 10 | 12 | 12 | 12 | 12 |  | 50 Ohms | TOP=L2:L3=L2/L4:L6=L5/L7:BOTTOM=L7 |
| MINISAS_CN16_C_I2C_INT# | OTHERS | BUS | 6 | 5 | 5 | 10 | 5 | 14 | 6 | 10 | 12 | 12 | 12 | 12 |  | 50 Ohms | TOP=L2:L3=L2/L4:L6=L5/L7:BOTTOM=L7 |
| MINISAS_CN16_C_I2C_INT# | OTHERS | BUS | 7 | 5 | 5 | 10 | 5 | 14 | 6 | 10 | 12 | 12 | 12 | 12 |  | 50 Ohms | TOP=L2:L3=L2/L4:L6=L5/L7:BOTTOM=L7 |
| MINISAS_CN16_C_I2C_INT# | OTHERS | BUS | 8 | 4.75 | 5 | 10 | 5 | 14 | 6 | 9.5 | 12 | 12 | 12 | 12 |  | 50 Ohms | TOP=L2:L3=L2/L4:L6=L5/L7:BOTTOM=L7 |
| MINISAS_CN16_D_I2C_INT# | OTHERS | BUS | 1 | 4.75 | 5 | 10 | 5 | 14 | 6 | 9.5 | 12 | 12 | 12 | 12 |  | 50 Ohms | TOP=L2:L3=L2/L4:L6=L5/L7:BOTTOM=L7 |
| MINISAS_CN16_D_I2C_INT# | OTHERS | BUS | 2 | 5 | 5 | 10 | 5 | 14 | 6 | 10 | 12 | 12 | 12 | 12 |  | 50 Ohms | TOP=L2:L3=L2/L4:L6=L5/L7:BOTTOM=L7 |
| MINISAS_CN16_D_I2C_INT# | OTHERS | BUS | 3 | 5 | 5 | 10 | 5 | 14 | 6 | 10 | 12 | 12 | 12 | 12 |  | 50 Ohms | TOP=L2:L3=L2/L4:L6=L5/L7:BOTTOM=L7 |
| MINISAS_CN16_D_I2C_INT# | OTHERS | BUS | 4 | 5 | 5 | 10 | 5 | 14 | 6 | 10 | 12 | 12 | 12 | 12 |  | 50 Ohms | TOP=L2:L3=L2/L4:L6=L5/L7:BOTTOM=L7 |
| MINISAS_CN16_D_I2C_INT# | OTHERS | BUS | 5 | 5 | 5 | 10 | 5 | 14 | 6 | 10 | 12 | 12 | 12 | 12 |  | 50 Ohms | TOP=L2:L3=L2/L4:L6=L5/L7:BOTTOM=L7 |
| MINISAS_CN16_D_I2C_INT# | OTHERS | BUS | 6 | 5 | 5 | 10 | 5 | 14 | 6 | 10 | 12 | 12 | 12 | 12 |  | 50 Ohms | TOP=L2:L3=L2/L4:L6=L5/L7:BOTTOM=L7 |
| MINISAS_CN16_D_I2C_INT# | OTHERS | BUS | 7 | 5 | 5 | 10 | 5 | 14 | 6 | 10 | 12 | 12 | 12 | 12 |  | 50 Ohms | TOP=L2:L3=L2/L4:L6=L5/L7:BOTTOM=L7 |
| MINISAS_CN16_D_I2C_INT# | OTHERS | BUS | 8 | 4.75 | 5 | 10 | 5 | 14 | 6 | 9.5 | 12 | 12 | 12 | 12 |  | 50 Ohms | TOP=L2:L3=L2/L4:L6=L5/L7:BOTTOM=L7 |
| NCSI_10G_RCLK | OTHERS | BUS | 1 | 4.75 | 5 | 10 | 5 | 14 | 6 | 9.5 | 12 | 12 | 12 | 12 |  | 50 Ohms | TOP=L2:L3=L2/L4:L6=L5/L7:BOTTOM=L7 |
| NCSI_10G_RCLK | OTHERS | BUS | 2 | 5 | 5 | 10 | 5 | 14 | 6 | 10 | 12 | 12 | 12 | 12 |  | 50 Ohms | TOP=L2:L3=L2/L4:L6=L5/L7:BOTTOM=L7 |
| NCSI_10G_RCLK | OTHERS | BUS | 3 | 5 | 5 | 10 | 5 | 14 | 6 | 10 | 12 | 12 | 12 | 12 |  | 50 Ohms | TOP=L2:L3=L2/L4:L6=L5/L7:BOTTOM=L7 |
| NCSI_10G_RCLK | OTHERS | BUS | 4 | 5 | 5 | 10 | 5 | 14 | 6 | 10 | 12 | 12 | 12 | 12 |  | 50 Ohms | TOP=L2:L3=L2/L4:L6=L5/L7:BOTTOM=L7 |
| NCSI_10G_RCLK | OTHERS | BUS | 5 | 5 | 5 | 10 | 5 | 14 | 6 | 10 | 12 | 12 | 12 | 12 |  | 50 Ohms | TOP=L2:L3=L2/L4:L6=L5/L7:BOTTOM=L7 |
| NCSI_10G_RCLK | OTHERS | BUS | 6 | 5 | 5 | 10 | 5 | 14 | 6 | 10 | 12 | 12 | 12 | 12 |  | 50 Ohms | TOP=L2:L3=L2/L4:L6=L5/L7:BOTTOM=L7 |
| NCSI_10G_RCLK | OTHERS | BUS | 7 | 5 | 5 | 10 | 5 | 14 | 6 | 10 | 12 | 12 | 12 | 12 |  | 50 Ohms | TOP=L2:L3=L2/L4:L6=L5/L7:BOTTOM=L7 |
| NCSI_10G_RCLK | OTHERS | BUS | 8 | 4.75 | 5 | 10 | 5 | 14 | 6 | 9.5 | 12 | 12 | 12 | 12 |  | 50 Ohms | TOP=L2:L3=L2/L4:L6=L5/L7:BOTTOM=L7 |
| NCSI_ARB_IN | OTHERS | BUS | 1 | 4.75 | 5 | 10 | 5 | 14 | 6 | 9.5 | 12 | 12 | 12 | 12 |  | 50 Ohms | TOP=L2:L3=L2/L4:L6=L5/L7:BOTTOM=L7 |
| NCSI_ARB_IN | OTHERS | BUS | 2 | 5 | 5 | 10 | 5 | 14 | 6 | 10 | 12 | 12 | 12 | 12 |  | 50 Ohms | TOP=L2:L3=L2/L4:L6=L5/L7:BOTTOM=L7 |
| NCSI_ARB_IN | OTHERS | BUS | 3 | 5 | 5 | 10 | 5 | 14 | 6 | 10 | 12 | 12 | 12 | 12 |  | 50 Ohms | TOP=L2:L3=L2/L4:L6=L5/L7:BOTTOM=L7 |
| NCSI_ARB_IN | OTHERS | BUS | 4 | 5 | 5 | 10 | 5 | 14 | 6 | 10 | 12 | 12 | 12 | 12 |  | 50 Ohms | TOP=L2:L3=L2/L4:L6=L5/L7:BOTTOM=L7 |
| NCSI_ARB_IN | OTHERS | BUS | 5 | 5 | 5 | 10 | 5 | 14 | 6 | 10 | 12 | 12 | 12 | 12 |  | 50 Ohms | TOP=L2:L3=L2/L4:L6=L5/L7:BOTTOM=L7 |
| NCSI_ARB_IN | OTHERS | BUS | 6 | 5 | 5 | 10 | 5 | 14 | 6 | 10 | 12 | 12 | 12 | 12 |  | 50 Ohms | TOP=L2:L3=L2/L4:L6=L5/L7:BOTTOM=L7 |
| NCSI_ARB_IN | OTHERS | BUS | 7 | 5 | 5 | 10 | 5 | 14 | 6 | 10 | 12 | 12 | 12 | 12 |  | 50 Ohms | TOP=L2:L3=L2/L4:L6=L5/L7:BOTTOM=L7 |
| NCSI_ARB_IN | OTHERS | BUS | 8 | 4.75 | 5 | 10 | 5 | 14 | 6 | 9.5 | 12 | 12 | 12 | 12 |  | 50 Ohms | TOP=L2:L3=L2/L4:L6=L5/L7:BOTTOM=L7 |
| NCSI_ARB_OUT | OTHERS | BUS | 1 | 4.75 | 5 | 10 | 5 | 14 | 6 | 9.5 | 12 | 12 | 12 | 12 |  | 50 Ohms | TOP=L2:L3=L2/L4:L6=L5/L7:BOTTOM=L7 |
| NCSI_ARB_OUT | OTHERS | BUS | 2 | 5 | 5 | 10 | 5 | 14 | 6 | 10 | 12 | 12 | 12 | 12 |  | 50 Ohms | TOP=L2:L3=L2/L4:L6=L5/L7:BOTTOM=L7 |
| NCSI_ARB_OUT | OTHERS | BUS | 3 | 5 | 5 | 10 | 5 | 14 | 6 | 10 | 12 | 12 | 12 | 12 |  | 50 Ohms | TOP=L2:L3=L2/L4:L6=L5/L7:BOTTOM=L7 |
| NCSI_ARB_OUT | OTHERS | BUS | 4 | 5 | 5 | 10 | 5 | 14 | 6 | 10 | 12 | 12 | 12 | 12 |  | 50 Ohms | TOP=L2:L3=L2/L4:L6=L5/L7:BOTTOM=L7 |
| NCSI_ARB_OUT | OTHERS | BUS | 5 | 5 | 5 | 10 | 5 | 14 | 6 | 10 | 12 | 12 | 12 | 12 |  | 50 Ohms | TOP=L2:L3=L2/L4:L6=L5/L7:BOTTOM=L7 |
| NCSI_ARB_OUT | OTHERS | BUS | 6 | 5 | 5 | 10 | 5 | 14 | 6 | 10 | 12 | 12 | 12 | 12 |  | 50 Ohms | TOP=L2:L3=L2/L4:L6=L5/L7:BOTTOM=L7 |
| NCSI_ARB_OUT | OTHERS | BUS | 7 | 5 | 5 | 10 | 5 | 14 | 6 | 10 | 12 | 12 | 12 | 12 |  | 50 Ohms | TOP=L2:L3=L2/L4:L6=L5/L7:BOTTOM=L7 |
| NCSI_ARB_OUT | OTHERS | BUS | 8 | 4.75 | 5 | 10 | 5 | 14 | 6 | 9.5 | 12 | 12 | 12 | 12 |  | 50 Ohms | TOP=L2:L3=L2/L4:L6=L5/L7:BOTTOM=L7 |
| NIC_JTCK | OTHERS | BUS | 1 | 4.75 | 5 | 10 | 5 | 14 | 6 | 9.5 | 12 | 12 | 12 | 12 |  | 50 Ohms | TOP=L2:L3=L2/L4:L6=L5/L7:BOTTOM=L7 |
| NIC_JTCK | OTHERS | BUS | 2 | 5 | 5 | 10 | 5 | 14 | 6 | 10 | 12 | 12 | 12 | 12 |  | 50 Ohms | TOP=L2:L3=L2/L4:L6=L5/L7:BOTTOM=L7 |
| NIC_JTCK | OTHERS | BUS | 3 | 5 | 5 | 10 | 5 | 14 | 6 | 10 | 12 | 12 | 12 | 12 |  | 50 Ohms | TOP=L2:L3=L2/L4:L6=L5/L7:BOTTOM=L7 |
| NIC_JTCK | OTHERS | BUS | 4 | 5 | 5 | 10 | 5 | 14 | 6 | 10 | 12 | 12 | 12 | 12 |  | 50 Ohms | TOP=L2:L3=L2/L4:L6=L5/L7:BOTTOM=L7 |
| NIC_JTCK | OTHERS | BUS | 5 | 5 | 5 | 10 | 5 | 14 | 6 | 10 | 12 | 12 | 12 | 12 |  | 50 Ohms | TOP=L2:L3=L2/L4:L6=L5/L7:BOTTOM=L7 |
| NIC_JTCK | OTHERS | BUS | 6 | 5 | 5 | 10 | 5 | 14 | 6 | 10 | 12 | 12 | 12 | 12 |  | 50 Ohms | TOP=L2:L3=L2/L4:L6=L5/L7:BOTTOM=L7 |
| NIC_JTCK | OTHERS | BUS | 7 | 5 | 5 | 10 | 5 | 14 | 6 | 10 | 12 | 12 | 12 | 12 |  | 50 Ohms | TOP=L2:L3=L2/L4:L6=L5/L7:BOTTOM=L7 |
| NIC_JTCK | OTHERS | BUS | 8 | 4.75 | 5 | 10 | 5 | 14 | 6 | 9.5 | 12 | 12 | 12 | 12 |  | 50 Ohms | TOP=L2:L3=L2/L4:L6=L5/L7:BOTTOM=L7 |
| NIC_JTDI | OTHERS | BUS | 1 | 4.75 | 5 | 10 | 5 | 14 | 6 | 9.5 | 12 | 12 | 12 | 12 |  | 50 Ohms | TOP=L2:L3=L2/L4:L6=L5/L7:BOTTOM=L7 |
| NIC_JTDI | OTHERS | BUS | 2 | 5 | 5 | 10 | 5 | 14 | 6 | 10 | 12 | 12 | 12 | 12 |  | 50 Ohms | TOP=L2:L3=L2/L4:L6=L5/L7:BOTTOM=L7 |
| NIC_JTDI | OTHERS | BUS | 3 | 5 | 5 | 10 | 5 | 14 | 6 | 10 | 12 | 12 | 12 | 12 |  | 50 Ohms | TOP=L2:L3=L2/L4:L6=L5/L7:BOTTOM=L7 |
| NIC_JTDI | OTHERS | BUS | 4 | 5 | 5 | 10 | 5 | 14 | 6 | 10 | 12 | 12 | 12 | 12 |  | 50 Ohms | TOP=L2:L3=L2/L4:L6=L5/L7:BOTTOM=L7 |
| NIC_JTDI | OTHERS | BUS | 5 | 5 | 5 | 10 | 5 | 14 | 6 | 10 | 12 | 12 | 12 | 12 |  | 50 Ohms | TOP=L2:L3=L2/L4:L6=L5/L7:BOTTOM=L7 |
| NIC_JTDI | OTHERS | BUS | 6 | 5 | 5 | 10 | 5 | 14 | 6 | 10 | 12 | 12 | 12 | 12 |  | 50 Ohms | TOP=L2:L3=L2/L4:L6=L5/L7:BOTTOM=L7 |
| NIC_JTDI | OTHERS | BUS | 7 | 5 | 5 | 10 | 5 | 14 | 6 | 10 | 12 | 12 | 12 | 12 |  | 50 Ohms | TOP=L2:L3=L2/L4:L6=L5/L7:BOTTOM=L7 |
| NIC_JTDI | OTHERS | BUS | 8 | 4.75 | 5 | 10 | 5 | 14 | 6 | 9.5 | 12 | 12 | 12 | 12 |  | 50 Ohms | TOP=L2:L3=L2/L4:L6=L5/L7:BOTTOM=L7 |
| NIC_JTDO | OTHERS | BUS | 1 | 4.75 | 5 | 10 | 5 | 14 | 6 | 9.5 | 12 | 12 | 12 | 12 |  | 50 Ohms | TOP=L2:L3=L2/L4:L6=L5/L7:BOTTOM=L7 |
| NIC_JTDO | OTHERS | BUS | 2 | 5 | 5 | 10 | 5 | 14 | 6 | 10 | 12 | 12 | 12 | 12 |  | 50 Ohms | TOP=L2:L3=L2/L4:L6=L5/L7:BOTTOM=L7 |
| NIC_JTDO | OTHERS | BUS | 3 | 5 | 5 | 10 | 5 | 14 | 6 | 10 | 12 | 12 | 12 | 12 |  | 50 Ohms | TOP=L2:L3=L2/L4:L6=L5/L7:BOTTOM=L7 |
| NIC_JTDO | OTHERS | BUS | 4 | 5 | 5 | 10 | 5 | 14 | 6 | 10 | 12 | 12 | 12 | 12 |  | 50 Ohms | TOP=L2:L3=L2/L4:L6=L5/L7:BOTTOM=L7 |
| NIC_JTDO | OTHERS | BUS | 5 | 5 | 5 | 10 | 5 | 14 | 6 | 10 | 12 | 12 | 12 | 12 |  | 50 Ohms | TOP=L2:L3=L2/L4:L6=L5/L7:BOTTOM=L7 |
| NIC_JTDO | OTHERS | BUS | 6 | 5 | 5 | 10 | 5 | 14 | 6 | 10 | 12 | 12 | 12 | 12 |  | 50 Ohms | TOP=L2:L3=L2/L4:L6=L5/L7:BOTTOM=L7 |
| NIC_JTDO | OTHERS | BUS | 7 | 5 | 5 | 10 | 5 | 14 | 6 | 10 | 12 | 12 | 12 | 12 |  | 50 Ohms | TOP=L2:L3=L2/L4:L6=L5/L7:BOTTOM=L7 |
| NIC_JTDO | OTHERS | BUS | 8 | 4.75 | 5 | 10 | 5 | 14 | 6 | 9.5 | 12 | 12 | 12 | 12 |  | 50 Ohms | TOP=L2:L3=L2/L4:L6=L5/L7:BOTTOM=L7 |
| NIC_JTMS | OTHERS | BUS | 1 | 4.75 | 5 | 10 | 5 | 14 | 6 | 9.5 | 12 | 12 | 12 | 12 |  | 50 Ohms | TOP=L2:L3=L2/L4:L6=L5/L7:BOTTOM=L7 |
| NIC_JTMS | OTHERS | BUS | 2 | 5 | 5 | 10 | 5 | 14 | 6 | 10 | 12 | 12 | 12 | 12 |  | 50 Ohms | TOP=L2:L3=L2/L4:L6=L5/L7:BOTTOM=L7 |
| NIC_JTMS | OTHERS | BUS | 3 | 5 | 5 | 10 | 5 | 14 | 6 | 10 | 12 | 12 | 12 | 12 |  | 50 Ohms | TOP=L2:L3=L2/L4:L6=L5/L7:BOTTOM=L7 |
| NIC_JTMS | OTHERS | BUS | 4 | 5 | 5 | 10 | 5 | 14 | 6 | 10 | 12 | 12 | 12 | 12 |  | 50 Ohms | TOP=L2:L3=L2/L4:L6=L5/L7:BOTTOM=L7 |
| NIC_JTMS | OTHERS | BUS | 5 | 5 | 5 | 10 | 5 | 14 | 6 | 10 | 12 | 12 | 12 | 12 |  | 50 Ohms | TOP=L2:L3=L2/L4:L6=L5/L7:BOTTOM=L7 |
| NIC_JTMS | OTHERS | BUS | 6 | 5 | 5 | 10 | 5 | 14 | 6 | 10 | 12 | 12 | 12 | 12 |  | 50 Ohms | TOP=L2:L3=L2/L4:L6=L5/L7:BOTTOM=L7 |
| NIC_JTMS | OTHERS | BUS | 7 | 5 | 5 | 10 | 5 | 14 | 6 | 10 | 12 | 12 | 12 | 12 |  | 50 Ohms | TOP=L2:L3=L2/L4:L6=L5/L7:BOTTOM=L7 |
| NIC_JTMS | OTHERS | BUS | 8 | 4.75 | 5 | 10 | 5 | 14 | 6 | 9.5 | 12 | 12 | 12 | 12 |  | 50 Ohms | TOP=L2:L3=L2/L4:L6=L5/L7:BOTTOM=L7 |
| NIC0_CT_POWER | OTHERS | BUS | 1 | 4.75 | 5 | 10 | 5 | 14 | 6 | 9.5 | 12 | 12 | 12 | 12 |  | 50 Ohms | TOP=L2:L3=L2/L4:L6=L5/L7:BOTTOM=L7 |
| NIC0_CT_POWER | OTHERS | BUS | 2 | 5 | 5 | 10 | 5 | 14 | 6 | 10 | 12 | 12 | 12 | 12 |  | 50 Ohms | TOP=L2:L3=L2/L4:L6=L5/L7:BOTTOM=L7 |
| NIC0_CT_POWER | OTHERS | BUS | 3 | 5 | 5 | 10 | 5 | 14 | 6 | 10 | 12 | 12 | 12 | 12 |  | 50 Ohms | TOP=L2:L3=L2/L4:L6=L5/L7:BOTTOM=L7 |
| NIC0_CT_POWER | OTHERS | BUS | 4 | 5 | 5 | 10 | 5 | 14 | 6 | 10 | 12 | 12 | 12 | 12 |  | 50 Ohms | TOP=L2:L3=L2/L4:L6=L5/L7:BOTTOM=L7 |
| NIC0_CT_POWER | OTHERS | BUS | 5 | 5 | 5 | 10 | 5 | 14 | 6 | 10 | 12 | 12 | 12 | 12 |  | 50 Ohms | TOP=L2:L3=L2/L4:L6=L5/L7:BOTTOM=L7 |
| NIC0_CT_POWER | OTHERS | BUS | 6 | 5 | 5 | 10 | 5 | 14 | 6 | 10 | 12 | 12 | 12 | 12 |  | 50 Ohms | TOP=L2:L3=L2/L4:L6=L5/L7:BOTTOM=L7 |
| NIC0_CT_POWER | OTHERS | BUS | 7 | 5 | 5 | 10 | 5 | 14 | 6 | 10 | 12 | 12 | 12 | 12 |  | 50 Ohms | TOP=L2:L3=L2/L4:L6=L5/L7:BOTTOM=L7 |
| NIC0_CT_POWER | OTHERS | BUS | 8 | 4.75 | 5 | 10 | 5 | 14 | 6 | 9.5 | 12 | 12 | 12 | 12 |  | 50 Ohms | TOP=L2:L3=L2/L4:L6=L5/L7:BOTTOM=L7 |
| P0V9_E_EN | OTHERS | BUS | 1 | 4.75 | 5 | 10 | 5 | 14 | 6 | 9.5 | 12 | 12 | 12 | 12 |  | 50 Ohms | TOP=L2:L3=L2/L4:L6=L5/L7:BOTTOM=L7 |
| P0V9_E_EN | OTHERS | BUS | 2 | 5 | 5 | 10 | 5 | 14 | 6 | 10 | 12 | 12 | 12 | 12 |  | 50 Ohms | TOP=L2:L3=L2/L4:L6=L5/L7:BOTTOM=L7 |
| P0V9_E_EN | OTHERS | BUS | 3 | 5 | 5 | 10 | 5 | 14 | 6 | 10 | 12 | 12 | 12 | 12 |  | 50 Ohms | TOP=L2:L3=L2/L4:L6=L5/L7:BOTTOM=L7 |
| P0V9_E_EN | OTHERS | BUS | 4 | 5 | 5 | 10 | 5 | 14 | 6 | 10 | 12 | 12 | 12 | 12 |  | 50 Ohms | TOP=L2:L3=L2/L4:L6=L5/L7:BOTTOM=L7 |
| P0V9_E_EN | OTHERS | BUS | 5 | 5 | 5 | 10 | 5 | 14 | 6 | 10 | 12 | 12 | 12 | 12 |  | 50 Ohms | TOP=L2:L3=L2/L4:L6=L5/L7:BOTTOM=L7 |
| P0V9_E_EN | OTHERS | BUS | 6 | 5 | 5 | 10 | 5 | 14 | 6 | 10 | 12 | 12 | 12 | 12 |  | 50 Ohms | TOP=L2:L3=L2/L4:L6=L5/L7:BOTTOM=L7 |
| P0V9_E_EN | OTHERS | BUS | 7 | 5 | 5 | 10 | 5 | 14 | 6 | 10 | 12 | 12 | 12 | 12 |  | 50 Ohms | TOP=L2:L3=L2/L4:L6=L5/L7:BOTTOM=L7 |
| P0V9_E_EN | OTHERS | BUS | 8 | 4.75 | 5 | 10 | 5 | 14 | 6 | 9.5 | 12 | 12 | 12 | 12 |  | 50 Ohms | TOP=L2:L3=L2/L4:L6=L5/L7:BOTTOM=L7 |
| P0V9_E_PG | OTHERS | BUS | 1 | 4.75 | 5 | 10 | 5 | 14 | 6 | 9.5 | 12 | 12 | 12 | 12 |  | 50 Ohms | TOP=L2:L3=L2/L4:L6=L5/L7:BOTTOM=L7 |
| P0V9_E_PG | OTHERS | BUS | 2 | 5 | 5 | 10 | 5 | 14 | 6 | 10 | 12 | 12 | 12 | 12 |  | 50 Ohms | TOP=L2:L3=L2/L4:L6=L5/L7:BOTTOM=L7 |
| P0V9_E_PG | OTHERS | BUS | 3 | 5 | 5 | 10 | 5 | 14 | 6 | 10 | 12 | 12 | 12 | 12 |  | 50 Ohms | TOP=L2:L3=L2/L4:L6=L5/L7:BOTTOM=L7 |
| P0V9_E_PG | OTHERS | BUS | 4 | 5 | 5 | 10 | 5 | 14 | 6 | 10 | 12 | 12 | 12 | 12 |  | 50 Ohms | TOP=L2:L3=L2/L4:L6=L5/L7:BOTTOM=L7 |
| P0V9_E_PG | OTHERS | BUS | 5 | 5 | 5 | 10 | 5 | 14 | 6 | 10 | 12 | 12 | 12 | 12 |  | 50 Ohms | TOP=L2:L3=L2/L4:L6=L5/L7:BOTTOM=L7 |
| P0V9_E_PG | OTHERS | BUS | 6 | 5 | 5 | 10 | 5 | 14 | 6 | 10 | 12 | 12 | 12 | 12 |  | 50 Ohms | TOP=L2:L3=L2/L4:L6=L5/L7:BOTTOM=L7 |
| P0V9_E_PG | OTHERS | BUS | 7 | 5 | 5 | 10 | 5 | 14 | 6 | 10 | 12 | 12 | 12 | 12 |  | 50 Ohms | TOP=L2:L3=L2/L4:L6=L5/L7:BOTTOM=L7 |
| P0V9_E_PG | OTHERS | BUS | 8 | 4.75 | 5 | 10 | 5 | 14 | 6 | 9.5 | 12 | 12 | 12 | 12 |  | 50 Ohms | TOP=L2:L3=L2/L4:L6=L5/L7:BOTTOM=L7 |
| P0V9_E_VFB_AVS | OTHERS | BUS | 1 | 4.75 | 5 | 10 | 5 | 14 | 6 | 9.5 | 12 | 12 | 12 | 12 |  | 50 Ohms | TOP=L2:L3=L2/L4:L6=L5/L7:BOTTOM=L7 |
| P0V9_E_VFB_AVS | OTHERS | BUS | 2 | 5 | 5 | 10 | 5 | 14 | 6 | 10 | 12 | 12 | 12 | 12 |  | 50 Ohms | TOP=L2:L3=L2/L4:L6=L5/L7:BOTTOM=L7 |
| P0V9_E_VFB_AVS | OTHERS | BUS | 3 | 5 | 5 | 10 | 5 | 14 | 6 | 10 | 12 | 12 | 12 | 12 |  | 50 Ohms | TOP=L2:L3=L2/L4:L6=L5/L7:BOTTOM=L7 |
| P0V9_E_VFB_AVS | OTHERS | BUS | 4 | 5 | 5 | 10 | 5 | 14 | 6 | 10 | 12 | 12 | 12 | 12 |  | 50 Ohms | TOP=L2:L3=L2/L4:L6=L5/L7:BOTTOM=L7 |
| P0V9_E_VFB_AVS | OTHERS | BUS | 5 | 5 | 5 | 10 | 5 | 14 | 6 | 10 | 12 | 12 | 12 | 12 |  | 50 Ohms | TOP=L2:L3=L2/L4:L6=L5/L7:BOTTOM=L7 |
| P0V9_E_VFB_AVS | OTHERS | BUS | 6 | 5 | 5 | 10 | 5 | 14 | 6 | 10 | 12 | 12 | 12 | 12 |  | 50 Ohms | TOP=L2:L3=L2/L4:L6=L5/L7:BOTTOM=L7 |
| P0V9_E_VFB_AVS | OTHERS | BUS | 7 | 5 | 5 | 10 | 5 | 14 | 6 | 10 | 12 | 12 | 12 | 12 |  | 50 Ohms | TOP=L2:L3=L2/L4:L6=L5/L7:BOTTOM=L7 |
| P0V9_E_VFB_AVS | OTHERS | BUS | 8 | 4.75 | 5 | 10 | 5 | 14 | 6 | 9.5 | 12 | 12 | 12 | 12 |  | 50 Ohms | TOP=L2:L3=L2/L4:L6=L5/L7:BOTTOM=L7 |
| P0V9_EN | OTHERS | BUS | 1 | 4.75 | 5 | 10 | 5 | 14 | 6 | 9.5 | 12 | 12 | 12 | 12 |  | 50 Ohms | TOP=L2:L3=L2/L4:L6=L5/L7:BOTTOM=L7 |
| P0V9_EN | OTHERS | BUS | 2 | 5 | 5 | 10 | 5 | 14 | 6 | 10 | 12 | 12 | 12 | 12 |  | 50 Ohms | TOP=L2:L3=L2/L4:L6=L5/L7:BOTTOM=L7 |
| P0V9_EN | OTHERS | BUS | 3 | 5 | 5 | 10 | 5 | 14 | 6 | 10 | 12 | 12 | 12 | 12 |  | 50 Ohms | TOP=L2:L3=L2/L4:L6=L5/L7:BOTTOM=L7 |
| P0V9_EN | OTHERS | BUS | 4 | 5 | 5 | 10 | 5 | 14 | 6 | 10 | 12 | 12 | 12 | 12 |  | 50 Ohms | TOP=L2:L3=L2/L4:L6=L5/L7:BOTTOM=L7 |
| P0V9_EN | OTHERS | BUS | 5 | 5 | 5 | 10 | 5 | 14 | 6 | 10 | 12 | 12 | 12 | 12 |  | 50 Ohms | TOP=L2:L3=L2/L4:L6=L5/L7:BOTTOM=L7 |
| P0V9_EN | OTHERS | BUS | 6 | 5 | 5 | 10 | 5 | 14 | 6 | 10 | 12 | 12 | 12 | 12 |  | 50 Ohms | TOP=L2:L3=L2/L4:L6=L5/L7:BOTTOM=L7 |
| P0V9_EN | OTHERS | BUS | 7 | 5 | 5 | 10 | 5 | 14 | 6 | 10 | 12 | 12 | 12 | 12 |  | 50 Ohms | TOP=L2:L3=L2/L4:L6=L5/L7:BOTTOM=L7 |
| P0V9_EN | OTHERS | BUS | 8 | 4.75 | 5 | 10 | 5 | 14 | 6 | 9.5 | 12 | 12 | 12 | 12 |  | 50 Ohms | TOP=L2:L3=L2/L4:L6=L5/L7:BOTTOM=L7 |
| P0V9_PG | OTHERS | BUS | 1 | 4.75 | 5 | 10 | 5 | 14 | 6 | 9.5 | 12 | 12 | 12 | 12 |  | 50 Ohms | TOP=L2:L3=L2/L4:L6=L5/L7:BOTTOM=L7 |
| P0V9_PG | OTHERS | BUS | 2 | 5 | 5 | 10 | 5 | 14 | 6 | 10 | 12 | 12 | 12 | 12 |  | 50 Ohms | TOP=L2:L3=L2/L4:L6=L5/L7:BOTTOM=L7 |
| P0V9_PG | OTHERS | BUS | 3 | 5 | 5 | 10 | 5 | 14 | 6 | 10 | 12 | 12 | 12 | 12 |  | 50 Ohms | TOP=L2:L3=L2/L4:L6=L5/L7:BOTTOM=L7 |
| P0V9_PG | OTHERS | BUS | 4 | 5 | 5 | 10 | 5 | 14 | 6 | 10 | 12 | 12 | 12 | 12 |  | 50 Ohms | TOP=L2:L3=L2/L4:L6=L5/L7:BOTTOM=L7 |
| P0V9_PG | OTHERS | BUS | 5 | 5 | 5 | 10 | 5 | 14 | 6 | 10 | 12 | 12 | 12 | 12 |  | 50 Ohms | TOP=L2:L3=L2/L4:L6=L5/L7:BOTTOM=L7 |
| P0V9_PG | OTHERS | BUS | 6 | 5 | 5 | 10 | 5 | 14 | 6 | 10 | 12 | 12 | 12 | 12 |  | 50 Ohms | TOP=L2:L3=L2/L4:L6=L5/L7:BOTTOM=L7 |
| P0V9_PG | OTHERS | BUS | 7 | 5 | 5 | 10 | 5 | 14 | 6 | 10 | 12 | 12 | 12 | 12 |  | 50 Ohms | TOP=L2:L3=L2/L4:L6=L5/L7:BOTTOM=L7 |
| P0V9_PG | OTHERS | BUS | 8 | 4.75 | 5 | 10 | 5 | 14 | 6 | 9.5 | 12 | 12 | 12 | 12 |  | 50 Ohms | TOP=L2:L3=L2/L4:L6=L5/L7:BOTTOM=L7 |
| P0V9_VFB_AVS | OTHERS | BUS | 1 | 4.75 | 5 | 10 | 5 | 14 | 6 | 9.5 | 12 | 12 | 12 | 12 |  | 50 Ohms | TOP=L2:L3=L2/L4:L6=L5/L7:BOTTOM=L7 |
| P0V9_VFB_AVS | OTHERS | BUS | 2 | 5 | 5 | 10 | 5 | 14 | 6 | 10 | 12 | 12 | 12 | 12 |  | 50 Ohms | TOP=L2:L3=L2/L4:L6=L5/L7:BOTTOM=L7 |
| P0V9_VFB_AVS | OTHERS | BUS | 3 | 5 | 5 | 10 | 5 | 14 | 6 | 10 | 12 | 12 | 12 | 12 |  | 50 Ohms | TOP=L2:L3=L2/L4:L6=L5/L7:BOTTOM=L7 |
| P0V9_VFB_AVS | OTHERS | BUS | 4 | 5 | 5 | 10 | 5 | 14 | 6 | 10 | 12 | 12 | 12 | 12 |  | 50 Ohms | TOP=L2:L3=L2/L4:L6=L5/L7:BOTTOM=L7 |
| P0V9_VFB_AVS | OTHERS | BUS | 5 | 5 | 5 | 10 | 5 | 14 | 6 | 10 | 12 | 12 | 12 | 12 |  | 50 Ohms | TOP=L2:L3=L2/L4:L6=L5/L7:BOTTOM=L7 |
| P0V9_VFB_AVS | OTHERS | BUS | 6 | 5 | 5 | 10 | 5 | 14 | 6 | 10 | 12 | 12 | 12 | 12 |  | 50 Ohms | TOP=L2:L3=L2/L4:L6=L5/L7:BOTTOM=L7 |
| P0V9_VFB_AVS | OTHERS | BUS | 7 | 5 | 5 | 10 | 5 | 14 | 6 | 10 | 12 | 12 | 12 | 12 |  | 50 Ohms | TOP=L2:L3=L2/L4:L6=L5/L7:BOTTOM=L7 |
| P0V9_VFB_AVS | OTHERS | BUS | 8 | 4.75 | 5 | 10 | 5 | 14 | 6 | 9.5 | 12 | 12 | 12 | 12 |  | 50 Ohms | TOP=L2:L3=L2/L4:L6=L5/L7:BOTTOM=L7 |
| P3V3_STBY_EN | OTHERS | BUS | 1 | 4.75 | 5 | 10 | 5 | 14 | 6 | 9.5 | 12 | 12 | 12 | 12 |  | 50 Ohms | TOP=L2:L3=L2/L4:L6=L5/L7:BOTTOM=L7 |
| P3V3_STBY_EN | OTHERS | BUS | 2 | 5 | 5 | 10 | 5 | 14 | 6 | 10 | 12 | 12 | 12 | 12 |  | 50 Ohms | TOP=L2:L3=L2/L4:L6=L5/L7:BOTTOM=L7 |
| P3V3_STBY_EN | OTHERS | BUS | 3 | 5 | 5 | 10 | 5 | 14 | 6 | 10 | 12 | 12 | 12 | 12 |  | 50 Ohms | TOP=L2:L3=L2/L4:L6=L5/L7:BOTTOM=L7 |
| P3V3_STBY_EN | OTHERS | BUS | 4 | 5 | 5 | 10 | 5 | 14 | 6 | 10 | 12 | 12 | 12 | 12 |  | 50 Ohms | TOP=L2:L3=L2/L4:L6=L5/L7:BOTTOM=L7 |
| P3V3_STBY_EN | OTHERS | BUS | 5 | 5 | 5 | 10 | 5 | 14 | 6 | 10 | 12 | 12 | 12 | 12 |  | 50 Ohms | TOP=L2:L3=L2/L4:L6=L5/L7:BOTTOM=L7 |
| P3V3_STBY_EN | OTHERS | BUS | 6 | 5 | 5 | 10 | 5 | 14 | 6 | 10 | 12 | 12 | 12 | 12 |  | 50 Ohms | TOP=L2:L3=L2/L4:L6=L5/L7:BOTTOM=L7 |
| P3V3_STBY_EN | OTHERS | BUS | 7 | 5 | 5 | 10 | 5 | 14 | 6 | 10 | 12 | 12 | 12 | 12 |  | 50 Ohms | TOP=L2:L3=L2/L4:L6=L5/L7:BOTTOM=L7 |
| P3V3_STBY_EN | OTHERS | BUS | 8 | 4.75 | 5 | 10 | 5 | 14 | 6 | 9.5 | 12 | 12 | 12 | 12 |  | 50 Ohms | TOP=L2:L3=L2/L4:L6=L5/L7:BOTTOM=L7 |
| P3V3_STBY_PG | OTHERS | BUS | 1 | 4.75 | 5 | 10 | 5 | 14 | 6 | 9.5 | 12 | 12 | 12 | 12 |  | 50 Ohms | TOP=L2:L3=L2/L4:L6=L5/L7:BOTTOM=L7 |
| P3V3_STBY_PG | OTHERS | BUS | 2 | 5 | 5 | 10 | 5 | 14 | 6 | 10 | 12 | 12 | 12 | 12 |  | 50 Ohms | TOP=L2:L3=L2/L4:L6=L5/L7:BOTTOM=L7 |
| P3V3_STBY_PG | OTHERS | BUS | 3 | 5 | 5 | 10 | 5 | 14 | 6 | 10 | 12 | 12 | 12 | 12 |  | 50 Ohms | TOP=L2:L3=L2/L4:L6=L5/L7:BOTTOM=L7 |
| P3V3_STBY_PG | OTHERS | BUS | 4 | 5 | 5 | 10 | 5 | 14 | 6 | 10 | 12 | 12 | 12 | 12 |  | 50 Ohms | TOP=L2:L3=L2/L4:L6=L5/L7:BOTTOM=L7 |
| P3V3_STBY_PG | OTHERS | BUS | 5 | 5 | 5 | 10 | 5 | 14 | 6 | 10 | 12 | 12 | 12 | 12 |  | 50 Ohms | TOP=L2:L3=L2/L4:L6=L5/L7:BOTTOM=L7 |
| P3V3_STBY_PG | OTHERS | BUS | 6 | 5 | 5 | 10 | 5 | 14 | 6 | 10 | 12 | 12 | 12 | 12 |  | 50 Ohms | TOP=L2:L3=L2/L4:L6=L5/L7:BOTTOM=L7 |
| P3V3_STBY_PG | OTHERS | BUS | 7 | 5 | 5 | 10 | 5 | 14 | 6 | 10 | 12 | 12 | 12 | 12 |  | 50 Ohms | TOP=L2:L3=L2/L4:L6=L5/L7:BOTTOM=L7 |
| P3V3_STBY_PG | OTHERS | BUS | 8 | 4.75 | 5 | 10 | 5 | 14 | 6 | 9.5 | 12 | 12 | 12 | 12 |  | 50 Ohms | TOP=L2:L3=L2/L4:L6=L5/L7:BOTTOM=L7 |
| P5V_STBY_EN | OTHERS | BUS | 1 | 4.75 | 5 | 10 | 5 | 14 | 6 | 9.5 | 12 | 12 | 12 | 12 |  | 50 Ohms | TOP=L2:L3=L2/L4:L6=L5/L7:BOTTOM=L7 |
| P5V_STBY_EN | OTHERS | BUS | 2 | 5 | 5 | 10 | 5 | 14 | 6 | 10 | 12 | 12 | 12 | 12 |  | 50 Ohms | TOP=L2:L3=L2/L4:L6=L5/L7:BOTTOM=L7 |
| P5V_STBY_EN | OTHERS | BUS | 3 | 5 | 5 | 10 | 5 | 14 | 6 | 10 | 12 | 12 | 12 | 12 |  | 50 Ohms | TOP=L2:L3=L2/L4:L6=L5/L7:BOTTOM=L7 |
| P5V_STBY_EN | OTHERS | BUS | 4 | 5 | 5 | 10 | 5 | 14 | 6 | 10 | 12 | 12 | 12 | 12 |  | 50 Ohms | TOP=L2:L3=L2/L4:L6=L5/L7:BOTTOM=L7 |
| P5V_STBY_EN | OTHERS | BUS | 5 | 5 | 5 | 10 | 5 | 14 | 6 | 10 | 12 | 12 | 12 | 12 |  | 50 Ohms | TOP=L2:L3=L2/L4:L6=L5/L7:BOTTOM=L7 |
| P5V_STBY_EN | OTHERS | BUS | 6 | 5 | 5 | 10 | 5 | 14 | 6 | 10 | 12 | 12 | 12 | 12 |  | 50 Ohms | TOP=L2:L3=L2/L4:L6=L5/L7:BOTTOM=L7 |
| P5V_STBY_EN | OTHERS | BUS | 7 | 5 | 5 | 10 | 5 | 14 | 6 | 10 | 12 | 12 | 12 | 12 |  | 50 Ohms | TOP=L2:L3=L2/L4:L6=L5/L7:BOTTOM=L7 |
| P5V_STBY_EN | OTHERS | BUS | 8 | 4.75 | 5 | 10 | 5 | 14 | 6 | 9.5 | 12 | 12 | 12 | 12 |  | 50 Ohms | TOP=L2:L3=L2/L4:L6=L5/L7:BOTTOM=L7 |
| PCIE_CLKGEN2_OE0 | OTHERS | BUS | 1 | 4.75 | 5 | 10 | 5 | 14 | 6 | 9.5 | 12 | 12 | 12 | 12 |  | 50 Ohms | TOP=L2:L3=L2/L4:L6=L5/L7:BOTTOM=L7 |
| PCIE_CLKGEN2_OE0 | OTHERS | BUS | 2 | 5 | 5 | 10 | 5 | 14 | 6 | 10 | 12 | 12 | 12 | 12 |  | 50 Ohms | TOP=L2:L3=L2/L4:L6=L5/L7:BOTTOM=L7 |
| PCIE_CLKGEN2_OE0 | OTHERS | BUS | 3 | 5 | 5 | 10 | 5 | 14 | 6 | 10 | 12 | 12 | 12 | 12 |  | 50 Ohms | TOP=L2:L3=L2/L4:L6=L5/L7:BOTTOM=L7 |
| PCIE_CLKGEN2_OE0 | OTHERS | BUS | 4 | 5 | 5 | 10 | 5 | 14 | 6 | 10 | 12 | 12 | 12 | 12 |  | 50 Ohms | TOP=L2:L3=L2/L4:L6=L5/L7:BOTTOM=L7 |
| PCIE_CLKGEN2_OE0 | OTHERS | BUS | 5 | 5 | 5 | 10 | 5 | 14 | 6 | 10 | 12 | 12 | 12 | 12 |  | 50 Ohms | TOP=L2:L3=L2/L4:L6=L5/L7:BOTTOM=L7 |
| PCIE_CLKGEN2_OE0 | OTHERS | BUS | 6 | 5 | 5 | 10 | 5 | 14 | 6 | 10 | 12 | 12 | 12 | 12 |  | 50 Ohms | TOP=L2:L3=L2/L4:L6=L5/L7:BOTTOM=L7 |
| PCIE_CLKGEN2_OE0 | OTHERS | BUS | 7 | 5 | 5 | 10 | 5 | 14 | 6 | 10 | 12 | 12 | 12 | 12 |  | 50 Ohms | TOP=L2:L3=L2/L4:L6=L5/L7:BOTTOM=L7 |
| PCIE_CLKGEN2_OE0 | OTHERS | BUS | 8 | 4.75 | 5 | 10 | 5 | 14 | 6 | 9.5 | 12 | 12 | 12 | 12 |  | 50 Ohms | TOP=L2:L3=L2/L4:L6=L5/L7:BOTTOM=L7 |
| PCIE_CLKGEN2_OE0_R | OTHERS | BUS | 1 | 4.75 | 5 | 10 | 5 | 14 | 6 | 9.5 | 12 | 12 | 12 | 12 |  | 50 Ohms | TOP=L2:L3=L2/L4:L6=L5/L7:BOTTOM=L7 |
| PCIE_CLKGEN2_OE0_R | OTHERS | BUS | 2 | 5 | 5 | 10 | 5 | 14 | 6 | 10 | 12 | 12 | 12 | 12 |  | 50 Ohms | TOP=L2:L3=L2/L4:L6=L5/L7:BOTTOM=L7 |
| PCIE_CLKGEN2_OE0_R | OTHERS | BUS | 3 | 5 | 5 | 10 | 5 | 14 | 6 | 10 | 12 | 12 | 12 | 12 |  | 50 Ohms | TOP=L2:L3=L2/L4:L6=L5/L7:BOTTOM=L7 |
| PCIE_CLKGEN2_OE0_R | OTHERS | BUS | 4 | 5 | 5 | 10 | 5 | 14 | 6 | 10 | 12 | 12 | 12 | 12 |  | 50 Ohms | TOP=L2:L3=L2/L4:L6=L5/L7:BOTTOM=L7 |
| PCIE_CLKGEN2_OE0_R | OTHERS | BUS | 5 | 5 | 5 | 10 | 5 | 14 | 6 | 10 | 12 | 12 | 12 | 12 |  | 50 Ohms | TOP=L2:L3=L2/L4:L6=L5/L7:BOTTOM=L7 |
| PCIE_CLKGEN2_OE0_R | OTHERS | BUS | 6 | 5 | 5 | 10 | 5 | 14 | 6 | 10 | 12 | 12 | 12 | 12 |  | 50 Ohms | TOP=L2:L3=L2/L4:L6=L5/L7:BOTTOM=L7 |
| PCIE_CLKGEN2_OE0_R | OTHERS | BUS | 7 | 5 | 5 | 10 | 5 | 14 | 6 | 10 | 12 | 12 | 12 | 12 |  | 50 Ohms | TOP=L2:L3=L2/L4:L6=L5/L7:BOTTOM=L7 |
| PCIE_CLKGEN2_OE0_R | OTHERS | BUS | 8 | 4.75 | 5 | 10 | 5 | 14 | 6 | 9.5 | 12 | 12 | 12 | 12 |  | 50 Ohms | TOP=L2:L3=L2/L4:L6=L5/L7:BOTTOM=L7 |
| PCIE_DIS | OTHERS | BUS | 1 | 4.75 | 5 | 10 | 5 | 14 | 6 | 9.5 | 12 | 12 | 12 | 12 |  | 50 Ohms | TOP=L2:L3=L2/L4:L6=L5/L7:BOTTOM=L7 |
| PCIE_DIS | OTHERS | BUS | 2 | 5 | 5 | 10 | 5 | 14 | 6 | 10 | 12 | 12 | 12 | 12 |  | 50 Ohms | TOP=L2:L3=L2/L4:L6=L5/L7:BOTTOM=L7 |
| PCIE_DIS | OTHERS | BUS | 3 | 5 | 5 | 10 | 5 | 14 | 6 | 10 | 12 | 12 | 12 | 12 |  | 50 Ohms | TOP=L2:L3=L2/L4:L6=L5/L7:BOTTOM=L7 |
| PCIE_DIS | OTHERS | BUS | 4 | 5 | 5 | 10 | 5 | 14 | 6 | 10 | 12 | 12 | 12 | 12 |  | 50 Ohms | TOP=L2:L3=L2/L4:L6=L5/L7:BOTTOM=L7 |
| PCIE_DIS | OTHERS | BUS | 5 | 5 | 5 | 10 | 5 | 14 | 6 | 10 | 12 | 12 | 12 | 12 |  | 50 Ohms | TOP=L2:L3=L2/L4:L6=L5/L7:BOTTOM=L7 |
| PCIE_DIS | OTHERS | BUS | 6 | 5 | 5 | 10 | 5 | 14 | 6 | 10 | 12 | 12 | 12 | 12 |  | 50 Ohms | TOP=L2:L3=L2/L4:L6=L5/L7:BOTTOM=L7 |
| PCIE_DIS | OTHERS | BUS | 7 | 5 | 5 | 10 | 5 | 14 | 6 | 10 | 12 | 12 | 12 | 12 |  | 50 Ohms | TOP=L2:L3=L2/L4:L6=L5/L7:BOTTOM=L7 |
| PCIE_DIS | OTHERS | BUS | 8 | 4.75 | 5 | 10 | 5 | 14 | 6 | 9.5 | 12 | 12 | 12 | 12 |  | 50 Ohms | TOP=L2:L3=L2/L4:L6=L5/L7:BOTTOM=L7 |
| PCIE_MATED#_A | OTHERS | BUS | 1 | 4.75 | 5 | 10 | 5 | 14 | 6 | 9.5 | 12 | 12 | 12 | 12 |  | 50 Ohms | TOP=L2:L3=L2/L4:L6=L5/L7:BOTTOM=L7 |
| PCIE_MATED#_A | OTHERS | BUS | 2 | 5 | 5 | 10 | 5 | 14 | 6 | 10 | 12 | 12 | 12 | 12 |  | 50 Ohms | TOP=L2:L3=L2/L4:L6=L5/L7:BOTTOM=L7 |
| PCIE_MATED#_A | OTHERS | BUS | 3 | 5 | 5 | 10 | 5 | 14 | 6 | 10 | 12 | 12 | 12 | 12 |  | 50 Ohms | TOP=L2:L3=L2/L4:L6=L5/L7:BOTTOM=L7 |
| PCIE_MATED#_A | OTHERS | BUS | 4 | 5 | 5 | 10 | 5 | 14 | 6 | 10 | 12 | 12 | 12 | 12 |  | 50 Ohms | TOP=L2:L3=L2/L4:L6=L5/L7:BOTTOM=L7 |
| PCIE_MATED#_A | OTHERS | BUS | 5 | 5 | 5 | 10 | 5 | 14 | 6 | 10 | 12 | 12 | 12 | 12 |  | 50 Ohms | TOP=L2:L3=L2/L4:L6=L5/L7:BOTTOM=L7 |
| PCIE_MATED#_A | OTHERS | BUS | 6 | 5 | 5 | 10 | 5 | 14 | 6 | 10 | 12 | 12 | 12 | 12 |  | 50 Ohms | TOP=L2:L3=L2/L4:L6=L5/L7:BOTTOM=L7 |
| PCIE_MATED#_A | OTHERS | BUS | 7 | 5 | 5 | 10 | 5 | 14 | 6 | 10 | 12 | 12 | 12 | 12 |  | 50 Ohms | TOP=L2:L3=L2/L4:L6=L5/L7:BOTTOM=L7 |
| PCIE_MATED#_A | OTHERS | BUS | 8 | 4.75 | 5 | 10 | 5 | 14 | 6 | 9.5 | 12 | 12 | 12 | 12 |  | 50 Ohms | TOP=L2:L3=L2/L4:L6=L5/L7:BOTTOM=L7 |
| PCIE_MATED#_B | OTHERS | BUS | 1 | 4.75 | 5 | 10 | 5 | 14 | 6 | 9.5 | 12 | 12 | 12 | 12 |  | 50 Ohms | TOP=L2:L3=L2/L4:L6=L5/L7:BOTTOM=L7 |
| PCIE_MATED#_B | OTHERS | BUS | 2 | 5 | 5 | 10 | 5 | 14 | 6 | 10 | 12 | 12 | 12 | 12 |  | 50 Ohms | TOP=L2:L3=L2/L4:L6=L5/L7:BOTTOM=L7 |
| PCIE_MATED#_B | OTHERS | BUS | 3 | 5 | 5 | 10 | 5 | 14 | 6 | 10 | 12 | 12 | 12 | 12 |  | 50 Ohms | TOP=L2:L3=L2/L4:L6=L5/L7:BOTTOM=L7 |
| PCIE_MATED#_B | OTHERS | BUS | 4 | 5 | 5 | 10 | 5 | 14 | 6 | 10 | 12 | 12 | 12 | 12 |  | 50 Ohms | TOP=L2:L3=L2/L4:L6=L5/L7:BOTTOM=L7 |
| PCIE_MATED#_B | OTHERS | BUS | 5 | 5 | 5 | 10 | 5 | 14 | 6 | 10 | 12 | 12 | 12 | 12 |  | 50 Ohms | TOP=L2:L3=L2/L4:L6=L5/L7:BOTTOM=L7 |
| PCIE_MATED#_B | OTHERS | BUS | 6 | 5 | 5 | 10 | 5 | 14 | 6 | 10 | 12 | 12 | 12 | 12 |  | 50 Ohms | TOP=L2:L3=L2/L4:L6=L5/L7:BOTTOM=L7 |
| PCIE_MATED#_B | OTHERS | BUS | 7 | 5 | 5 | 10 | 5 | 14 | 6 | 10 | 12 | 12 | 12 | 12 |  | 50 Ohms | TOP=L2:L3=L2/L4:L6=L5/L7:BOTTOM=L7 |
| PCIE_MATED#_B | OTHERS | BUS | 8 | 4.75 | 5 | 10 | 5 | 14 | 6 | 9.5 | 12 | 12 | 12 | 12 |  | 50 Ohms | TOP=L2:L3=L2/L4:L6=L5/L7:BOTTOM=L7 |
| PD_USB2VRES | OTHERS | BUS | 1 | 4.75 | 5 | 10 | 5 | 14 | 6 | 9.5 | 12 | 12 | 12 | 12 |  | 50 Ohms | TOP=L2:L3=L2/L4:L6=L5/L7:BOTTOM=L7 |
| PD_USB2VRES | OTHERS | BUS | 2 | 5 | 5 | 10 | 5 | 14 | 6 | 10 | 12 | 12 | 12 | 12 |  | 50 Ohms | TOP=L2:L3=L2/L4:L6=L5/L7:BOTTOM=L7 |
| PD_USB2VRES | OTHERS | BUS | 3 | 5 | 5 | 10 | 5 | 14 | 6 | 10 | 12 | 12 | 12 | 12 |  | 50 Ohms | TOP=L2:L3=L2/L4:L6=L5/L7:BOTTOM=L7 |
| PD_USB2VRES | OTHERS | BUS | 4 | 5 | 5 | 10 | 5 | 14 | 6 | 10 | 12 | 12 | 12 | 12 |  | 50 Ohms | TOP=L2:L3=L2/L4:L6=L5/L7:BOTTOM=L7 |
| PD_USB2VRES | OTHERS | BUS | 5 | 5 | 5 | 10 | 5 | 14 | 6 | 10 | 12 | 12 | 12 | 12 |  | 50 Ohms | TOP=L2:L3=L2/L4:L6=L5/L7:BOTTOM=L7 |
| PD_USB2VRES | OTHERS | BUS | 6 | 5 | 5 | 10 | 5 | 14 | 6 | 10 | 12 | 12 | 12 | 12 |  | 50 Ohms | TOP=L2:L3=L2/L4:L6=L5/L7:BOTTOM=L7 |
| PD_USB2VRES | OTHERS | BUS | 7 | 5 | 5 | 10 | 5 | 14 | 6 | 10 | 12 | 12 | 12 | 12 |  | 50 Ohms | TOP=L2:L3=L2/L4:L6=L5/L7:BOTTOM=L7 |
| PD_USB2VRES | OTHERS | BUS | 8 | 4.75 | 5 | 10 | 5 | 14 | 6 | 9.5 | 12 | 12 | 12 | 12 |  | 50 Ohms | TOP=L2:L3=L2/L4:L6=L5/L7:BOTTOM=L7 |
| PD_ZQ | OTHERS | BUS | 1 | 4.75 | 5 | 10 | 5 | 14 | 6 | 9.5 | 12 | 12 | 12 | 12 |  | 50 Ohms | TOP=L2:L3=L2/L4:L6=L5/L7:BOTTOM=L7 |
| PD_ZQ | OTHERS | BUS | 2 | 5 | 5 | 10 | 5 | 14 | 6 | 10 | 12 | 12 | 12 | 12 |  | 50 Ohms | TOP=L2:L3=L2/L4:L6=L5/L7:BOTTOM=L7 |
| PD_ZQ | OTHERS | BUS | 3 | 5 | 5 | 10 | 5 | 14 | 6 | 10 | 12 | 12 | 12 | 12 |  | 50 Ohms | TOP=L2:L3=L2/L4:L6=L5/L7:BOTTOM=L7 |
| PD_ZQ | OTHERS | BUS | 4 | 5 | 5 | 10 | 5 | 14 | 6 | 10 | 12 | 12 | 12 | 12 |  | 50 Ohms | TOP=L2:L3=L2/L4:L6=L5/L7:BOTTOM=L7 |
| PD_ZQ | OTHERS | BUS | 5 | 5 | 5 | 10 | 5 | 14 | 6 | 10 | 12 | 12 | 12 | 12 |  | 50 Ohms | TOP=L2:L3=L2/L4:L6=L5/L7:BOTTOM=L7 |
| PD_ZQ | OTHERS | BUS | 6 | 5 | 5 | 10 | 5 | 14 | 6 | 10 | 12 | 12 | 12 | 12 |  | 50 Ohms | TOP=L2:L3=L2/L4:L6=L5/L7:BOTTOM=L7 |
| PD_ZQ | OTHERS | BUS | 7 | 5 | 5 | 10 | 5 | 14 | 6 | 10 | 12 | 12 | 12 | 12 |  | 50 Ohms | TOP=L2:L3=L2/L4:L6=L5/L7:BOTTOM=L7 |
| PD_ZQ | OTHERS | BUS | 8 | 4.75 | 5 | 10 | 5 | 14 | 6 | 9.5 | 12 | 12 | 12 | 12 |  | 50 Ohms | TOP=L2:L3=L2/L4:L6=L5/L7:BOTTOM=L7 |
| PE1_PERST# | OTHERS | BUS | 1 | 4.75 | 5 | 10 | 5 | 14 | 6 | 9.5 | 12 | 12 | 12 | 12 |  | 50 Ohms | TOP=L2:L3=L2/L4:L6=L5/L7:BOTTOM=L7 |
| PE1_PERST# | OTHERS | BUS | 2 | 5 | 5 | 10 | 5 | 14 | 6 | 10 | 12 | 12 | 12 | 12 |  | 50 Ohms | TOP=L2:L3=L2/L4:L6=L5/L7:BOTTOM=L7 |
| PE1_PERST# | OTHERS | BUS | 3 | 5 | 5 | 10 | 5 | 14 | 6 | 10 | 12 | 12 | 12 | 12 |  | 50 Ohms | TOP=L2:L3=L2/L4:L6=L5/L7:BOTTOM=L7 |
| PE1_PERST# | OTHERS | BUS | 4 | 5 | 5 | 10 | 5 | 14 | 6 | 10 | 12 | 12 | 12 | 12 |  | 50 Ohms | TOP=L2:L3=L2/L4:L6=L5/L7:BOTTOM=L7 |
| PE1_PERST# | OTHERS | BUS | 5 | 5 | 5 | 10 | 5 | 14 | 6 | 10 | 12 | 12 | 12 | 12 |  | 50 Ohms | TOP=L2:L3=L2/L4:L6=L5/L7:BOTTOM=L7 |
| PE1_PERST# | OTHERS | BUS | 6 | 5 | 5 | 10 | 5 | 14 | 6 | 10 | 12 | 12 | 12 | 12 |  | 50 Ohms | TOP=L2:L3=L2/L4:L6=L5/L7:BOTTOM=L7 |
| PE1_PERST# | OTHERS | BUS | 7 | 5 | 5 | 10 | 5 | 14 | 6 | 10 | 12 | 12 | 12 | 12 |  | 50 Ohms | TOP=L2:L3=L2/L4:L6=L5/L7:BOTTOM=L7 |
| PE1_PERST# | OTHERS | BUS | 8 | 4.75 | 5 | 10 | 5 | 14 | 6 | 9.5 | 12 | 12 | 12 | 12 |  | 50 Ohms | TOP=L2:L3=L2/L4:L6=L5/L7:BOTTOM=L7 |
| PE1_PERST#_BMC | OTHERS | BUS | 1 | 4.75 | 5 | 10 | 5 | 14 | 6 | 9.5 | 12 | 12 | 12 | 12 |  | 50 Ohms | TOP=L2:L3=L2/L4:L6=L5/L7:BOTTOM=L7 |
| PE1_PERST#_BMC | OTHERS | BUS | 2 | 5 | 5 | 10 | 5 | 14 | 6 | 10 | 12 | 12 | 12 | 12 |  | 50 Ohms | TOP=L2:L3=L2/L4:L6=L5/L7:BOTTOM=L7 |
| PE1_PERST#_BMC | OTHERS | BUS | 3 | 5 | 5 | 10 | 5 | 14 | 6 | 10 | 12 | 12 | 12 | 12 |  | 50 Ohms | TOP=L2:L3=L2/L4:L6=L5/L7:BOTTOM=L7 |
| PE1_PERST#_BMC | OTHERS | BUS | 4 | 5 | 5 | 10 | 5 | 14 | 6 | 10 | 12 | 12 | 12 | 12 |  | 50 Ohms | TOP=L2:L3=L2/L4:L6=L5/L7:BOTTOM=L7 |
| PE1_PERST#_BMC | OTHERS | BUS | 5 | 5 | 5 | 10 | 5 | 14 | 6 | 10 | 12 | 12 | 12 | 12 |  | 50 Ohms | TOP=L2:L3=L2/L4:L6=L5/L7:BOTTOM=L7 |
| PE1_PERST#_BMC | OTHERS | BUS | 6 | 5 | 5 | 10 | 5 | 14 | 6 | 10 | 12 | 12 | 12 | 12 |  | 50 Ohms | TOP=L2:L3=L2/L4:L6=L5/L7:BOTTOM=L7 |
| PE1_PERST#_BMC | OTHERS | BUS | 7 | 5 | 5 | 10 | 5 | 14 | 6 | 10 | 12 | 12 | 12 | 12 |  | 50 Ohms | TOP=L2:L3=L2/L4:L6=L5/L7:BOTTOM=L7 |
| PE1_PERST#_BMC | OTHERS | BUS | 8 | 4.75 | 5 | 10 | 5 | 14 | 6 | 9.5 | 12 | 12 | 12 | 12 |  | 50 Ohms | TOP=L2:L3=L2/L4:L6=L5/L7:BOTTOM=L7 |
| PE1_PERST#_R | OTHERS | BUS | 1 | 4.75 | 5 | 10 | 5 | 14 | 6 | 9.5 | 12 | 12 | 12 | 12 |  | 50 Ohms | TOP=L2:L3=L2/L4:L6=L5/L7:BOTTOM=L7 |
| PE1_PERST#_R | OTHERS | BUS | 2 | 5 | 5 | 10 | 5 | 14 | 6 | 10 | 12 | 12 | 12 | 12 |  | 50 Ohms | TOP=L2:L3=L2/L4:L6=L5/L7:BOTTOM=L7 |
| PE1_PERST#_R | OTHERS | BUS | 3 | 5 | 5 | 10 | 5 | 14 | 6 | 10 | 12 | 12 | 12 | 12 |  | 50 Ohms | TOP=L2:L3=L2/L4:L6=L5/L7:BOTTOM=L7 |
| PE1_PERST#_R | OTHERS | BUS | 4 | 5 | 5 | 10 | 5 | 14 | 6 | 10 | 12 | 12 | 12 | 12 |  | 50 Ohms | TOP=L2:L3=L2/L4:L6=L5/L7:BOTTOM=L7 |
| PE1_PERST#_R | OTHERS | BUS | 5 | 5 | 5 | 10 | 5 | 14 | 6 | 10 | 12 | 12 | 12 | 12 |  | 50 Ohms | TOP=L2:L3=L2/L4:L6=L5/L7:BOTTOM=L7 |
| PE1_PERST#_R | OTHERS | BUS | 6 | 5 | 5 | 10 | 5 | 14 | 6 | 10 | 12 | 12 | 12 | 12 |  | 50 Ohms | TOP=L2:L3=L2/L4:L6=L5/L7:BOTTOM=L7 |
| PE1_PERST#_R | OTHERS | BUS | 7 | 5 | 5 | 10 | 5 | 14 | 6 | 10 | 12 | 12 | 12 | 12 |  | 50 Ohms | TOP=L2:L3=L2/L4:L6=L5/L7:BOTTOM=L7 |
| PE1_PERST#_R | OTHERS | BUS | 8 | 4.75 | 5 | 10 | 5 | 14 | 6 | 9.5 | 12 | 12 | 12 | 12 |  | 50 Ohms | TOP=L2:L3=L2/L4:L6=L5/L7:BOTTOM=L7 |
| PECI0_R | OTHERS | BUS | 1 | 4.75 | 5 | 10 | 5 | 14 | 6 | 9.5 | 12 | 12 | 12 | 12 |  | 50 Ohms | TOP=L2:L3=L2/L4:L6=L5/L7:BOTTOM=L7 |
| PECI0_R | OTHERS | BUS | 2 | 5 | 5 | 10 | 5 | 14 | 6 | 10 | 12 | 12 | 12 | 12 |  | 50 Ohms | TOP=L2:L3=L2/L4:L6=L5/L7:BOTTOM=L7 |
| PECI0_R | OTHERS | BUS | 3 | 5 | 5 | 10 | 5 | 14 | 6 | 10 | 12 | 12 | 12 | 12 |  | 50 Ohms | TOP=L2:L3=L2/L4:L6=L5/L7:BOTTOM=L7 |
| PECI0_R | OTHERS | BUS | 4 | 5 | 5 | 10 | 5 | 14 | 6 | 10 | 12 | 12 | 12 | 12 |  | 50 Ohms | TOP=L2:L3=L2/L4:L6=L5/L7:BOTTOM=L7 |
| PECI0_R | OTHERS | BUS | 5 | 5 | 5 | 10 | 5 | 14 | 6 | 10 | 12 | 12 | 12 | 12 |  | 50 Ohms | TOP=L2:L3=L2/L4:L6=L5/L7:BOTTOM=L7 |
| PECI0_R | OTHERS | BUS | 6 | 5 | 5 | 10 | 5 | 14 | 6 | 10 | 12 | 12 | 12 | 12 |  | 50 Ohms | TOP=L2:L3=L2/L4:L6=L5/L7:BOTTOM=L7 |
| PECI0_R | OTHERS | BUS | 7 | 5 | 5 | 10 | 5 | 14 | 6 | 10 | 12 | 12 | 12 | 12 |  | 50 Ohms | TOP=L2:L3=L2/L4:L6=L5/L7:BOTTOM=L7 |
| PECI0_R | OTHERS | BUS | 8 | 4.75 | 5 | 10 | 5 | 14 | 6 | 9.5 | 12 | 12 | 12 | 12 |  | 50 Ohms | TOP=L2:L3=L2/L4:L6=L5/L7:BOTTOM=L7 |
| PEER_BMC_HB | OTHERS | BUS | 1 | 4.75 | 5 | 10 | 5 | 14 | 6 | 9.5 | 12 | 12 | 12 | 12 |  | 50 Ohms | TOP=L2:L3=L2/L4:L6=L5/L7:BOTTOM=L7 |
| PEER_BMC_HB | OTHERS | BUS | 2 | 5 | 5 | 10 | 5 | 14 | 6 | 10 | 12 | 12 | 12 | 12 |  | 50 Ohms | TOP=L2:L3=L2/L4:L6=L5/L7:BOTTOM=L7 |
| PEER_BMC_HB | OTHERS | BUS | 3 | 5 | 5 | 10 | 5 | 14 | 6 | 10 | 12 | 12 | 12 | 12 |  | 50 Ohms | TOP=L2:L3=L2/L4:L6=L5/L7:BOTTOM=L7 |
| PEER_BMC_HB | OTHERS | BUS | 4 | 5 | 5 | 10 | 5 | 14 | 6 | 10 | 12 | 12 | 12 | 12 |  | 50 Ohms | TOP=L2:L3=L2/L4:L6=L5/L7:BOTTOM=L7 |
| PEER_BMC_HB | OTHERS | BUS | 5 | 5 | 5 | 10 | 5 | 14 | 6 | 10 | 12 | 12 | 12 | 12 |  | 50 Ohms | TOP=L2:L3=L2/L4:L6=L5/L7:BOTTOM=L7 |
| PEER_BMC_HB | OTHERS | BUS | 6 | 5 | 5 | 10 | 5 | 14 | 6 | 10 | 12 | 12 | 12 | 12 |  | 50 Ohms | TOP=L2:L3=L2/L4:L6=L5/L7:BOTTOM=L7 |
| PEER_BMC_HB | OTHERS | BUS | 7 | 5 | 5 | 10 | 5 | 14 | 6 | 10 | 12 | 12 | 12 | 12 |  | 50 Ohms | TOP=L2:L3=L2/L4:L6=L5/L7:BOTTOM=L7 |
| PEER_BMC_HB | OTHERS | BUS | 8 | 4.75 | 5 | 10 | 5 | 14 | 6 | 9.5 | 12 | 12 | 12 | 12 |  | 50 Ohms | TOP=L2:L3=L2/L4:L6=L5/L7:BOTTOM=L7 |
| PEER_TRAY_BMC | OTHERS | BUS | 1 | 4.75 | 5 | 10 | 5 | 14 | 6 | 9.5 | 12 | 12 | 12 | 12 |  | 50 Ohms | TOP=L2:L3=L2/L4:L6=L5/L7:BOTTOM=L7 |
| PEER_TRAY_BMC | OTHERS | BUS | 2 | 5 | 5 | 10 | 5 | 14 | 6 | 10 | 12 | 12 | 12 | 12 |  | 50 Ohms | TOP=L2:L3=L2/L4:L6=L5/L7:BOTTOM=L7 |
| PEER_TRAY_BMC | OTHERS | BUS | 3 | 5 | 5 | 10 | 5 | 14 | 6 | 10 | 12 | 12 | 12 | 12 |  | 50 Ohms | TOP=L2:L3=L2/L4:L6=L5/L7:BOTTOM=L7 |
| PEER_TRAY_BMC | OTHERS | BUS | 4 | 5 | 5 | 10 | 5 | 14 | 6 | 10 | 12 | 12 | 12 | 12 |  | 50 Ohms | TOP=L2:L3=L2/L4:L6=L5/L7:BOTTOM=L7 |
| PEER_TRAY_BMC | OTHERS | BUS | 5 | 5 | 5 | 10 | 5 | 14 | 6 | 10 | 12 | 12 | 12 | 12 |  | 50 Ohms | TOP=L2:L3=L2/L4:L6=L5/L7:BOTTOM=L7 |
| PEER_TRAY_BMC | OTHERS | BUS | 6 | 5 | 5 | 10 | 5 | 14 | 6 | 10 | 12 | 12 | 12 | 12 |  | 50 Ohms | TOP=L2:L3=L2/L4:L6=L5/L7:BOTTOM=L7 |
| PEER_TRAY_BMC | OTHERS | BUS | 7 | 5 | 5 | 10 | 5 | 14 | 6 | 10 | 12 | 12 | 12 | 12 |  | 50 Ohms | TOP=L2:L3=L2/L4:L6=L5/L7:BOTTOM=L7 |
| PEER_TRAY_BMC | OTHERS | BUS | 8 | 4.75 | 5 | 10 | 5 | 14 | 6 | 9.5 | 12 | 12 | 12 | 12 |  | 50 Ohms | TOP=L2:L3=L2/L4:L6=L5/L7:BOTTOM=L7 |
| PEER_TRAY_R | OTHERS | BUS | 1 | 4.75 | 5 | 10 | 5 | 14 | 6 | 9.5 | 12 | 12 | 12 | 12 |  | 50 Ohms | TOP=L2:L3=L2/L4:L6=L5/L7:BOTTOM=L7 |
| PEER_TRAY_R | OTHERS | BUS | 2 | 5 | 5 | 10 | 5 | 14 | 6 | 10 | 12 | 12 | 12 | 12 |  | 50 Ohms | TOP=L2:L3=L2/L4:L6=L5/L7:BOTTOM=L7 |
| PEER_TRAY_R | OTHERS | BUS | 3 | 5 | 5 | 10 | 5 | 14 | 6 | 10 | 12 | 12 | 12 | 12 |  | 50 Ohms | TOP=L2:L3=L2/L4:L6=L5/L7:BOTTOM=L7 |
| PEER_TRAY_R | OTHERS | BUS | 4 | 5 | 5 | 10 | 5 | 14 | 6 | 10 | 12 | 12 | 12 | 12 |  | 50 Ohms | TOP=L2:L3=L2/L4:L6=L5/L7:BOTTOM=L7 |
| PEER_TRAY_R | OTHERS | BUS | 5 | 5 | 5 | 10 | 5 | 14 | 6 | 10 | 12 | 12 | 12 | 12 |  | 50 Ohms | TOP=L2:L3=L2/L4:L6=L5/L7:BOTTOM=L7 |
| PEER_TRAY_R | OTHERS | BUS | 6 | 5 | 5 | 10 | 5 | 14 | 6 | 10 | 12 | 12 | 12 | 12 |  | 50 Ohms | TOP=L2:L3=L2/L4:L6=L5/L7:BOTTOM=L7 |
| PEER_TRAY_R | OTHERS | BUS | 7 | 5 | 5 | 10 | 5 | 14 | 6 | 10 | 12 | 12 | 12 | 12 |  | 50 Ohms | TOP=L2:L3=L2/L4:L6=L5/L7:BOTTOM=L7 |
| PEER_TRAY_R | OTHERS | BUS | 8 | 4.75 | 5 | 10 | 5 | 14 | 6 | 9.5 | 12 | 12 | 12 | 12 |  | 50 Ohms | TOP=L2:L3=L2/L4:L6=L5/L7:BOTTOM=L7 |
| PEWAKE# | OTHERS | BUS | 1 | 4.75 | 5 | 10 | 5 | 14 | 6 | 9.5 | 12 | 12 | 12 | 12 |  | 50 Ohms | TOP=L2:L3=L2/L4:L6=L5/L7:BOTTOM=L7 |
| PEWAKE# | OTHERS | BUS | 2 | 5 | 5 | 10 | 5 | 14 | 6 | 10 | 12 | 12 | 12 | 12 |  | 50 Ohms | TOP=L2:L3=L2/L4:L6=L5/L7:BOTTOM=L7 |
| PEWAKE# | OTHERS | BUS | 3 | 5 | 5 | 10 | 5 | 14 | 6 | 10 | 12 | 12 | 12 | 12 |  | 50 Ohms | TOP=L2:L3=L2/L4:L6=L5/L7:BOTTOM=L7 |
| PEWAKE# | OTHERS | BUS | 4 | 5 | 5 | 10 | 5 | 14 | 6 | 10 | 12 | 12 | 12 | 12 |  | 50 Ohms | TOP=L2:L3=L2/L4:L6=L5/L7:BOTTOM=L7 |
| PEWAKE# | OTHERS | BUS | 5 | 5 | 5 | 10 | 5 | 14 | 6 | 10 | 12 | 12 | 12 | 12 |  | 50 Ohms | TOP=L2:L3=L2/L4:L6=L5/L7:BOTTOM=L7 |
| PEWAKE# | OTHERS | BUS | 6 | 5 | 5 | 10 | 5 | 14 | 6 | 10 | 12 | 12 | 12 | 12 |  | 50 Ohms | TOP=L2:L3=L2/L4:L6=L5/L7:BOTTOM=L7 |
| PEWAKE# | OTHERS | BUS | 7 | 5 | 5 | 10 | 5 | 14 | 6 | 10 | 12 | 12 | 12 | 12 |  | 50 Ohms | TOP=L2:L3=L2/L4:L6=L5/L7:BOTTOM=L7 |
| PEWAKE# | OTHERS | BUS | 8 | 4.75 | 5 | 10 | 5 | 14 | 6 | 9.5 | 12 | 12 | 12 | 12 |  | 50 Ohms | TOP=L2:L3=L2/L4:L6=L5/L7:BOTTOM=L7 |
| PHY_RESET_N | OTHERS | BUS | 1 | 4.75 | 5 | 10 | 5 | 14 | 6 | 9.5 | 12 | 12 | 12 | 12 |  | 50 Ohms | TOP=L2:L3=L2/L4:L6=L5/L7:BOTTOM=L7 |
| PHY_RESET_N | OTHERS | BUS | 2 | 5 | 5 | 10 | 5 | 14 | 6 | 10 | 12 | 12 | 12 | 12 |  | 50 Ohms | TOP=L2:L3=L2/L4:L6=L5/L7:BOTTOM=L7 |
| PHY_RESET_N | OTHERS | BUS | 3 | 5 | 5 | 10 | 5 | 14 | 6 | 10 | 12 | 12 | 12 | 12 |  | 50 Ohms | TOP=L2:L3=L2/L4:L6=L5/L7:BOTTOM=L7 |
| PHY_RESET_N | OTHERS | BUS | 4 | 5 | 5 | 10 | 5 | 14 | 6 | 10 | 12 | 12 | 12 | 12 |  | 50 Ohms | TOP=L2:L3=L2/L4:L6=L5/L7:BOTTOM=L7 |
| PHY_RESET_N | OTHERS | BUS | 5 | 5 | 5 | 10 | 5 | 14 | 6 | 10 | 12 | 12 | 12 | 12 |  | 50 Ohms | TOP=L2:L3=L2/L4:L6=L5/L7:BOTTOM=L7 |
| PHY_RESET_N | OTHERS | BUS | 6 | 5 | 5 | 10 | 5 | 14 | 6 | 10 | 12 | 12 | 12 | 12 |  | 50 Ohms | TOP=L2:L3=L2/L4:L6=L5/L7:BOTTOM=L7 |
| PHY_RESET_N | OTHERS | BUS | 7 | 5 | 5 | 10 | 5 | 14 | 6 | 10 | 12 | 12 | 12 | 12 |  | 50 Ohms | TOP=L2:L3=L2/L4:L6=L5/L7:BOTTOM=L7 |
| PHY_RESET_N | OTHERS | BUS | 8 | 4.75 | 5 | 10 | 5 | 14 | 6 | 9.5 | 12 | 12 | 12 | 12 |  | 50 Ohms | TOP=L2:L3=L2/L4:L6=L5/L7:BOTTOM=L7 |
| PHY_WAKE_N | OTHERS | BUS | 1 | 4.75 | 5 | 10 | 5 | 14 | 6 | 9.5 | 12 | 12 | 12 | 12 |  | 50 Ohms | TOP=L2:L3=L2/L4:L6=L5/L7:BOTTOM=L7 |
| PHY_WAKE_N | OTHERS | BUS | 2 | 5 | 5 | 10 | 5 | 14 | 6 | 10 | 12 | 12 | 12 | 12 |  | 50 Ohms | TOP=L2:L3=L2/L4:L6=L5/L7:BOTTOM=L7 |
| PHY_WAKE_N | OTHERS | BUS | 3 | 5 | 5 | 10 | 5 | 14 | 6 | 10 | 12 | 12 | 12 | 12 |  | 50 Ohms | TOP=L2:L3=L2/L4:L6=L5/L7:BOTTOM=L7 |
| PHY_WAKE_N | OTHERS | BUS | 4 | 5 | 5 | 10 | 5 | 14 | 6 | 10 | 12 | 12 | 12 | 12 |  | 50 Ohms | TOP=L2:L3=L2/L4:L6=L5/L7:BOTTOM=L7 |
| PHY_WAKE_N | OTHERS | BUS | 5 | 5 | 5 | 10 | 5 | 14 | 6 | 10 | 12 | 12 | 12 | 12 |  | 50 Ohms | TOP=L2:L3=L2/L4:L6=L5/L7:BOTTOM=L7 |
| PHY_WAKE_N | OTHERS | BUS | 6 | 5 | 5 | 10 | 5 | 14 | 6 | 10 | 12 | 12 | 12 | 12 |  | 50 Ohms | TOP=L2:L3=L2/L4:L6=L5/L7:BOTTOM=L7 |
| PHY_WAKE_N | OTHERS | BUS | 7 | 5 | 5 | 10 | 5 | 14 | 6 | 10 | 12 | 12 | 12 | 12 |  | 50 Ohms | TOP=L2:L3=L2/L4:L6=L5/L7:BOTTOM=L7 |
| PHY_WAKE_N | OTHERS | BUS | 8 | 4.75 | 5 | 10 | 5 | 14 | 6 | 9.5 | 12 | 12 | 12 | 12 |  | 50 Ohms | TOP=L2:L3=L2/L4:L6=L5/L7:BOTTOM=L7 |
| PM8536_HB | OTHERS | BUS | 1 | 4.75 | 5 | 10 | 5 | 14 | 6 | 9.5 | 12 | 12 | 12 | 12 |  | 50 Ohms | TOP=L2:L3=L2/L4:L6=L5/L7:BOTTOM=L7 |
| PM8536_HB | OTHERS | BUS | 2 | 5 | 5 | 10 | 5 | 14 | 6 | 10 | 12 | 12 | 12 | 12 |  | 50 Ohms | TOP=L2:L3=L2/L4:L6=L5/L7:BOTTOM=L7 |
| PM8536_HB | OTHERS | BUS | 3 | 5 | 5 | 10 | 5 | 14 | 6 | 10 | 12 | 12 | 12 | 12 |  | 50 Ohms | TOP=L2:L3=L2/L4:L6=L5/L7:BOTTOM=L7 |
| PM8536_HB | OTHERS | BUS | 4 | 5 | 5 | 10 | 5 | 14 | 6 | 10 | 12 | 12 | 12 | 12 |  | 50 Ohms | TOP=L2:L3=L2/L4:L6=L5/L7:BOTTOM=L7 |
| PM8536_HB | OTHERS | BUS | 5 | 5 | 5 | 10 | 5 | 14 | 6 | 10 | 12 | 12 | 12 | 12 |  | 50 Ohms | TOP=L2:L3=L2/L4:L6=L5/L7:BOTTOM=L7 |
| PM8536_HB | OTHERS | BUS | 6 | 5 | 5 | 10 | 5 | 14 | 6 | 10 | 12 | 12 | 12 | 12 |  | 50 Ohms | TOP=L2:L3=L2/L4:L6=L5/L7:BOTTOM=L7 |
| PM8536_HB | OTHERS | BUS | 7 | 5 | 5 | 10 | 5 | 14 | 6 | 10 | 12 | 12 | 12 | 12 |  | 50 Ohms | TOP=L2:L3=L2/L4:L6=L5/L7:BOTTOM=L7 |
| PM8536_HB | OTHERS | BUS | 8 | 4.75 | 5 | 10 | 5 | 14 | 6 | 9.5 | 12 | 12 | 12 | 12 |  | 50 Ohms | TOP=L2:L3=L2/L4:L6=L5/L7:BOTTOM=L7 |
| PM8536_PG2_R | OTHERS | BUS | 1 | 4.75 | 5 | 10 | 5 | 14 | 6 | 9.5 | 12 | 12 | 12 | 12 |  | 50 Ohms | TOP=L2:L3=L2/L4:L6=L5/L7:BOTTOM=L7 |
| PM8536_PG2_R | OTHERS | BUS | 2 | 5 | 5 | 10 | 5 | 14 | 6 | 10 | 12 | 12 | 12 | 12 |  | 50 Ohms | TOP=L2:L3=L2/L4:L6=L5/L7:BOTTOM=L7 |
| PM8536_PG2_R | OTHERS | BUS | 3 | 5 | 5 | 10 | 5 | 14 | 6 | 10 | 12 | 12 | 12 | 12 |  | 50 Ohms | TOP=L2:L3=L2/L4:L6=L5/L7:BOTTOM=L7 |
| PM8536_PG2_R | OTHERS | BUS | 4 | 5 | 5 | 10 | 5 | 14 | 6 | 10 | 12 | 12 | 12 | 12 |  | 50 Ohms | TOP=L2:L3=L2/L4:L6=L5/L7:BOTTOM=L7 |
| PM8536_PG2_R | OTHERS | BUS | 5 | 5 | 5 | 10 | 5 | 14 | 6 | 10 | 12 | 12 | 12 | 12 |  | 50 Ohms | TOP=L2:L3=L2/L4:L6=L5/L7:BOTTOM=L7 |
| PM8536_PG2_R | OTHERS | BUS | 6 | 5 | 5 | 10 | 5 | 14 | 6 | 10 | 12 | 12 | 12 | 12 |  | 50 Ohms | TOP=L2:L3=L2/L4:L6=L5/L7:BOTTOM=L7 |
| PM8536_PG2_R | OTHERS | BUS | 7 | 5 | 5 | 10 | 5 | 14 | 6 | 10 | 12 | 12 | 12 | 12 |  | 50 Ohms | TOP=L2:L3=L2/L4:L6=L5/L7:BOTTOM=L7 |
| PM8536_PG2_R | OTHERS | BUS | 8 | 4.75 | 5 | 10 | 5 | 14 | 6 | 9.5 | 12 | 12 | 12 | 12 |  | 50 Ohms | TOP=L2:L3=L2/L4:L6=L5/L7:BOTTOM=L7 |
| PM8536_RST# | OTHERS | BUS | 1 | 4.75 | 5 | 10 | 5 | 14 | 6 | 9.5 | 12 | 12 | 12 | 12 |  | 50 Ohms | TOP=L2:L3=L2/L4:L6=L5/L7:BOTTOM=L7 |
| PM8536_RST# | OTHERS | BUS | 2 | 5 | 5 | 10 | 5 | 14 | 6 | 10 | 12 | 12 | 12 | 12 |  | 50 Ohms | TOP=L2:L3=L2/L4:L6=L5/L7:BOTTOM=L7 |
| PM8536_RST# | OTHERS | BUS | 3 | 5 | 5 | 10 | 5 | 14 | 6 | 10 | 12 | 12 | 12 | 12 |  | 50 Ohms | TOP=L2:L3=L2/L4:L6=L5/L7:BOTTOM=L7 |
| PM8536_RST# | OTHERS | BUS | 4 | 5 | 5 | 10 | 5 | 14 | 6 | 10 | 12 | 12 | 12 | 12 |  | 50 Ohms | TOP=L2:L3=L2/L4:L6=L5/L7:BOTTOM=L7 |
| PM8536_RST# | OTHERS | BUS | 5 | 5 | 5 | 10 | 5 | 14 | 6 | 10 | 12 | 12 | 12 | 12 |  | 50 Ohms | TOP=L2:L3=L2/L4:L6=L5/L7:BOTTOM=L7 |
| PM8536_RST# | OTHERS | BUS | 6 | 5 | 5 | 10 | 5 | 14 | 6 | 10 | 12 | 12 | 12 | 12 |  | 50 Ohms | TOP=L2:L3=L2/L4:L6=L5/L7:BOTTOM=L7 |
| PM8536_RST# | OTHERS | BUS | 7 | 5 | 5 | 10 | 5 | 14 | 6 | 10 | 12 | 12 | 12 | 12 |  | 50 Ohms | TOP=L2:L3=L2/L4:L6=L5/L7:BOTTOM=L7 |
| PM8536_RST# | OTHERS | BUS | 8 | 4.75 | 5 | 10 | 5 | 14 | 6 | 9.5 | 12 | 12 | 12 | 12 |  | 50 Ohms | TOP=L2:L3=L2/L4:L6=L5/L7:BOTTOM=L7 |
| PM8536_RST#_AND | OTHERS | BUS | 1 | 4.75 | 5 | 10 | 5 | 14 | 6 | 9.5 | 12 | 12 | 12 | 12 |  | 50 Ohms | TOP=L2:L3=L2/L4:L6=L5/L7:BOTTOM=L7 |
| PM8536_RST#_AND | OTHERS | BUS | 2 | 5 | 5 | 10 | 5 | 14 | 6 | 10 | 12 | 12 | 12 | 12 |  | 50 Ohms | TOP=L2:L3=L2/L4:L6=L5/L7:BOTTOM=L7 |
| PM8536_RST#_AND | OTHERS | BUS | 3 | 5 | 5 | 10 | 5 | 14 | 6 | 10 | 12 | 12 | 12 | 12 |  | 50 Ohms | TOP=L2:L3=L2/L4:L6=L5/L7:BOTTOM=L7 |
| PM8536_RST#_AND | OTHERS | BUS | 4 | 5 | 5 | 10 | 5 | 14 | 6 | 10 | 12 | 12 | 12 | 12 |  | 50 Ohms | TOP=L2:L3=L2/L4:L6=L5/L7:BOTTOM=L7 |
| PM8536_RST#_AND | OTHERS | BUS | 5 | 5 | 5 | 10 | 5 | 14 | 6 | 10 | 12 | 12 | 12 | 12 |  | 50 Ohms | TOP=L2:L3=L2/L4:L6=L5/L7:BOTTOM=L7 |
| PM8536_RST#_AND | OTHERS | BUS | 6 | 5 | 5 | 10 | 5 | 14 | 6 | 10 | 12 | 12 | 12 | 12 |  | 50 Ohms | TOP=L2:L3=L2/L4:L6=L5/L7:BOTTOM=L7 |
| PM8536_RST#_AND | OTHERS | BUS | 7 | 5 | 5 | 10 | 5 | 14 | 6 | 10 | 12 | 12 | 12 | 12 |  | 50 Ohms | TOP=L2:L3=L2/L4:L6=L5/L7:BOTTOM=L7 |
| PM8536_RST#_AND | OTHERS | BUS | 8 | 4.75 | 5 | 10 | 5 | 14 | 6 | 9.5 | 12 | 12 | 12 | 12 |  | 50 Ohms | TOP=L2:L3=L2/L4:L6=L5/L7:BOTTOM=L7 |
| PM8536_RST#_LS | OTHERS | BUS | 1 | 4.75 | 5 | 10 | 5 | 14 | 6 | 9.5 | 12 | 12 | 12 | 12 |  | 50 Ohms | TOP=L2:L3=L2/L4:L6=L5/L7:BOTTOM=L7 |
| PM8536_RST#_LS | OTHERS | BUS | 2 | 5 | 5 | 10 | 5 | 14 | 6 | 10 | 12 | 12 | 12 | 12 |  | 50 Ohms | TOP=L2:L3=L2/L4:L6=L5/L7:BOTTOM=L7 |
| PM8536_RST#_LS | OTHERS | BUS | 3 | 5 | 5 | 10 | 5 | 14 | 6 | 10 | 12 | 12 | 12 | 12 |  | 50 Ohms | TOP=L2:L3=L2/L4:L6=L5/L7:BOTTOM=L7 |
| PM8536_RST#_LS | OTHERS | BUS | 4 | 5 | 5 | 10 | 5 | 14 | 6 | 10 | 12 | 12 | 12 | 12 |  | 50 Ohms | TOP=L2:L3=L2/L4:L6=L5/L7:BOTTOM=L7 |
| PM8536_RST#_LS | OTHERS | BUS | 5 | 5 | 5 | 10 | 5 | 14 | 6 | 10 | 12 | 12 | 12 | 12 |  | 50 Ohms | TOP=L2:L3=L2/L4:L6=L5/L7:BOTTOM=L7 |
| PM8536_RST#_LS | OTHERS | BUS | 6 | 5 | 5 | 10 | 5 | 14 | 6 | 10 | 12 | 12 | 12 | 12 |  | 50 Ohms | TOP=L2:L3=L2/L4:L6=L5/L7:BOTTOM=L7 |
| PM8536_RST#_LS | OTHERS | BUS | 7 | 5 | 5 | 10 | 5 | 14 | 6 | 10 | 12 | 12 | 12 | 12 |  | 50 Ohms | TOP=L2:L3=L2/L4:L6=L5/L7:BOTTOM=L7 |
| PM8536_RST#_LS | OTHERS | BUS | 8 | 4.75 | 5 | 10 | 5 | 14 | 6 | 9.5 | 12 | 12 | 12 | 12 |  | 50 Ohms | TOP=L2:L3=L2/L4:L6=L5/L7:BOTTOM=L7 |
| PM8536_RST#_LS_R | OTHERS | BUS | 1 | 4.75 | 5 | 10 | 5 | 14 | 6 | 9.5 | 12 | 12 | 12 | 12 |  | 50 Ohms | TOP=L2:L3=L2/L4:L6=L5/L7:BOTTOM=L7 |
| PM8536_RST#_LS_R | OTHERS | BUS | 2 | 5 | 5 | 10 | 5 | 14 | 6 | 10 | 12 | 12 | 12 | 12 |  | 50 Ohms | TOP=L2:L3=L2/L4:L6=L5/L7:BOTTOM=L7 |
| PM8536_RST#_LS_R | OTHERS | BUS | 3 | 5 | 5 | 10 | 5 | 14 | 6 | 10 | 12 | 12 | 12 | 12 |  | 50 Ohms | TOP=L2:L3=L2/L4:L6=L5/L7:BOTTOM=L7 |
| PM8536_RST#_LS_R | OTHERS | BUS | 4 | 5 | 5 | 10 | 5 | 14 | 6 | 10 | 12 | 12 | 12 | 12 |  | 50 Ohms | TOP=L2:L3=L2/L4:L6=L5/L7:BOTTOM=L7 |
| PM8536_RST#_LS_R | OTHERS | BUS | 5 | 5 | 5 | 10 | 5 | 14 | 6 | 10 | 12 | 12 | 12 | 12 |  | 50 Ohms | TOP=L2:L3=L2/L4:L6=L5/L7:BOTTOM=L7 |
| PM8536_RST#_LS_R | OTHERS | BUS | 6 | 5 | 5 | 10 | 5 | 14 | 6 | 10 | 12 | 12 | 12 | 12 |  | 50 Ohms | TOP=L2:L3=L2/L4:L6=L5/L7:BOTTOM=L7 |
| PM8536_RST#_LS_R | OTHERS | BUS | 7 | 5 | 5 | 10 | 5 | 14 | 6 | 10 | 12 | 12 | 12 | 12 |  | 50 Ohms | TOP=L2:L3=L2/L4:L6=L5/L7:BOTTOM=L7 |
| PM8536_RST#_LS_R | OTHERS | BUS | 8 | 4.75 | 5 | 10 | 5 | 14 | 6 | 9.5 | 12 | 12 | 12 | 12 |  | 50 Ohms | TOP=L2:L3=L2/L4:L6=L5/L7:BOTTOM=L7 |
| PMC_PLX_BOARD | OTHERS | BUS | 1 | 4.75 | 5 | 10 | 5 | 14 | 6 | 9.5 | 12 | 12 | 12 | 12 |  | 50 Ohms | TOP=L2:L3=L2/L4:L6=L5/L7:BOTTOM=L7 |
| PMC_PLX_BOARD | OTHERS | BUS | 2 | 5 | 5 | 10 | 5 | 14 | 6 | 10 | 12 | 12 | 12 | 12 |  | 50 Ohms | TOP=L2:L3=L2/L4:L6=L5/L7:BOTTOM=L7 |
| PMC_PLX_BOARD | OTHERS | BUS | 3 | 5 | 5 | 10 | 5 | 14 | 6 | 10 | 12 | 12 | 12 | 12 |  | 50 Ohms | TOP=L2:L3=L2/L4:L6=L5/L7:BOTTOM=L7 |
| PMC_PLX_BOARD | OTHERS | BUS | 4 | 5 | 5 | 10 | 5 | 14 | 6 | 10 | 12 | 12 | 12 | 12 |  | 50 Ohms | TOP=L2:L3=L2/L4:L6=L5/L7:BOTTOM=L7 |
| PMC_PLX_BOARD | OTHERS | BUS | 5 | 5 | 5 | 10 | 5 | 14 | 6 | 10 | 12 | 12 | 12 | 12 |  | 50 Ohms | TOP=L2:L3=L2/L4:L6=L5/L7:BOTTOM=L7 |
| PMC_PLX_BOARD | OTHERS | BUS | 6 | 5 | 5 | 10 | 5 | 14 | 6 | 10 | 12 | 12 | 12 | 12 |  | 50 Ohms | TOP=L2:L3=L2/L4:L6=L5/L7:BOTTOM=L7 |
| PMC_PLX_BOARD | OTHERS | BUS | 7 | 5 | 5 | 10 | 5 | 14 | 6 | 10 | 12 | 12 | 12 | 12 |  | 50 Ohms | TOP=L2:L3=L2/L4:L6=L5/L7:BOTTOM=L7 |
| PMC_PLX_BOARD | OTHERS | BUS | 8 | 4.75 | 5 | 10 | 5 | 14 | 6 | 9.5 | 12 | 12 | 12 | 12 |  | 50 Ohms | TOP=L2:L3=L2/L4:L6=L5/L7:BOTTOM=L7 |
| PMC_R_RXD5 | OTHERS | BUS | 1 | 4.75 | 5 | 10 | 5 | 14 | 6 | 9.5 | 12 | 12 | 12 | 12 |  | 50 Ohms | TOP=L2:L3=L2/L4:L6=L5/L7:BOTTOM=L7 |
| PMC_R_RXD5 | OTHERS | BUS | 2 | 5 | 5 | 10 | 5 | 14 | 6 | 10 | 12 | 12 | 12 | 12 |  | 50 Ohms | TOP=L2:L3=L2/L4:L6=L5/L7:BOTTOM=L7 |
| PMC_R_RXD5 | OTHERS | BUS | 3 | 5 | 5 | 10 | 5 | 14 | 6 | 10 | 12 | 12 | 12 | 12 |  | 50 Ohms | TOP=L2:L3=L2/L4:L6=L5/L7:BOTTOM=L7 |
| PMC_R_RXD5 | OTHERS | BUS | 4 | 5 | 5 | 10 | 5 | 14 | 6 | 10 | 12 | 12 | 12 | 12 |  | 50 Ohms | TOP=L2:L3=L2/L4:L6=L5/L7:BOTTOM=L7 |
| PMC_R_RXD5 | OTHERS | BUS | 5 | 5 | 5 | 10 | 5 | 14 | 6 | 10 | 12 | 12 | 12 | 12 |  | 50 Ohms | TOP=L2:L3=L2/L4:L6=L5/L7:BOTTOM=L7 |
| PMC_R_RXD5 | OTHERS | BUS | 6 | 5 | 5 | 10 | 5 | 14 | 6 | 10 | 12 | 12 | 12 | 12 |  | 50 Ohms | TOP=L2:L3=L2/L4:L6=L5/L7:BOTTOM=L7 |
| PMC_R_RXD5 | OTHERS | BUS | 7 | 5 | 5 | 10 | 5 | 14 | 6 | 10 | 12 | 12 | 12 | 12 |  | 50 Ohms | TOP=L2:L3=L2/L4:L6=L5/L7:BOTTOM=L7 |
| PMC_R_RXD5 | OTHERS | BUS | 8 | 4.75 | 5 | 10 | 5 | 14 | 6 | 9.5 | 12 | 12 | 12 | 12 |  | 50 Ohms | TOP=L2:L3=L2/L4:L6=L5/L7:BOTTOM=L7 |
| PMC_R_TXD5 | OTHERS | BUS | 1 | 4.75 | 5 | 10 | 5 | 14 | 6 | 9.5 | 12 | 12 | 12 | 12 |  | 50 Ohms | TOP=L2:L3=L2/L4:L6=L5/L7:BOTTOM=L7 |
| PMC_R_TXD5 | OTHERS | BUS | 2 | 5 | 5 | 10 | 5 | 14 | 6 | 10 | 12 | 12 | 12 | 12 |  | 50 Ohms | TOP=L2:L3=L2/L4:L6=L5/L7:BOTTOM=L7 |
| PMC_R_TXD5 | OTHERS | BUS | 3 | 5 | 5 | 10 | 5 | 14 | 6 | 10 | 12 | 12 | 12 | 12 |  | 50 Ohms | TOP=L2:L3=L2/L4:L6=L5/L7:BOTTOM=L7 |
| PMC_R_TXD5 | OTHERS | BUS | 4 | 5 | 5 | 10 | 5 | 14 | 6 | 10 | 12 | 12 | 12 | 12 |  | 50 Ohms | TOP=L2:L3=L2/L4:L6=L5/L7:BOTTOM=L7 |
| PMC_R_TXD5 | OTHERS | BUS | 5 | 5 | 5 | 10 | 5 | 14 | 6 | 10 | 12 | 12 | 12 | 12 |  | 50 Ohms | TOP=L2:L3=L2/L4:L6=L5/L7:BOTTOM=L7 |
| PMC_R_TXD5 | OTHERS | BUS | 6 | 5 | 5 | 10 | 5 | 14 | 6 | 10 | 12 | 12 | 12 | 12 |  | 50 Ohms | TOP=L2:L3=L2/L4:L6=L5/L7:BOTTOM=L7 |
| PMC_R_TXD5 | OTHERS | BUS | 7 | 5 | 5 | 10 | 5 | 14 | 6 | 10 | 12 | 12 | 12 | 12 |  | 50 Ohms | TOP=L2:L3=L2/L4:L6=L5/L7:BOTTOM=L7 |
| PMC_R_TXD5 | OTHERS | BUS | 8 | 4.75 | 5 | 10 | 5 | 14 | 6 | 9.5 | 12 | 12 | 12 | 12 |  | 50 Ohms | TOP=L2:L3=L2/L4:L6=L5/L7:BOTTOM=L7 |
| PQ21_G | OTHERS | BUS | 1 | 4.75 | 5 | 10 | 5 | 14 | 6 | 9.5 | 12 | 12 | 12 | 12 |  | 50 Ohms | TOP=L2:L3=L2/L4:L6=L5/L7:BOTTOM=L7 |
| PQ21_G | OTHERS | BUS | 2 | 5 | 5 | 10 | 5 | 14 | 6 | 10 | 12 | 12 | 12 | 12 |  | 50 Ohms | TOP=L2:L3=L2/L4:L6=L5/L7:BOTTOM=L7 |
| PQ21_G | OTHERS | BUS | 3 | 5 | 5 | 10 | 5 | 14 | 6 | 10 | 12 | 12 | 12 | 12 |  | 50 Ohms | TOP=L2:L3=L2/L4:L6=L5/L7:BOTTOM=L7 |
| PQ21_G | OTHERS | BUS | 4 | 5 | 5 | 10 | 5 | 14 | 6 | 10 | 12 | 12 | 12 | 12 |  | 50 Ohms | TOP=L2:L3=L2/L4:L6=L5/L7:BOTTOM=L7 |
| PQ21_G | OTHERS | BUS | 5 | 5 | 5 | 10 | 5 | 14 | 6 | 10 | 12 | 12 | 12 | 12 |  | 50 Ohms | TOP=L2:L3=L2/L4:L6=L5/L7:BOTTOM=L7 |
| PQ21_G | OTHERS | BUS | 6 | 5 | 5 | 10 | 5 | 14 | 6 | 10 | 12 | 12 | 12 | 12 |  | 50 Ohms | TOP=L2:L3=L2/L4:L6=L5/L7:BOTTOM=L7 |
| PQ21_G | OTHERS | BUS | 7 | 5 | 5 | 10 | 5 | 14 | 6 | 10 | 12 | 12 | 12 | 12 |  | 50 Ohms | TOP=L2:L3=L2/L4:L6=L5/L7:BOTTOM=L7 |
| PQ21_G | OTHERS | BUS | 8 | 4.75 | 5 | 10 | 5 | 14 | 6 | 9.5 | 12 | 12 | 12 | 12 |  | 50 Ohms | TOP=L2:L3=L2/L4:L6=L5/L7:BOTTOM=L7 |
| PQ22_G | OTHERS | BUS | 1 | 4.75 | 5 | 10 | 5 | 14 | 6 | 9.5 | 12 | 12 | 12 | 12 |  | 50 Ohms | TOP=L2:L3=L2/L4:L6=L5/L7:BOTTOM=L7 |
| PQ22_G | OTHERS | BUS | 2 | 5 | 5 | 10 | 5 | 14 | 6 | 10 | 12 | 12 | 12 | 12 |  | 50 Ohms | TOP=L2:L3=L2/L4:L6=L5/L7:BOTTOM=L7 |
| PQ22_G | OTHERS | BUS | 3 | 5 | 5 | 10 | 5 | 14 | 6 | 10 | 12 | 12 | 12 | 12 |  | 50 Ohms | TOP=L2:L3=L2/L4:L6=L5/L7:BOTTOM=L7 |
| PQ22_G | OTHERS | BUS | 4 | 5 | 5 | 10 | 5 | 14 | 6 | 10 | 12 | 12 | 12 | 12 |  | 50 Ohms | TOP=L2:L3=L2/L4:L6=L5/L7:BOTTOM=L7 |
| PQ22_G | OTHERS | BUS | 5 | 5 | 5 | 10 | 5 | 14 | 6 | 10 | 12 | 12 | 12 | 12 |  | 50 Ohms | TOP=L2:L3=L2/L4:L6=L5/L7:BOTTOM=L7 |
| PQ22_G | OTHERS | BUS | 6 | 5 | 5 | 10 | 5 | 14 | 6 | 10 | 12 | 12 | 12 | 12 |  | 50 Ohms | TOP=L2:L3=L2/L4:L6=L5/L7:BOTTOM=L7 |
| PQ22_G | OTHERS | BUS | 7 | 5 | 5 | 10 | 5 | 14 | 6 | 10 | 12 | 12 | 12 | 12 |  | 50 Ohms | TOP=L2:L3=L2/L4:L6=L5/L7:BOTTOM=L7 |
| PQ22_G | OTHERS | BUS | 8 | 4.75 | 5 | 10 | 5 | 14 | 6 | 9.5 | 12 | 12 | 12 | 12 |  | 50 Ohms | TOP=L2:L3=L2/L4:L6=L5/L7:BOTTOM=L7 |
| PU_IBMC_BT_HOLD_N | OTHERS | BUS | 1 | 4.75 | 5 | 10 | 5 | 14 | 6 | 9.5 | 12 | 12 | 12 | 12 |  | 50 Ohms | TOP=L2:L3=L2/L4:L6=L5/L7:BOTTOM=L7 |
| PU_IBMC_BT_HOLD_N | OTHERS | BUS | 2 | 5 | 5 | 10 | 5 | 14 | 6 | 10 | 12 | 12 | 12 | 12 |  | 50 Ohms | TOP=L2:L3=L2/L4:L6=L5/L7:BOTTOM=L7 |
| PU_IBMC_BT_HOLD_N | OTHERS | BUS | 3 | 5 | 5 | 10 | 5 | 14 | 6 | 10 | 12 | 12 | 12 | 12 |  | 50 Ohms | TOP=L2:L3=L2/L4:L6=L5/L7:BOTTOM=L7 |
| PU_IBMC_BT_HOLD_N | OTHERS | BUS | 4 | 5 | 5 | 10 | 5 | 14 | 6 | 10 | 12 | 12 | 12 | 12 |  | 50 Ohms | TOP=L2:L3=L2/L4:L6=L5/L7:BOTTOM=L7 |
| PU_IBMC_BT_HOLD_N | OTHERS | BUS | 5 | 5 | 5 | 10 | 5 | 14 | 6 | 10 | 12 | 12 | 12 | 12 |  | 50 Ohms | TOP=L2:L3=L2/L4:L6=L5/L7:BOTTOM=L7 |
| PU_IBMC_BT_HOLD_N | OTHERS | BUS | 6 | 5 | 5 | 10 | 5 | 14 | 6 | 10 | 12 | 12 | 12 | 12 |  | 50 Ohms | TOP=L2:L3=L2/L4:L6=L5/L7:BOTTOM=L7 |
| PU_IBMC_BT_HOLD_N | OTHERS | BUS | 7 | 5 | 5 | 10 | 5 | 14 | 6 | 10 | 12 | 12 | 12 | 12 |  | 50 Ohms | TOP=L2:L3=L2/L4:L6=L5/L7:BOTTOM=L7 |
| PU_IBMC_BT_HOLD_N | OTHERS | BUS | 8 | 4.75 | 5 | 10 | 5 | 14 | 6 | 9.5 | 12 | 12 | 12 | 12 |  | 50 Ohms | TOP=L2:L3=L2/L4:L6=L5/L7:BOTTOM=L7 |
| PWGD_P0V9_E_PG_R | OTHERS | BUS | 1 | 4.75 | 5 | 10 | 5 | 14 | 6 | 9.5 | 12 | 12 | 12 | 12 |  | 50 Ohms | TOP=L2:L3=L2/L4:L6=L5/L7:BOTTOM=L7 |
| PWGD_P0V9_E_PG_R | OTHERS | BUS | 2 | 5 | 5 | 10 | 5 | 14 | 6 | 10 | 12 | 12 | 12 | 12 |  | 50 Ohms | TOP=L2:L3=L2/L4:L6=L5/L7:BOTTOM=L7 |
| PWGD_P0V9_E_PG_R | OTHERS | BUS | 3 | 5 | 5 | 10 | 5 | 14 | 6 | 10 | 12 | 12 | 12 | 12 |  | 50 Ohms | TOP=L2:L3=L2/L4:L6=L5/L7:BOTTOM=L7 |
| PWGD_P0V9_E_PG_R | OTHERS | BUS | 4 | 5 | 5 | 10 | 5 | 14 | 6 | 10 | 12 | 12 | 12 | 12 |  | 50 Ohms | TOP=L2:L3=L2/L4:L6=L5/L7:BOTTOM=L7 |
| PWGD_P0V9_E_PG_R | OTHERS | BUS | 5 | 5 | 5 | 10 | 5 | 14 | 6 | 10 | 12 | 12 | 12 | 12 |  | 50 Ohms | TOP=L2:L3=L2/L4:L6=L5/L7:BOTTOM=L7 |
| PWGD_P0V9_E_PG_R | OTHERS | BUS | 6 | 5 | 5 | 10 | 5 | 14 | 6 | 10 | 12 | 12 | 12 | 12 |  | 50 Ohms | TOP=L2:L3=L2/L4:L6=L5/L7:BOTTOM=L7 |
| PWGD_P0V9_E_PG_R | OTHERS | BUS | 7 | 5 | 5 | 10 | 5 | 14 | 6 | 10 | 12 | 12 | 12 | 12 |  | 50 Ohms | TOP=L2:L3=L2/L4:L6=L5/L7:BOTTOM=L7 |
| PWGD_P0V9_E_PG_R | OTHERS | BUS | 8 | 4.75 | 5 | 10 | 5 | 14 | 6 | 9.5 | 12 | 12 | 12 | 12 |  | 50 Ohms | TOP=L2:L3=L2/L4:L6=L5/L7:BOTTOM=L7 |
| PWM_EXP_A | OTHERS | BUS | 1 | 4.75 | 5 | 10 | 5 | 14 | 6 | 9.5 | 12 | 12 | 12 | 12 |  | 50 Ohms | TOP=L2:L3=L2/L4:L6=L5/L7:BOTTOM=L7 |
| PWM_EXP_A | OTHERS | BUS | 2 | 5 | 5 | 10 | 5 | 14 | 6 | 10 | 12 | 12 | 12 | 12 |  | 50 Ohms | TOP=L2:L3=L2/L4:L6=L5/L7:BOTTOM=L7 |
| PWM_EXP_A | OTHERS | BUS | 3 | 5 | 5 | 10 | 5 | 14 | 6 | 10 | 12 | 12 | 12 | 12 |  | 50 Ohms | TOP=L2:L3=L2/L4:L6=L5/L7:BOTTOM=L7 |
| PWM_EXP_A | OTHERS | BUS | 4 | 5 | 5 | 10 | 5 | 14 | 6 | 10 | 12 | 12 | 12 | 12 |  | 50 Ohms | TOP=L2:L3=L2/L4:L6=L5/L7:BOTTOM=L7 |
| PWM_EXP_A | OTHERS | BUS | 5 | 5 | 5 | 10 | 5 | 14 | 6 | 10 | 12 | 12 | 12 | 12 |  | 50 Ohms | TOP=L2:L3=L2/L4:L6=L5/L7:BOTTOM=L7 |
| PWM_EXP_A | OTHERS | BUS | 6 | 5 | 5 | 10 | 5 | 14 | 6 | 10 | 12 | 12 | 12 | 12 |  | 50 Ohms | TOP=L2:L3=L2/L4:L6=L5/L7:BOTTOM=L7 |
| PWM_EXP_A | OTHERS | BUS | 7 | 5 | 5 | 10 | 5 | 14 | 6 | 10 | 12 | 12 | 12 | 12 |  | 50 Ohms | TOP=L2:L3=L2/L4:L6=L5/L7:BOTTOM=L7 |
| PWM_EXP_A | OTHERS | BUS | 8 | 4.75 | 5 | 10 | 5 | 14 | 6 | 9.5 | 12 | 12 | 12 | 12 |  | 50 Ohms | TOP=L2:L3=L2/L4:L6=L5/L7:BOTTOM=L7 |
| PWRGD_P1V26_STBY | OTHERS | BUS | 1 | 4.75 | 5 | 10 | 5 | 14 | 6 | 9.5 | 12 | 12 | 12 | 12 |  | 50 Ohms | TOP=L2:L3=L2/L4:L6=L5/L7:BOTTOM=L7 |
| PWRGD_P1V26_STBY | OTHERS | BUS | 2 | 5 | 5 | 10 | 5 | 14 | 6 | 10 | 12 | 12 | 12 | 12 |  | 50 Ohms | TOP=L2:L3=L2/L4:L6=L5/L7:BOTTOM=L7 |
| PWRGD_P1V26_STBY | OTHERS | BUS | 3 | 5 | 5 | 10 | 5 | 14 | 6 | 10 | 12 | 12 | 12 | 12 |  | 50 Ohms | TOP=L2:L3=L2/L4:L6=L5/L7:BOTTOM=L7 |
| PWRGD_P1V26_STBY | OTHERS | BUS | 4 | 5 | 5 | 10 | 5 | 14 | 6 | 10 | 12 | 12 | 12 | 12 |  | 50 Ohms | TOP=L2:L3=L2/L4:L6=L5/L7:BOTTOM=L7 |
| PWRGD_P1V26_STBY | OTHERS | BUS | 5 | 5 | 5 | 10 | 5 | 14 | 6 | 10 | 12 | 12 | 12 | 12 |  | 50 Ohms | TOP=L2:L3=L2/L4:L6=L5/L7:BOTTOM=L7 |
| PWRGD_P1V26_STBY | OTHERS | BUS | 6 | 5 | 5 | 10 | 5 | 14 | 6 | 10 | 12 | 12 | 12 | 12 |  | 50 Ohms | TOP=L2:L3=L2/L4:L6=L5/L7:BOTTOM=L7 |
| PWRGD_P1V26_STBY | OTHERS | BUS | 7 | 5 | 5 | 10 | 5 | 14 | 6 | 10 | 12 | 12 | 12 | 12 |  | 50 Ohms | TOP=L2:L3=L2/L4:L6=L5/L7:BOTTOM=L7 |
| PWRGD_P1V26_STBY | OTHERS | BUS | 8 | 4.75 | 5 | 10 | 5 | 14 | 6 | 9.5 | 12 | 12 | 12 | 12 |  | 50 Ohms | TOP=L2:L3=L2/L4:L6=L5/L7:BOTTOM=L7 |
| PWRGD_P1V538_STBY | OTHERS | BUS | 1 | 4.75 | 5 | 10 | 5 | 14 | 6 | 9.5 | 12 | 12 | 12 | 12 |  | 50 Ohms | TOP=L2:L3=L2/L4:L6=L5/L7:BOTTOM=L7 |
| PWRGD_P1V538_STBY | OTHERS | BUS | 2 | 5 | 5 | 10 | 5 | 14 | 6 | 10 | 12 | 12 | 12 | 12 |  | 50 Ohms | TOP=L2:L3=L2/L4:L6=L5/L7:BOTTOM=L7 |
| PWRGD_P1V538_STBY | OTHERS | BUS | 3 | 5 | 5 | 10 | 5 | 14 | 6 | 10 | 12 | 12 | 12 | 12 |  | 50 Ohms | TOP=L2:L3=L2/L4:L6=L5/L7:BOTTOM=L7 |
| PWRGD_P1V538_STBY | OTHERS | BUS | 4 | 5 | 5 | 10 | 5 | 14 | 6 | 10 | 12 | 12 | 12 | 12 |  | 50 Ohms | TOP=L2:L3=L2/L4:L6=L5/L7:BOTTOM=L7 |
| PWRGD_P1V538_STBY | OTHERS | BUS | 5 | 5 | 5 | 10 | 5 | 14 | 6 | 10 | 12 | 12 | 12 | 12 |  | 50 Ohms | TOP=L2:L3=L2/L4:L6=L5/L7:BOTTOM=L7 |
| PWRGD_P1V538_STBY | OTHERS | BUS | 6 | 5 | 5 | 10 | 5 | 14 | 6 | 10 | 12 | 12 | 12 | 12 |  | 50 Ohms | TOP=L2:L3=L2/L4:L6=L5/L7:BOTTOM=L7 |
| PWRGD_P1V538_STBY | OTHERS | BUS | 7 | 5 | 5 | 10 | 5 | 14 | 6 | 10 | 12 | 12 | 12 | 12 |  | 50 Ohms | TOP=L2:L3=L2/L4:L6=L5/L7:BOTTOM=L7 |
| PWRGD_P1V538_STBY | OTHERS | BUS | 8 | 4.75 | 5 | 10 | 5 | 14 | 6 | 9.5 | 12 | 12 | 12 | 12 |  | 50 Ohms | TOP=L2:L3=L2/L4:L6=L5/L7:BOTTOM=L7 |
| PWRGD_P1V8_STBY | OTHERS | BUS | 1 | 4.75 | 5 | 10 | 5 | 14 | 6 | 9.5 | 12 | 12 | 12 | 12 |  | 50 Ohms | TOP=L2:L3=L2/L4:L6=L5/L7:BOTTOM=L7 |
| PWRGD_P1V8_STBY | OTHERS | BUS | 2 | 5 | 5 | 10 | 5 | 14 | 6 | 10 | 12 | 12 | 12 | 12 |  | 50 Ohms | TOP=L2:L3=L2/L4:L6=L5/L7:BOTTOM=L7 |
| PWRGD_P1V8_STBY | OTHERS | BUS | 3 | 5 | 5 | 10 | 5 | 14 | 6 | 10 | 12 | 12 | 12 | 12 |  | 50 Ohms | TOP=L2:L3=L2/L4:L6=L5/L7:BOTTOM=L7 |
| PWRGD_P1V8_STBY | OTHERS | BUS | 4 | 5 | 5 | 10 | 5 | 14 | 6 | 10 | 12 | 12 | 12 | 12 |  | 50 Ohms | TOP=L2:L3=L2/L4:L6=L5/L7:BOTTOM=L7 |
| PWRGD_P1V8_STBY | OTHERS | BUS | 5 | 5 | 5 | 10 | 5 | 14 | 6 | 10 | 12 | 12 | 12 | 12 |  | 50 Ohms | TOP=L2:L3=L2/L4:L6=L5/L7:BOTTOM=L7 |
| PWRGD_P1V8_STBY | OTHERS | BUS | 6 | 5 | 5 | 10 | 5 | 14 | 6 | 10 | 12 | 12 | 12 | 12 |  | 50 Ohms | TOP=L2:L3=L2/L4:L6=L5/L7:BOTTOM=L7 |
| PWRGD_P1V8_STBY | OTHERS | BUS | 7 | 5 | 5 | 10 | 5 | 14 | 6 | 10 | 12 | 12 | 12 | 12 |  | 50 Ohms | TOP=L2:L3=L2/L4:L6=L5/L7:BOTTOM=L7 |
| PWRGD_P1V8_STBY | OTHERS | BUS | 8 | 4.75 | 5 | 10 | 5 | 14 | 6 | 9.5 | 12 | 12 | 12 | 12 |  | 50 Ohms | TOP=L2:L3=L2/L4:L6=L5/L7:BOTTOM=L7 |
| Q20_G | OTHERS | BUS | 1 | 4.75 | 5 | 10 | 5 | 14 | 6 | 9.5 | 12 | 12 | 12 | 12 |  | 50 Ohms | TOP=L2:L3=L2/L4:L6=L5/L7:BOTTOM=L7 |
| Q20_G | OTHERS | BUS | 2 | 5 | 5 | 10 | 5 | 14 | 6 | 10 | 12 | 12 | 12 | 12 |  | 50 Ohms | TOP=L2:L3=L2/L4:L6=L5/L7:BOTTOM=L7 |
| Q20_G | OTHERS | BUS | 3 | 5 | 5 | 10 | 5 | 14 | 6 | 10 | 12 | 12 | 12 | 12 |  | 50 Ohms | TOP=L2:L3=L2/L4:L6=L5/L7:BOTTOM=L7 |
| Q20_G | OTHERS | BUS | 4 | 5 | 5 | 10 | 5 | 14 | 6 | 10 | 12 | 12 | 12 | 12 |  | 50 Ohms | TOP=L2:L3=L2/L4:L6=L5/L7:BOTTOM=L7 |
| Q20_G | OTHERS | BUS | 5 | 5 | 5 | 10 | 5 | 14 | 6 | 10 | 12 | 12 | 12 | 12 |  | 50 Ohms | TOP=L2:L3=L2/L4:L6=L5/L7:BOTTOM=L7 |
| Q20_G | OTHERS | BUS | 6 | 5 | 5 | 10 | 5 | 14 | 6 | 10 | 12 | 12 | 12 | 12 |  | 50 Ohms | TOP=L2:L3=L2/L4:L6=L5/L7:BOTTOM=L7 |
| Q20_G | OTHERS | BUS | 7 | 5 | 5 | 10 | 5 | 14 | 6 | 10 | 12 | 12 | 12 | 12 |  | 50 Ohms | TOP=L2:L3=L2/L4:L6=L5/L7:BOTTOM=L7 |
| Q20_G | OTHERS | BUS | 8 | 4.75 | 5 | 10 | 5 | 14 | 6 | 9.5 | 12 | 12 | 12 | 12 |  | 50 Ohms | TOP=L2:L3=L2/L4:L6=L5/L7:BOTTOM=L7 |
| Q21_G | OTHERS | BUS | 1 | 4.75 | 5 | 10 | 5 | 14 | 6 | 9.5 | 12 | 12 | 12 | 12 |  | 50 Ohms | TOP=L2:L3=L2/L4:L6=L5/L7:BOTTOM=L7 |
| Q21_G | OTHERS | BUS | 2 | 5 | 5 | 10 | 5 | 14 | 6 | 10 | 12 | 12 | 12 | 12 |  | 50 Ohms | TOP=L2:L3=L2/L4:L6=L5/L7:BOTTOM=L7 |
| Q21_G | OTHERS | BUS | 3 | 5 | 5 | 10 | 5 | 14 | 6 | 10 | 12 | 12 | 12 | 12 |  | 50 Ohms | TOP=L2:L3=L2/L4:L6=L5/L7:BOTTOM=L7 |
| Q21_G | OTHERS | BUS | 4 | 5 | 5 | 10 | 5 | 14 | 6 | 10 | 12 | 12 | 12 | 12 |  | 50 Ohms | TOP=L2:L3=L2/L4:L6=L5/L7:BOTTOM=L7 |
| Q21_G | OTHERS | BUS | 5 | 5 | 5 | 10 | 5 | 14 | 6 | 10 | 12 | 12 | 12 | 12 |  | 50 Ohms | TOP=L2:L3=L2/L4:L6=L5/L7:BOTTOM=L7 |
| Q21_G | OTHERS | BUS | 6 | 5 | 5 | 10 | 5 | 14 | 6 | 10 | 12 | 12 | 12 | 12 |  | 50 Ohms | TOP=L2:L3=L2/L4:L6=L5/L7:BOTTOM=L7 |
| Q21_G | OTHERS | BUS | 7 | 5 | 5 | 10 | 5 | 14 | 6 | 10 | 12 | 12 | 12 | 12 |  | 50 Ohms | TOP=L2:L3=L2/L4:L6=L5/L7:BOTTOM=L7 |
| Q21_G | OTHERS | BUS | 8 | 4.75 | 5 | 10 | 5 | 14 | 6 | 9.5 | 12 | 12 | 12 | 12 |  | 50 Ohms | TOP=L2:L3=L2/L4:L6=L5/L7:BOTTOM=L7 |
| Q22_D | OTHERS | BUS | 1 | 4.75 | 5 | 10 | 5 | 14 | 6 | 9.5 | 12 | 12 | 12 | 12 |  | 50 Ohms | TOP=L2:L3=L2/L4:L6=L5/L7:BOTTOM=L7 |
| Q22_D | OTHERS | BUS | 2 | 5 | 5 | 10 | 5 | 14 | 6 | 10 | 12 | 12 | 12 | 12 |  | 50 Ohms | TOP=L2:L3=L2/L4:L6=L5/L7:BOTTOM=L7 |
| Q22_D | OTHERS | BUS | 3 | 5 | 5 | 10 | 5 | 14 | 6 | 10 | 12 | 12 | 12 | 12 |  | 50 Ohms | TOP=L2:L3=L2/L4:L6=L5/L7:BOTTOM=L7 |
| Q22_D | OTHERS | BUS | 4 | 5 | 5 | 10 | 5 | 14 | 6 | 10 | 12 | 12 | 12 | 12 |  | 50 Ohms | TOP=L2:L3=L2/L4:L6=L5/L7:BOTTOM=L7 |
| Q22_D | OTHERS | BUS | 5 | 5 | 5 | 10 | 5 | 14 | 6 | 10 | 12 | 12 | 12 | 12 |  | 50 Ohms | TOP=L2:L3=L2/L4:L6=L5/L7:BOTTOM=L7 |
| Q22_D | OTHERS | BUS | 6 | 5 | 5 | 10 | 5 | 14 | 6 | 10 | 12 | 12 | 12 | 12 |  | 50 Ohms | TOP=L2:L3=L2/L4:L6=L5/L7:BOTTOM=L7 |
| Q22_D | OTHERS | BUS | 7 | 5 | 5 | 10 | 5 | 14 | 6 | 10 | 12 | 12 | 12 | 12 |  | 50 Ohms | TOP=L2:L3=L2/L4:L6=L5/L7:BOTTOM=L7 |
| Q22_D | OTHERS | BUS | 8 | 4.75 | 5 | 10 | 5 | 14 | 6 | 9.5 | 12 | 12 | 12 | 12 |  | 50 Ohms | TOP=L2:L3=L2/L4:L6=L5/L7:BOTTOM=L7 |
| Q22_G | OTHERS | BUS | 1 | 4.75 | 5 | 10 | 5 | 14 | 6 | 9.5 | 12 | 12 | 12 | 12 |  | 50 Ohms | TOP=L2:L3=L2/L4:L6=L5/L7:BOTTOM=L7 |
| Q22_G | OTHERS | BUS | 2 | 5 | 5 | 10 | 5 | 14 | 6 | 10 | 12 | 12 | 12 | 12 |  | 50 Ohms | TOP=L2:L3=L2/L4:L6=L5/L7:BOTTOM=L7 |
| Q22_G | OTHERS | BUS | 3 | 5 | 5 | 10 | 5 | 14 | 6 | 10 | 12 | 12 | 12 | 12 |  | 50 Ohms | TOP=L2:L3=L2/L4:L6=L5/L7:BOTTOM=L7 |
| Q22_G | OTHERS | BUS | 4 | 5 | 5 | 10 | 5 | 14 | 6 | 10 | 12 | 12 | 12 | 12 |  | 50 Ohms | TOP=L2:L3=L2/L4:L6=L5/L7:BOTTOM=L7 |
| Q22_G | OTHERS | BUS | 5 | 5 | 5 | 10 | 5 | 14 | 6 | 10 | 12 | 12 | 12 | 12 |  | 50 Ohms | TOP=L2:L3=L2/L4:L6=L5/L7:BOTTOM=L7 |
| Q22_G | OTHERS | BUS | 6 | 5 | 5 | 10 | 5 | 14 | 6 | 10 | 12 | 12 | 12 | 12 |  | 50 Ohms | TOP=L2:L3=L2/L4:L6=L5/L7:BOTTOM=L7 |
| Q22_G | OTHERS | BUS | 7 | 5 | 5 | 10 | 5 | 14 | 6 | 10 | 12 | 12 | 12 | 12 |  | 50 Ohms | TOP=L2:L3=L2/L4:L6=L5/L7:BOTTOM=L7 |
| Q22_G | OTHERS | BUS | 8 | 4.75 | 5 | 10 | 5 | 14 | 6 | 9.5 | 12 | 12 | 12 | 12 |  | 50 Ohms | TOP=L2:L3=L2/L4:L6=L5/L7:BOTTOM=L7 |
| Q3202_D | OTHERS | BUS | 1 | 4.75 | 5 | 10 | 5 | 14 | 6 | 9.5 | 12 | 12 | 12 | 12 |  | 50 Ohms | TOP=L2:L3=L2/L4:L6=L5/L7:BOTTOM=L7 |
| Q3202_D | OTHERS | BUS | 2 | 5 | 5 | 10 | 5 | 14 | 6 | 10 | 12 | 12 | 12 | 12 |  | 50 Ohms | TOP=L2:L3=L2/L4:L6=L5/L7:BOTTOM=L7 |
| Q3202_D | OTHERS | BUS | 3 | 5 | 5 | 10 | 5 | 14 | 6 | 10 | 12 | 12 | 12 | 12 |  | 50 Ohms | TOP=L2:L3=L2/L4:L6=L5/L7:BOTTOM=L7 |
| Q3202_D | OTHERS | BUS | 4 | 5 | 5 | 10 | 5 | 14 | 6 | 10 | 12 | 12 | 12 | 12 |  | 50 Ohms | TOP=L2:L3=L2/L4:L6=L5/L7:BOTTOM=L7 |
| Q3202_D | OTHERS | BUS | 5 | 5 | 5 | 10 | 5 | 14 | 6 | 10 | 12 | 12 | 12 | 12 |  | 50 Ohms | TOP=L2:L3=L2/L4:L6=L5/L7:BOTTOM=L7 |
| Q3202_D | OTHERS | BUS | 6 | 5 | 5 | 10 | 5 | 14 | 6 | 10 | 12 | 12 | 12 | 12 |  | 50 Ohms | TOP=L2:L3=L2/L4:L6=L5/L7:BOTTOM=L7 |
| Q3202_D | OTHERS | BUS | 7 | 5 | 5 | 10 | 5 | 14 | 6 | 10 | 12 | 12 | 12 | 12 |  | 50 Ohms | TOP=L2:L3=L2/L4:L6=L5/L7:BOTTOM=L7 |
| Q3202_D | OTHERS | BUS | 8 | 4.75 | 5 | 10 | 5 | 14 | 6 | 9.5 | 12 | 12 | 12 | 12 |  | 50 Ohms | TOP=L2:L3=L2/L4:L6=L5/L7:BOTTOM=L7 |
| Q3203_G | OTHERS | BUS | 1 | 4.75 | 5 | 10 | 5 | 14 | 6 | 9.5 | 12 | 12 | 12 | 12 |  | 50 Ohms | TOP=L2:L3=L2/L4:L6=L5/L7:BOTTOM=L7 |
| Q3203_G | OTHERS | BUS | 2 | 5 | 5 | 10 | 5 | 14 | 6 | 10 | 12 | 12 | 12 | 12 |  | 50 Ohms | TOP=L2:L3=L2/L4:L6=L5/L7:BOTTOM=L7 |
| Q3203_G | OTHERS | BUS | 3 | 5 | 5 | 10 | 5 | 14 | 6 | 10 | 12 | 12 | 12 | 12 |  | 50 Ohms | TOP=L2:L3=L2/L4:L6=L5/L7:BOTTOM=L7 |
| Q3203_G | OTHERS | BUS | 4 | 5 | 5 | 10 | 5 | 14 | 6 | 10 | 12 | 12 | 12 | 12 |  | 50 Ohms | TOP=L2:L3=L2/L4:L6=L5/L7:BOTTOM=L7 |
| Q3203_G | OTHERS | BUS | 5 | 5 | 5 | 10 | 5 | 14 | 6 | 10 | 12 | 12 | 12 | 12 |  | 50 Ohms | TOP=L2:L3=L2/L4:L6=L5/L7:BOTTOM=L7 |
| Q3203_G | OTHERS | BUS | 6 | 5 | 5 | 10 | 5 | 14 | 6 | 10 | 12 | 12 | 12 | 12 |  | 50 Ohms | TOP=L2:L3=L2/L4:L6=L5/L7:BOTTOM=L7 |
| Q3203_G | OTHERS | BUS | 7 | 5 | 5 | 10 | 5 | 14 | 6 | 10 | 12 | 12 | 12 | 12 |  | 50 Ohms | TOP=L2:L3=L2/L4:L6=L5/L7:BOTTOM=L7 |
| Q3203_G | OTHERS | BUS | 8 | 4.75 | 5 | 10 | 5 | 14 | 6 | 9.5 | 12 | 12 | 12 | 12 |  | 50 Ohms | TOP=L2:L3=L2/L4:L6=L5/L7:BOTTOM=L7 |
| Q37_G | OTHERS | BUS | 1 | 4.75 | 5 | 10 | 5 | 14 | 6 | 9.5 | 12 | 12 | 12 | 12 |  | 50 Ohms | TOP=L2:L3=L2/L4:L6=L5/L7:BOTTOM=L7 |
| Q37_G | OTHERS | BUS | 2 | 5 | 5 | 10 | 5 | 14 | 6 | 10 | 12 | 12 | 12 | 12 |  | 50 Ohms | TOP=L2:L3=L2/L4:L6=L5/L7:BOTTOM=L7 |
| Q37_G | OTHERS | BUS | 3 | 5 | 5 | 10 | 5 | 14 | 6 | 10 | 12 | 12 | 12 | 12 |  | 50 Ohms | TOP=L2:L3=L2/L4:L6=L5/L7:BOTTOM=L7 |
| Q37_G | OTHERS | BUS | 4 | 5 | 5 | 10 | 5 | 14 | 6 | 10 | 12 | 12 | 12 | 12 |  | 50 Ohms | TOP=L2:L3=L2/L4:L6=L5/L7:BOTTOM=L7 |
| Q37_G | OTHERS | BUS | 5 | 5 | 5 | 10 | 5 | 14 | 6 | 10 | 12 | 12 | 12 | 12 |  | 50 Ohms | TOP=L2:L3=L2/L4:L6=L5/L7:BOTTOM=L7 |
| Q37_G | OTHERS | BUS | 6 | 5 | 5 | 10 | 5 | 14 | 6 | 10 | 12 | 12 | 12 | 12 |  | 50 Ohms | TOP=L2:L3=L2/L4:L6=L5/L7:BOTTOM=L7 |
| Q37_G | OTHERS | BUS | 7 | 5 | 5 | 10 | 5 | 14 | 6 | 10 | 12 | 12 | 12 | 12 |  | 50 Ohms | TOP=L2:L3=L2/L4:L6=L5/L7:BOTTOM=L7 |
| Q37_G | OTHERS | BUS | 8 | 4.75 | 5 | 10 | 5 | 14 | 6 | 9.5 | 12 | 12 | 12 | 12 |  | 50 Ohms | TOP=L2:L3=L2/L4:L6=L5/L7:BOTTOM=L7 |
| Q40_D | OTHERS | BUS | 1 | 4.75 | 5 | 10 | 5 | 14 | 6 | 9.5 | 12 | 12 | 12 | 12 |  | 50 Ohms | TOP=L2:L3=L2/L4:L6=L5/L7:BOTTOM=L7 |
| Q40_D | OTHERS | BUS | 2 | 5 | 5 | 10 | 5 | 14 | 6 | 10 | 12 | 12 | 12 | 12 |  | 50 Ohms | TOP=L2:L3=L2/L4:L6=L5/L7:BOTTOM=L7 |
| Q40_D | OTHERS | BUS | 3 | 5 | 5 | 10 | 5 | 14 | 6 | 10 | 12 | 12 | 12 | 12 |  | 50 Ohms | TOP=L2:L3=L2/L4:L6=L5/L7:BOTTOM=L7 |
| Q40_D | OTHERS | BUS | 4 | 5 | 5 | 10 | 5 | 14 | 6 | 10 | 12 | 12 | 12 | 12 |  | 50 Ohms | TOP=L2:L3=L2/L4:L6=L5/L7:BOTTOM=L7 |
| Q40_D | OTHERS | BUS | 5 | 5 | 5 | 10 | 5 | 14 | 6 | 10 | 12 | 12 | 12 | 12 |  | 50 Ohms | TOP=L2:L3=L2/L4:L6=L5/L7:BOTTOM=L7 |
| Q40_D | OTHERS | BUS | 6 | 5 | 5 | 10 | 5 | 14 | 6 | 10 | 12 | 12 | 12 | 12 |  | 50 Ohms | TOP=L2:L3=L2/L4:L6=L5/L7:BOTTOM=L7 |
| Q40_D | OTHERS | BUS | 7 | 5 | 5 | 10 | 5 | 14 | 6 | 10 | 12 | 12 | 12 | 12 |  | 50 Ohms | TOP=L2:L3=L2/L4:L6=L5/L7:BOTTOM=L7 |
| Q40_D | OTHERS | BUS | 8 | 4.75 | 5 | 10 | 5 | 14 | 6 | 9.5 | 12 | 12 | 12 | 12 |  | 50 Ohms | TOP=L2:L3=L2/L4:L6=L5/L7:BOTTOM=L7 |
| Q42_D | OTHERS | BUS | 1 | 4.75 | 5 | 10 | 5 | 14 | 6 | 9.5 | 12 | 12 | 12 | 12 |  | 50 Ohms | TOP=L2:L3=L2/L4:L6=L5/L7:BOTTOM=L7 |
| Q42_D | OTHERS | BUS | 2 | 5 | 5 | 10 | 5 | 14 | 6 | 10 | 12 | 12 | 12 | 12 |  | 50 Ohms | TOP=L2:L3=L2/L4:L6=L5/L7:BOTTOM=L7 |
| Q42_D | OTHERS | BUS | 3 | 5 | 5 | 10 | 5 | 14 | 6 | 10 | 12 | 12 | 12 | 12 |  | 50 Ohms | TOP=L2:L3=L2/L4:L6=L5/L7:BOTTOM=L7 |
| Q42_D | OTHERS | BUS | 4 | 5 | 5 | 10 | 5 | 14 | 6 | 10 | 12 | 12 | 12 | 12 |  | 50 Ohms | TOP=L2:L3=L2/L4:L6=L5/L7:BOTTOM=L7 |
| Q42_D | OTHERS | BUS | 5 | 5 | 5 | 10 | 5 | 14 | 6 | 10 | 12 | 12 | 12 | 12 |  | 50 Ohms | TOP=L2:L3=L2/L4:L6=L5/L7:BOTTOM=L7 |
| Q42_D | OTHERS | BUS | 6 | 5 | 5 | 10 | 5 | 14 | 6 | 10 | 12 | 12 | 12 | 12 |  | 50 Ohms | TOP=L2:L3=L2/L4:L6=L5/L7:BOTTOM=L7 |
| Q42_D | OTHERS | BUS | 7 | 5 | 5 | 10 | 5 | 14 | 6 | 10 | 12 | 12 | 12 | 12 |  | 50 Ohms | TOP=L2:L3=L2/L4:L6=L5/L7:BOTTOM=L7 |
| Q42_D | OTHERS | BUS | 8 | 4.75 | 5 | 10 | 5 | 14 | 6 | 9.5 | 12 | 12 | 12 | 12 |  | 50 Ohms | TOP=L2:L3=L2/L4:L6=L5/L7:BOTTOM=L7 |
| Q43_B | OTHERS | BUS | 1 | 4.75 | 5 | 10 | 5 | 14 | 6 | 9.5 | 12 | 12 | 12 | 12 |  | 50 Ohms | TOP=L2:L3=L2/L4:L6=L5/L7:BOTTOM=L7 |
| Q43_B | OTHERS | BUS | 2 | 5 | 5 | 10 | 5 | 14 | 6 | 10 | 12 | 12 | 12 | 12 |  | 50 Ohms | TOP=L2:L3=L2/L4:L6=L5/L7:BOTTOM=L7 |
| Q43_B | OTHERS | BUS | 3 | 5 | 5 | 10 | 5 | 14 | 6 | 10 | 12 | 12 | 12 | 12 |  | 50 Ohms | TOP=L2:L3=L2/L4:L6=L5/L7:BOTTOM=L7 |
| Q43_B | OTHERS | BUS | 4 | 5 | 5 | 10 | 5 | 14 | 6 | 10 | 12 | 12 | 12 | 12 |  | 50 Ohms | TOP=L2:L3=L2/L4:L6=L5/L7:BOTTOM=L7 |
| Q43_B | OTHERS | BUS | 5 | 5 | 5 | 10 | 5 | 14 | 6 | 10 | 12 | 12 | 12 | 12 |  | 50 Ohms | TOP=L2:L3=L2/L4:L6=L5/L7:BOTTOM=L7 |
| Q43_B | OTHERS | BUS | 6 | 5 | 5 | 10 | 5 | 14 | 6 | 10 | 12 | 12 | 12 | 12 |  | 50 Ohms | TOP=L2:L3=L2/L4:L6=L5/L7:BOTTOM=L7 |
| Q43_B | OTHERS | BUS | 7 | 5 | 5 | 10 | 5 | 14 | 6 | 10 | 12 | 12 | 12 | 12 |  | 50 Ohms | TOP=L2:L3=L2/L4:L6=L5/L7:BOTTOM=L7 |
| Q43_B | OTHERS | BUS | 8 | 4.75 | 5 | 10 | 5 | 14 | 6 | 9.5 | 12 | 12 | 12 | 12 |  | 50 Ohms | TOP=L2:L3=L2/L4:L6=L5/L7:BOTTOM=L7 |
| Q45_D | OTHERS | BUS | 1 | 4.75 | 5 | 10 | 5 | 14 | 6 | 9.5 | 12 | 12 | 12 | 12 |  | 50 Ohms | TOP=L2:L3=L2/L4:L6=L5/L7:BOTTOM=L7 |
| Q45_D | OTHERS | BUS | 2 | 5 | 5 | 10 | 5 | 14 | 6 | 10 | 12 | 12 | 12 | 12 |  | 50 Ohms | TOP=L2:L3=L2/L4:L6=L5/L7:BOTTOM=L7 |
| Q45_D | OTHERS | BUS | 3 | 5 | 5 | 10 | 5 | 14 | 6 | 10 | 12 | 12 | 12 | 12 |  | 50 Ohms | TOP=L2:L3=L2/L4:L6=L5/L7:BOTTOM=L7 |
| Q45_D | OTHERS | BUS | 4 | 5 | 5 | 10 | 5 | 14 | 6 | 10 | 12 | 12 | 12 | 12 |  | 50 Ohms | TOP=L2:L3=L2/L4:L6=L5/L7:BOTTOM=L7 |
| Q45_D | OTHERS | BUS | 5 | 5 | 5 | 10 | 5 | 14 | 6 | 10 | 12 | 12 | 12 | 12 |  | 50 Ohms | TOP=L2:L3=L2/L4:L6=L5/L7:BOTTOM=L7 |
| Q45_D | OTHERS | BUS | 6 | 5 | 5 | 10 | 5 | 14 | 6 | 10 | 12 | 12 | 12 | 12 |  | 50 Ohms | TOP=L2:L3=L2/L4:L6=L5/L7:BOTTOM=L7 |
| Q45_D | OTHERS | BUS | 7 | 5 | 5 | 10 | 5 | 14 | 6 | 10 | 12 | 12 | 12 | 12 |  | 50 Ohms | TOP=L2:L3=L2/L4:L6=L5/L7:BOTTOM=L7 |
| Q45_D | OTHERS | BUS | 8 | 4.75 | 5 | 10 | 5 | 14 | 6 | 9.5 | 12 | 12 | 12 | 12 |  | 50 Ohms | TOP=L2:L3=L2/L4:L6=L5/L7:BOTTOM=L7 |
| Q46_G | OTHERS | BUS | 1 | 4.75 | 5 | 10 | 5 | 14 | 6 | 9.5 | 12 | 12 | 12 | 12 |  | 50 Ohms | TOP=L2:L3=L2/L4:L6=L5/L7:BOTTOM=L7 |
| Q46_G | OTHERS | BUS | 2 | 5 | 5 | 10 | 5 | 14 | 6 | 10 | 12 | 12 | 12 | 12 |  | 50 Ohms | TOP=L2:L3=L2/L4:L6=L5/L7:BOTTOM=L7 |
| Q46_G | OTHERS | BUS | 3 | 5 | 5 | 10 | 5 | 14 | 6 | 10 | 12 | 12 | 12 | 12 |  | 50 Ohms | TOP=L2:L3=L2/L4:L6=L5/L7:BOTTOM=L7 |
| Q46_G | OTHERS | BUS | 4 | 5 | 5 | 10 | 5 | 14 | 6 | 10 | 12 | 12 | 12 | 12 |  | 50 Ohms | TOP=L2:L3=L2/L4:L6=L5/L7:BOTTOM=L7 |
| Q46_G | OTHERS | BUS | 5 | 5 | 5 | 10 | 5 | 14 | 6 | 10 | 12 | 12 | 12 | 12 |  | 50 Ohms | TOP=L2:L3=L2/L4:L6=L5/L7:BOTTOM=L7 |
| Q46_G | OTHERS | BUS | 6 | 5 | 5 | 10 | 5 | 14 | 6 | 10 | 12 | 12 | 12 | 12 |  | 50 Ohms | TOP=L2:L3=L2/L4:L6=L5/L7:BOTTOM=L7 |
| Q46_G | OTHERS | BUS | 7 | 5 | 5 | 10 | 5 | 14 | 6 | 10 | 12 | 12 | 12 | 12 |  | 50 Ohms | TOP=L2:L3=L2/L4:L6=L5/L7:BOTTOM=L7 |
| Q46_G | OTHERS | BUS | 8 | 4.75 | 5 | 10 | 5 | 14 | 6 | 9.5 | 12 | 12 | 12 | 12 |  | 50 Ohms | TOP=L2:L3=L2/L4:L6=L5/L7:BOTTOM=L7 |
| Q95_D | OTHERS | BUS | 1 | 4.75 | 5 | 10 | 5 | 14 | 6 | 9.5 | 12 | 12 | 12 | 12 |  | 50 Ohms | TOP=L2:L3=L2/L4:L6=L5/L7:BOTTOM=L7 |
| Q95_D | OTHERS | BUS | 2 | 5 | 5 | 10 | 5 | 14 | 6 | 10 | 12 | 12 | 12 | 12 |  | 50 Ohms | TOP=L2:L3=L2/L4:L6=L5/L7:BOTTOM=L7 |
| Q95_D | OTHERS | BUS | 3 | 5 | 5 | 10 | 5 | 14 | 6 | 10 | 12 | 12 | 12 | 12 |  | 50 Ohms | TOP=L2:L3=L2/L4:L6=L5/L7:BOTTOM=L7 |
| Q95_D | OTHERS | BUS | 4 | 5 | 5 | 10 | 5 | 14 | 6 | 10 | 12 | 12 | 12 | 12 |  | 50 Ohms | TOP=L2:L3=L2/L4:L6=L5/L7:BOTTOM=L7 |
| Q95_D | OTHERS | BUS | 5 | 5 | 5 | 10 | 5 | 14 | 6 | 10 | 12 | 12 | 12 | 12 |  | 50 Ohms | TOP=L2:L3=L2/L4:L6=L5/L7:BOTTOM=L7 |
| Q95_D | OTHERS | BUS | 6 | 5 | 5 | 10 | 5 | 14 | 6 | 10 | 12 | 12 | 12 | 12 |  | 50 Ohms | TOP=L2:L3=L2/L4:L6=L5/L7:BOTTOM=L7 |
| Q95_D | OTHERS | BUS | 7 | 5 | 5 | 10 | 5 | 14 | 6 | 10 | 12 | 12 | 12 | 12 |  | 50 Ohms | TOP=L2:L3=L2/L4:L6=L5/L7:BOTTOM=L7 |
| Q95_D | OTHERS | BUS | 8 | 4.75 | 5 | 10 | 5 | 14 | 6 | 9.5 | 12 | 12 | 12 | 12 |  | 50 Ohms | TOP=L2:L3=L2/L4:L6=L5/L7:BOTTOM=L7 |
| Q95_G | OTHERS | BUS | 1 | 4.75 | 5 | 10 | 5 | 14 | 6 | 9.5 | 12 | 12 | 12 | 12 |  | 50 Ohms | TOP=L2:L3=L2/L4:L6=L5/L7:BOTTOM=L7 |
| Q95_G | OTHERS | BUS | 2 | 5 | 5 | 10 | 5 | 14 | 6 | 10 | 12 | 12 | 12 | 12 |  | 50 Ohms | TOP=L2:L3=L2/L4:L6=L5/L7:BOTTOM=L7 |
| Q95_G | OTHERS | BUS | 3 | 5 | 5 | 10 | 5 | 14 | 6 | 10 | 12 | 12 | 12 | 12 |  | 50 Ohms | TOP=L2:L3=L2/L4:L6=L5/L7:BOTTOM=L7 |
| Q95_G | OTHERS | BUS | 4 | 5 | 5 | 10 | 5 | 14 | 6 | 10 | 12 | 12 | 12 | 12 |  | 50 Ohms | TOP=L2:L3=L2/L4:L6=L5/L7:BOTTOM=L7 |
| Q95_G | OTHERS | BUS | 5 | 5 | 5 | 10 | 5 | 14 | 6 | 10 | 12 | 12 | 12 | 12 |  | 50 Ohms | TOP=L2:L3=L2/L4:L6=L5/L7:BOTTOM=L7 |
| Q95_G | OTHERS | BUS | 6 | 5 | 5 | 10 | 5 | 14 | 6 | 10 | 12 | 12 | 12 | 12 |  | 50 Ohms | TOP=L2:L3=L2/L4:L6=L5/L7:BOTTOM=L7 |
| Q95_G | OTHERS | BUS | 7 | 5 | 5 | 10 | 5 | 14 | 6 | 10 | 12 | 12 | 12 | 12 |  | 50 Ohms | TOP=L2:L3=L2/L4:L6=L5/L7:BOTTOM=L7 |
| Q95_G | OTHERS | BUS | 8 | 4.75 | 5 | 10 | 5 | 14 | 6 | 9.5 | 12 | 12 | 12 | 12 |  | 50 Ohms | TOP=L2:L3=L2/L4:L6=L5/L7:BOTTOM=L7 |
| RMII_BMC_CRS_DV | OTHERS | BUS | 1 | 4.75 | 5 | 10 | 5 | 14 | 6 | 9.5 | 12 | 12 | 12 | 12 |  | 50 Ohms | TOP=L2:L3=L2/L4:L6=L5/L7:BOTTOM=L7 |
| RMII_BMC_CRS_DV | OTHERS | BUS | 2 | 5 | 5 | 10 | 5 | 14 | 6 | 10 | 12 | 12 | 12 | 12 |  | 50 Ohms | TOP=L2:L3=L2/L4:L6=L5/L7:BOTTOM=L7 |
| RMII_BMC_CRS_DV | OTHERS | BUS | 3 | 5 | 5 | 10 | 5 | 14 | 6 | 10 | 12 | 12 | 12 | 12 |  | 50 Ohms | TOP=L2:L3=L2/L4:L6=L5/L7:BOTTOM=L7 |
| RMII_BMC_CRS_DV | OTHERS | BUS | 4 | 5 | 5 | 10 | 5 | 14 | 6 | 10 | 12 | 12 | 12 | 12 |  | 50 Ohms | TOP=L2:L3=L2/L4:L6=L5/L7:BOTTOM=L7 |
| RMII_BMC_CRS_DV | OTHERS | BUS | 5 | 5 | 5 | 10 | 5 | 14 | 6 | 10 | 12 | 12 | 12 | 12 |  | 50 Ohms | TOP=L2:L3=L2/L4:L6=L5/L7:BOTTOM=L7 |
| RMII_BMC_CRS_DV | OTHERS | BUS | 6 | 5 | 5 | 10 | 5 | 14 | 6 | 10 | 12 | 12 | 12 | 12 |  | 50 Ohms | TOP=L2:L3=L2/L4:L6=L5/L7:BOTTOM=L7 |
| RMII_BMC_CRS_DV | OTHERS | BUS | 7 | 5 | 5 | 10 | 5 | 14 | 6 | 10 | 12 | 12 | 12 | 12 |  | 50 Ohms | TOP=L2:L3=L2/L4:L6=L5/L7:BOTTOM=L7 |
| RMII_BMC_CRS_DV | OTHERS | BUS | 8 | 4.75 | 5 | 10 | 5 | 14 | 6 | 9.5 | 12 | 12 | 12 | 12 |  | 50 Ohms | TOP=L2:L3=L2/L4:L6=L5/L7:BOTTOM=L7 |
| RMII_BMC_RX_ER | OTHERS | BUS | 1 | 4.75 | 5 | 10 | 5 | 14 | 6 | 9.5 | 12 | 12 | 12 | 12 |  | 50 Ohms | TOP=L2:L3=L2/L4:L6=L5/L7:BOTTOM=L7 |
| RMII_BMC_RX_ER | OTHERS | BUS | 2 | 5 | 5 | 10 | 5 | 14 | 6 | 10 | 12 | 12 | 12 | 12 |  | 50 Ohms | TOP=L2:L3=L2/L4:L6=L5/L7:BOTTOM=L7 |
| RMII_BMC_RX_ER | OTHERS | BUS | 3 | 5 | 5 | 10 | 5 | 14 | 6 | 10 | 12 | 12 | 12 | 12 |  | 50 Ohms | TOP=L2:L3=L2/L4:L6=L5/L7:BOTTOM=L7 |
| RMII_BMC_RX_ER | OTHERS | BUS | 4 | 5 | 5 | 10 | 5 | 14 | 6 | 10 | 12 | 12 | 12 | 12 |  | 50 Ohms | TOP=L2:L3=L2/L4:L6=L5/L7:BOTTOM=L7 |
| RMII_BMC_RX_ER | OTHERS | BUS | 5 | 5 | 5 | 10 | 5 | 14 | 6 | 10 | 12 | 12 | 12 | 12 |  | 50 Ohms | TOP=L2:L3=L2/L4:L6=L5/L7:BOTTOM=L7 |
| RMII_BMC_RX_ER | OTHERS | BUS | 6 | 5 | 5 | 10 | 5 | 14 | 6 | 10 | 12 | 12 | 12 | 12 |  | 50 Ohms | TOP=L2:L3=L2/L4:L6=L5/L7:BOTTOM=L7 |
| RMII_BMC_RX_ER | OTHERS | BUS | 7 | 5 | 5 | 10 | 5 | 14 | 6 | 10 | 12 | 12 | 12 | 12 |  | 50 Ohms | TOP=L2:L3=L2/L4:L6=L5/L7:BOTTOM=L7 |
| RMII_BMC_RX_ER | OTHERS | BUS | 8 | 4.75 | 5 | 10 | 5 | 14 | 6 | 9.5 | 12 | 12 | 12 | 12 |  | 50 Ohms | TOP=L2:L3=L2/L4:L6=L5/L7:BOTTOM=L7 |
| RMII_BMC_TX_EN | OTHERS | BUS | 1 | 4.75 | 5 | 10 | 5 | 14 | 6 | 9.5 | 12 | 12 | 12 | 12 |  | 50 Ohms | TOP=L2:L3=L2/L4:L6=L5/L7:BOTTOM=L7 |
| RMII_BMC_TX_EN | OTHERS | BUS | 2 | 5 | 5 | 10 | 5 | 14 | 6 | 10 | 12 | 12 | 12 | 12 |  | 50 Ohms | TOP=L2:L3=L2/L4:L6=L5/L7:BOTTOM=L7 |
| RMII_BMC_TX_EN | OTHERS | BUS | 3 | 5 | 5 | 10 | 5 | 14 | 6 | 10 | 12 | 12 | 12 | 12 |  | 50 Ohms | TOP=L2:L3=L2/L4:L6=L5/L7:BOTTOM=L7 |
| RMII_BMC_TX_EN | OTHERS | BUS | 4 | 5 | 5 | 10 | 5 | 14 | 6 | 10 | 12 | 12 | 12 | 12 |  | 50 Ohms | TOP=L2:L3=L2/L4:L6=L5/L7:BOTTOM=L7 |
| RMII_BMC_TX_EN | OTHERS | BUS | 5 | 5 | 5 | 10 | 5 | 14 | 6 | 10 | 12 | 12 | 12 | 12 |  | 50 Ohms | TOP=L2:L3=L2/L4:L6=L5/L7:BOTTOM=L7 |
| RMII_BMC_TX_EN | OTHERS | BUS | 6 | 5 | 5 | 10 | 5 | 14 | 6 | 10 | 12 | 12 | 12 | 12 |  | 50 Ohms | TOP=L2:L3=L2/L4:L6=L5/L7:BOTTOM=L7 |
| RMII_BMC_TX_EN | OTHERS | BUS | 7 | 5 | 5 | 10 | 5 | 14 | 6 | 10 | 12 | 12 | 12 | 12 |  | 50 Ohms | TOP=L2:L3=L2/L4:L6=L5/L7:BOTTOM=L7 |
| RMII_BMC_TX_EN | OTHERS | BUS | 8 | 4.75 | 5 | 10 | 5 | 14 | 6 | 9.5 | 12 | 12 | 12 | 12 |  | 50 Ohms | TOP=L2:L3=L2/L4:L6=L5/L7:BOTTOM=L7 |
| RMII_CRS_DV | OTHERS | BUS | 1 | 4.75 | 5 | 10 | 5 | 14 | 6 | 9.5 | 12 | 12 | 12 | 12 |  | 50 Ohms | TOP=L2:L3=L2/L4:L6=L5/L7:BOTTOM=L7 |
| RMII_CRS_DV | OTHERS | BUS | 2 | 5 | 5 | 10 | 5 | 14 | 6 | 10 | 12 | 12 | 12 | 12 |  | 50 Ohms | TOP=L2:L3=L2/L4:L6=L5/L7:BOTTOM=L7 |
| RMII_CRS_DV | OTHERS | BUS | 3 | 5 | 5 | 10 | 5 | 14 | 6 | 10 | 12 | 12 | 12 | 12 |  | 50 Ohms | TOP=L2:L3=L2/L4:L6=L5/L7:BOTTOM=L7 |
| RMII_CRS_DV | OTHERS | BUS | 4 | 5 | 5 | 10 | 5 | 14 | 6 | 10 | 12 | 12 | 12 | 12 |  | 50 Ohms | TOP=L2:L3=L2/L4:L6=L5/L7:BOTTOM=L7 |
| RMII_CRS_DV | OTHERS | BUS | 5 | 5 | 5 | 10 | 5 | 14 | 6 | 10 | 12 | 12 | 12 | 12 |  | 50 Ohms | TOP=L2:L3=L2/L4:L6=L5/L7:BOTTOM=L7 |
| RMII_CRS_DV | OTHERS | BUS | 6 | 5 | 5 | 10 | 5 | 14 | 6 | 10 | 12 | 12 | 12 | 12 |  | 50 Ohms | TOP=L2:L3=L2/L4:L6=L5/L7:BOTTOM=L7 |
| RMII_CRS_DV | OTHERS | BUS | 7 | 5 | 5 | 10 | 5 | 14 | 6 | 10 | 12 | 12 | 12 | 12 |  | 50 Ohms | TOP=L2:L3=L2/L4:L6=L5/L7:BOTTOM=L7 |
| RMII_CRS_DV | OTHERS | BUS | 8 | 4.75 | 5 | 10 | 5 | 14 | 6 | 9.5 | 12 | 12 | 12 | 12 |  | 50 Ohms | TOP=L2:L3=L2/L4:L6=L5/L7:BOTTOM=L7 |
| RMII_REF_CLK | OTHERS | BUS | 1 | 4.75 | 5 | 10 | 5 | 14 | 6 | 9.5 | 12 | 12 | 12 | 12 |  | 50 Ohms | TOP=L2:L3=L2/L4:L6=L5/L7:BOTTOM=L7 |
| RMII_REF_CLK | OTHERS | BUS | 2 | 5 | 5 | 10 | 5 | 14 | 6 | 10 | 12 | 12 | 12 | 12 |  | 50 Ohms | TOP=L2:L3=L2/L4:L6=L5/L7:BOTTOM=L7 |
| RMII_REF_CLK | OTHERS | BUS | 3 | 5 | 5 | 10 | 5 | 14 | 6 | 10 | 12 | 12 | 12 | 12 |  | 50 Ohms | TOP=L2:L3=L2/L4:L6=L5/L7:BOTTOM=L7 |
| RMII_REF_CLK | OTHERS | BUS | 4 | 5 | 5 | 10 | 5 | 14 | 6 | 10 | 12 | 12 | 12 | 12 |  | 50 Ohms | TOP=L2:L3=L2/L4:L6=L5/L7:BOTTOM=L7 |
| RMII_REF_CLK | OTHERS | BUS | 5 | 5 | 5 | 10 | 5 | 14 | 6 | 10 | 12 | 12 | 12 | 12 |  | 50 Ohms | TOP=L2:L3=L2/L4:L6=L5/L7:BOTTOM=L7 |
| RMII_REF_CLK | OTHERS | BUS | 6 | 5 | 5 | 10 | 5 | 14 | 6 | 10 | 12 | 12 | 12 | 12 |  | 50 Ohms | TOP=L2:L3=L2/L4:L6=L5/L7:BOTTOM=L7 |
| RMII_REF_CLK | OTHERS | BUS | 7 | 5 | 5 | 10 | 5 | 14 | 6 | 10 | 12 | 12 | 12 | 12 |  | 50 Ohms | TOP=L2:L3=L2/L4:L6=L5/L7:BOTTOM=L7 |
| RMII_REF_CLK | OTHERS | BUS | 8 | 4.75 | 5 | 10 | 5 | 14 | 6 | 9.5 | 12 | 12 | 12 | 12 |  | 50 Ohms | TOP=L2:L3=L2/L4:L6=L5/L7:BOTTOM=L7 |
| RMII_RX_ER | OTHERS | BUS | 1 | 4.75 | 5 | 10 | 5 | 14 | 6 | 9.5 | 12 | 12 | 12 | 12 |  | 50 Ohms | TOP=L2:L3=L2/L4:L6=L5/L7:BOTTOM=L7 |
| RMII_RX_ER | OTHERS | BUS | 2 | 5 | 5 | 10 | 5 | 14 | 6 | 10 | 12 | 12 | 12 | 12 |  | 50 Ohms | TOP=L2:L3=L2/L4:L6=L5/L7:BOTTOM=L7 |
| RMII_RX_ER | OTHERS | BUS | 3 | 5 | 5 | 10 | 5 | 14 | 6 | 10 | 12 | 12 | 12 | 12 |  | 50 Ohms | TOP=L2:L3=L2/L4:L6=L5/L7:BOTTOM=L7 |
| RMII_RX_ER | OTHERS | BUS | 4 | 5 | 5 | 10 | 5 | 14 | 6 | 10 | 12 | 12 | 12 | 12 |  | 50 Ohms | TOP=L2:L3=L2/L4:L6=L5/L7:BOTTOM=L7 |
| RMII_RX_ER | OTHERS | BUS | 5 | 5 | 5 | 10 | 5 | 14 | 6 | 10 | 12 | 12 | 12 | 12 |  | 50 Ohms | TOP=L2:L3=L2/L4:L6=L5/L7:BOTTOM=L7 |
| RMII_RX_ER | OTHERS | BUS | 6 | 5 | 5 | 10 | 5 | 14 | 6 | 10 | 12 | 12 | 12 | 12 |  | 50 Ohms | TOP=L2:L3=L2/L4:L6=L5/L7:BOTTOM=L7 |
| RMII_RX_ER | OTHERS | BUS | 7 | 5 | 5 | 10 | 5 | 14 | 6 | 10 | 12 | 12 | 12 | 12 |  | 50 Ohms | TOP=L2:L3=L2/L4:L6=L5/L7:BOTTOM=L7 |
| RMII_RX_ER | OTHERS | BUS | 8 | 4.75 | 5 | 10 | 5 | 14 | 6 | 9.5 | 12 | 12 | 12 | 12 |  | 50 Ohms | TOP=L2:L3=L2/L4:L6=L5/L7:BOTTOM=L7 |
| RMII_TX_EN | OTHERS | BUS | 1 | 4.75 | 5 | 10 | 5 | 14 | 6 | 9.5 | 12 | 12 | 12 | 12 |  | 50 Ohms | TOP=L2:L3=L2/L4:L6=L5/L7:BOTTOM=L7 |
| RMII_TX_EN | OTHERS | BUS | 2 | 5 | 5 | 10 | 5 | 14 | 6 | 10 | 12 | 12 | 12 | 12 |  | 50 Ohms | TOP=L2:L3=L2/L4:L6=L5/L7:BOTTOM=L7 |
| RMII_TX_EN | OTHERS | BUS | 3 | 5 | 5 | 10 | 5 | 14 | 6 | 10 | 12 | 12 | 12 | 12 |  | 50 Ohms | TOP=L2:L3=L2/L4:L6=L5/L7:BOTTOM=L7 |
| RMII_TX_EN | OTHERS | BUS | 4 | 5 | 5 | 10 | 5 | 14 | 6 | 10 | 12 | 12 | 12 | 12 |  | 50 Ohms | TOP=L2:L3=L2/L4:L6=L5/L7:BOTTOM=L7 |
| RMII_TX_EN | OTHERS | BUS | 5 | 5 | 5 | 10 | 5 | 14 | 6 | 10 | 12 | 12 | 12 | 12 |  | 50 Ohms | TOP=L2:L3=L2/L4:L6=L5/L7:BOTTOM=L7 |
| RMII_TX_EN | OTHERS | BUS | 6 | 5 | 5 | 10 | 5 | 14 | 6 | 10 | 12 | 12 | 12 | 12 |  | 50 Ohms | TOP=L2:L3=L2/L4:L6=L5/L7:BOTTOM=L7 |
| RMII_TX_EN | OTHERS | BUS | 7 | 5 | 5 | 10 | 5 | 14 | 6 | 10 | 12 | 12 | 12 | 12 |  | 50 Ohms | TOP=L2:L3=L2/L4:L6=L5/L7:BOTTOM=L7 |
| RMII_TX_EN | OTHERS | BUS | 8 | 4.75 | 5 | 10 | 5 | 14 | 6 | 9.5 | 12 | 12 | 12 | 12 |  | 50 Ohms | TOP=L2:L3=L2/L4:L6=L5/L7:BOTTOM=L7 |
| RMII0_BMC_C_CRS_DV | OTHERS | BUS | 1 | 4.75 | 5 | 10 | 5 | 14 | 6 | 9.5 | 12 | 12 | 12 | 12 |  | 50 Ohms | TOP=L2:L3=L2/L4:L6=L5/L7:BOTTOM=L7 |
| RMII0_BMC_C_CRS_DV | OTHERS | BUS | 2 | 5 | 5 | 10 | 5 | 14 | 6 | 10 | 12 | 12 | 12 | 12 |  | 50 Ohms | TOP=L2:L3=L2/L4:L6=L5/L7:BOTTOM=L7 |
| RMII0_BMC_C_CRS_DV | OTHERS | BUS | 3 | 5 | 5 | 10 | 5 | 14 | 6 | 10 | 12 | 12 | 12 | 12 |  | 50 Ohms | TOP=L2:L3=L2/L4:L6=L5/L7:BOTTOM=L7 |
| RMII0_BMC_C_CRS_DV | OTHERS | BUS | 4 | 5 | 5 | 10 | 5 | 14 | 6 | 10 | 12 | 12 | 12 | 12 |  | 50 Ohms | TOP=L2:L3=L2/L4:L6=L5/L7:BOTTOM=L7 |
| RMII0_BMC_C_CRS_DV | OTHERS | BUS | 5 | 5 | 5 | 10 | 5 | 14 | 6 | 10 | 12 | 12 | 12 | 12 |  | 50 Ohms | TOP=L2:L3=L2/L4:L6=L5/L7:BOTTOM=L7 |
| RMII0_BMC_C_CRS_DV | OTHERS | BUS | 6 | 5 | 5 | 10 | 5 | 14 | 6 | 10 | 12 | 12 | 12 | 12 |  | 50 Ohms | TOP=L2:L3=L2/L4:L6=L5/L7:BOTTOM=L7 |
| RMII0_BMC_C_CRS_DV | OTHERS | BUS | 7 | 5 | 5 | 10 | 5 | 14 | 6 | 10 | 12 | 12 | 12 | 12 |  | 50 Ohms | TOP=L2:L3=L2/L4:L6=L5/L7:BOTTOM=L7 |
| RMII0_BMC_C_CRS_DV | OTHERS | BUS | 8 | 4.75 | 5 | 10 | 5 | 14 | 6 | 9.5 | 12 | 12 | 12 | 12 |  | 50 Ohms | TOP=L2:L3=L2/L4:L6=L5/L7:BOTTOM=L7 |
| RMII0_BMC_C_TX_EN | OTHERS | BUS | 1 | 4.75 | 5 | 10 | 5 | 14 | 6 | 9.5 | 12 | 12 | 12 | 12 |  | 50 Ohms | TOP=L2:L3=L2/L4:L6=L5/L7:BOTTOM=L7 |
| RMII0_BMC_C_TX_EN | OTHERS | BUS | 2 | 5 | 5 | 10 | 5 | 14 | 6 | 10 | 12 | 12 | 12 | 12 |  | 50 Ohms | TOP=L2:L3=L2/L4:L6=L5/L7:BOTTOM=L7 |
| RMII0_BMC_C_TX_EN | OTHERS | BUS | 3 | 5 | 5 | 10 | 5 | 14 | 6 | 10 | 12 | 12 | 12 | 12 |  | 50 Ohms | TOP=L2:L3=L2/L4:L6=L5/L7:BOTTOM=L7 |
| RMII0_BMC_C_TX_EN | OTHERS | BUS | 4 | 5 | 5 | 10 | 5 | 14 | 6 | 10 | 12 | 12 | 12 | 12 |  | 50 Ohms | TOP=L2:L3=L2/L4:L6=L5/L7:BOTTOM=L7 |
| RMII0_BMC_C_TX_EN | OTHERS | BUS | 5 | 5 | 5 | 10 | 5 | 14 | 6 | 10 | 12 | 12 | 12 | 12 |  | 50 Ohms | TOP=L2:L3=L2/L4:L6=L5/L7:BOTTOM=L7 |
| RMII0_BMC_C_TX_EN | OTHERS | BUS | 6 | 5 | 5 | 10 | 5 | 14 | 6 | 10 | 12 | 12 | 12 | 12 |  | 50 Ohms | TOP=L2:L3=L2/L4:L6=L5/L7:BOTTOM=L7 |
| RMII0_BMC_C_TX_EN | OTHERS | BUS | 7 | 5 | 5 | 10 | 5 | 14 | 6 | 10 | 12 | 12 | 12 | 12 |  | 50 Ohms | TOP=L2:L3=L2/L4:L6=L5/L7:BOTTOM=L7 |
| RMII0_BMC_C_TX_EN | OTHERS | BUS | 8 | 4.75 | 5 | 10 | 5 | 14 | 6 | 9.5 | 12 | 12 | 12 | 12 |  | 50 Ohms | TOP=L2:L3=L2/L4:L6=L5/L7:BOTTOM=L7 |
| RMII0_PHY_BMC_RXCTL0 | OTHERS | BUS | 1 | 4.75 | 5 | 10 | 5 | 14 | 6 | 9.5 | 12 | 12 | 12 | 12 |  | 50 Ohms | TOP=L2:L3=L2/L4:L6=L5/L7:BOTTOM=L7 |
| RMII0_PHY_BMC_RXCTL0 | OTHERS | BUS | 2 | 5 | 5 | 10 | 5 | 14 | 6 | 10 | 12 | 12 | 12 | 12 |  | 50 Ohms | TOP=L2:L3=L2/L4:L6=L5/L7:BOTTOM=L7 |
| RMII0_PHY_BMC_RXCTL0 | OTHERS | BUS | 3 | 5 | 5 | 10 | 5 | 14 | 6 | 10 | 12 | 12 | 12 | 12 |  | 50 Ohms | TOP=L2:L3=L2/L4:L6=L5/L7:BOTTOM=L7 |
| RMII0_PHY_BMC_RXCTL0 | OTHERS | BUS | 4 | 5 | 5 | 10 | 5 | 14 | 6 | 10 | 12 | 12 | 12 | 12 |  | 50 Ohms | TOP=L2:L3=L2/L4:L6=L5/L7:BOTTOM=L7 |
| RMII0_PHY_BMC_RXCTL0 | OTHERS | BUS | 5 | 5 | 5 | 10 | 5 | 14 | 6 | 10 | 12 | 12 | 12 | 12 |  | 50 Ohms | TOP=L2:L3=L2/L4:L6=L5/L7:BOTTOM=L7 |
| RMII0_PHY_BMC_RXCTL0 | OTHERS | BUS | 6 | 5 | 5 | 10 | 5 | 14 | 6 | 10 | 12 | 12 | 12 | 12 |  | 50 Ohms | TOP=L2:L3=L2/L4:L6=L5/L7:BOTTOM=L7 |
| RMII0_PHY_BMC_RXCTL0 | OTHERS | BUS | 7 | 5 | 5 | 10 | 5 | 14 | 6 | 10 | 12 | 12 | 12 | 12 |  | 50 Ohms | TOP=L2:L3=L2/L4:L6=L5/L7:BOTTOM=L7 |
| RMII0_PHY_BMC_RXCTL0 | OTHERS | BUS | 8 | 4.75 | 5 | 10 | 5 | 14 | 6 | 9.5 | 12 | 12 | 12 | 12 |  | 50 Ohms | TOP=L2:L3=L2/L4:L6=L5/L7:BOTTOM=L7 |
| ROMA0 | OTHERS | BUS | 1 | 4.75 | 5 | 10 | 5 | 14 | 6 | 9.5 | 12 | 12 | 12 | 12 |  | 50 Ohms | TOP=L2:L3=L2/L4:L6=L5/L7:BOTTOM=L7 |
| ROMA0 | OTHERS | BUS | 2 | 5 | 5 | 10 | 5 | 14 | 6 | 10 | 12 | 12 | 12 | 12 |  | 50 Ohms | TOP=L2:L3=L2/L4:L6=L5/L7:BOTTOM=L7 |
| ROMA0 | OTHERS | BUS | 3 | 5 | 5 | 10 | 5 | 14 | 6 | 10 | 12 | 12 | 12 | 12 |  | 50 Ohms | TOP=L2:L3=L2/L4:L6=L5/L7:BOTTOM=L7 |
| ROMA0 | OTHERS | BUS | 4 | 5 | 5 | 10 | 5 | 14 | 6 | 10 | 12 | 12 | 12 | 12 |  | 50 Ohms | TOP=L2:L3=L2/L4:L6=L5/L7:BOTTOM=L7 |
| ROMA0 | OTHERS | BUS | 5 | 5 | 5 | 10 | 5 | 14 | 6 | 10 | 12 | 12 | 12 | 12 |  | 50 Ohms | TOP=L2:L3=L2/L4:L6=L5/L7:BOTTOM=L7 |
| ROMA0 | OTHERS | BUS | 6 | 5 | 5 | 10 | 5 | 14 | 6 | 10 | 12 | 12 | 12 | 12 |  | 50 Ohms | TOP=L2:L3=L2/L4:L6=L5/L7:BOTTOM=L7 |
| ROMA0 | OTHERS | BUS | 7 | 5 | 5 | 10 | 5 | 14 | 6 | 10 | 12 | 12 | 12 | 12 |  | 50 Ohms | TOP=L2:L3=L2/L4:L6=L5/L7:BOTTOM=L7 |
| ROMA0 | OTHERS | BUS | 8 | 4.75 | 5 | 10 | 5 | 14 | 6 | 9.5 | 12 | 12 | 12 | 12 |  | 50 Ohms | TOP=L2:L3=L2/L4:L6=L5/L7:BOTTOM=L7 |
| ROMA1 | OTHERS | BUS | 1 | 4.75 | 5 | 10 | 5 | 14 | 6 | 9.5 | 12 | 12 | 12 | 12 |  | 50 Ohms | TOP=L2:L3=L2/L4:L6=L5/L7:BOTTOM=L7 |
| ROMA1 | OTHERS | BUS | 2 | 5 | 5 | 10 | 5 | 14 | 6 | 10 | 12 | 12 | 12 | 12 |  | 50 Ohms | TOP=L2:L3=L2/L4:L6=L5/L7:BOTTOM=L7 |
| ROMA1 | OTHERS | BUS | 3 | 5 | 5 | 10 | 5 | 14 | 6 | 10 | 12 | 12 | 12 | 12 |  | 50 Ohms | TOP=L2:L3=L2/L4:L6=L5/L7:BOTTOM=L7 |
| ROMA1 | OTHERS | BUS | 4 | 5 | 5 | 10 | 5 | 14 | 6 | 10 | 12 | 12 | 12 | 12 |  | 50 Ohms | TOP=L2:L3=L2/L4:L6=L5/L7:BOTTOM=L7 |
| ROMA1 | OTHERS | BUS | 5 | 5 | 5 | 10 | 5 | 14 | 6 | 10 | 12 | 12 | 12 | 12 |  | 50 Ohms | TOP=L2:L3=L2/L4:L6=L5/L7:BOTTOM=L7 |
| ROMA1 | OTHERS | BUS | 6 | 5 | 5 | 10 | 5 | 14 | 6 | 10 | 12 | 12 | 12 | 12 |  | 50 Ohms | TOP=L2:L3=L2/L4:L6=L5/L7:BOTTOM=L7 |
| ROMA1 | OTHERS | BUS | 7 | 5 | 5 | 10 | 5 | 14 | 6 | 10 | 12 | 12 | 12 | 12 |  | 50 Ohms | TOP=L2:L3=L2/L4:L6=L5/L7:BOTTOM=L7 |
| ROMA1 | OTHERS | BUS | 8 | 4.75 | 5 | 10 | 5 | 14 | 6 | 9.5 | 12 | 12 | 12 | 12 |  | 50 Ohms | TOP=L2:L3=L2/L4:L6=L5/L7:BOTTOM=L7 |
| ROMA10 | OTHERS | BUS | 1 | 4.75 | 5 | 10 | 5 | 14 | 6 | 9.5 | 12 | 12 | 12 | 12 |  | 50 Ohms | TOP=L2:L3=L2/L4:L6=L5/L7:BOTTOM=L7 |
| ROMA10 | OTHERS | BUS | 2 | 5 | 5 | 10 | 5 | 14 | 6 | 10 | 12 | 12 | 12 | 12 |  | 50 Ohms | TOP=L2:L3=L2/L4:L6=L5/L7:BOTTOM=L7 |
| ROMA10 | OTHERS | BUS | 3 | 5 | 5 | 10 | 5 | 14 | 6 | 10 | 12 | 12 | 12 | 12 |  | 50 Ohms | TOP=L2:L3=L2/L4:L6=L5/L7:BOTTOM=L7 |
| ROMA10 | OTHERS | BUS | 4 | 5 | 5 | 10 | 5 | 14 | 6 | 10 | 12 | 12 | 12 | 12 |  | 50 Ohms | TOP=L2:L3=L2/L4:L6=L5/L7:BOTTOM=L7 |
| ROMA10 | OTHERS | BUS | 5 | 5 | 5 | 10 | 5 | 14 | 6 | 10 | 12 | 12 | 12 | 12 |  | 50 Ohms | TOP=L2:L3=L2/L4:L6=L5/L7:BOTTOM=L7 |
| ROMA10 | OTHERS | BUS | 6 | 5 | 5 | 10 | 5 | 14 | 6 | 10 | 12 | 12 | 12 | 12 |  | 50 Ohms | TOP=L2:L3=L2/L4:L6=L5/L7:BOTTOM=L7 |
| ROMA10 | OTHERS | BUS | 7 | 5 | 5 | 10 | 5 | 14 | 6 | 10 | 12 | 12 | 12 | 12 |  | 50 Ohms | TOP=L2:L3=L2/L4:L6=L5/L7:BOTTOM=L7 |
| ROMA10 | OTHERS | BUS | 8 | 4.75 | 5 | 10 | 5 | 14 | 6 | 9.5 | 12 | 12 | 12 | 12 |  | 50 Ohms | TOP=L2:L3=L2/L4:L6=L5/L7:BOTTOM=L7 |
| ROMA11 | OTHERS | BUS | 1 | 4.75 | 5 | 10 | 5 | 14 | 6 | 9.5 | 12 | 12 | 12 | 12 |  | 50 Ohms | TOP=L2:L3=L2/L4:L6=L5/L7:BOTTOM=L7 |
| ROMA11 | OTHERS | BUS | 2 | 5 | 5 | 10 | 5 | 14 | 6 | 10 | 12 | 12 | 12 | 12 |  | 50 Ohms | TOP=L2:L3=L2/L4:L6=L5/L7:BOTTOM=L7 |
| ROMA11 | OTHERS | BUS | 3 | 5 | 5 | 10 | 5 | 14 | 6 | 10 | 12 | 12 | 12 | 12 |  | 50 Ohms | TOP=L2:L3=L2/L4:L6=L5/L7:BOTTOM=L7 |
| ROMA11 | OTHERS | BUS | 4 | 5 | 5 | 10 | 5 | 14 | 6 | 10 | 12 | 12 | 12 | 12 |  | 50 Ohms | TOP=L2:L3=L2/L4:L6=L5/L7:BOTTOM=L7 |
| ROMA11 | OTHERS | BUS | 5 | 5 | 5 | 10 | 5 | 14 | 6 | 10 | 12 | 12 | 12 | 12 |  | 50 Ohms | TOP=L2:L3=L2/L4:L6=L5/L7:BOTTOM=L7 |
| ROMA11 | OTHERS | BUS | 6 | 5 | 5 | 10 | 5 | 14 | 6 | 10 | 12 | 12 | 12 | 12 |  | 50 Ohms | TOP=L2:L3=L2/L4:L6=L5/L7:BOTTOM=L7 |
| ROMA11 | OTHERS | BUS | 7 | 5 | 5 | 10 | 5 | 14 | 6 | 10 | 12 | 12 | 12 | 12 |  | 50 Ohms | TOP=L2:L3=L2/L4:L6=L5/L7:BOTTOM=L7 |
| ROMA11 | OTHERS | BUS | 8 | 4.75 | 5 | 10 | 5 | 14 | 6 | 9.5 | 12 | 12 | 12 | 12 |  | 50 Ohms | TOP=L2:L3=L2/L4:L6=L5/L7:BOTTOM=L7 |
| ROMA12 | OTHERS | BUS | 1 | 4.75 | 5 | 10 | 5 | 14 | 6 | 9.5 | 12 | 12 | 12 | 12 |  | 50 Ohms | TOP=L2:L3=L2/L4:L6=L5/L7:BOTTOM=L7 |
| ROMA12 | OTHERS | BUS | 2 | 5 | 5 | 10 | 5 | 14 | 6 | 10 | 12 | 12 | 12 | 12 |  | 50 Ohms | TOP=L2:L3=L2/L4:L6=L5/L7:BOTTOM=L7 |
| ROMA12 | OTHERS | BUS | 3 | 5 | 5 | 10 | 5 | 14 | 6 | 10 | 12 | 12 | 12 | 12 |  | 50 Ohms | TOP=L2:L3=L2/L4:L6=L5/L7:BOTTOM=L7 |
| ROMA12 | OTHERS | BUS | 4 | 5 | 5 | 10 | 5 | 14 | 6 | 10 | 12 | 12 | 12 | 12 |  | 50 Ohms | TOP=L2:L3=L2/L4:L6=L5/L7:BOTTOM=L7 |
| ROMA12 | OTHERS | BUS | 5 | 5 | 5 | 10 | 5 | 14 | 6 | 10 | 12 | 12 | 12 | 12 |  | 50 Ohms | TOP=L2:L3=L2/L4:L6=L5/L7:BOTTOM=L7 |
| ROMA12 | OTHERS | BUS | 6 | 5 | 5 | 10 | 5 | 14 | 6 | 10 | 12 | 12 | 12 | 12 |  | 50 Ohms | TOP=L2:L3=L2/L4:L6=L5/L7:BOTTOM=L7 |
| ROMA12 | OTHERS | BUS | 7 | 5 | 5 | 10 | 5 | 14 | 6 | 10 | 12 | 12 | 12 | 12 |  | 50 Ohms | TOP=L2:L3=L2/L4:L6=L5/L7:BOTTOM=L7 |
| ROMA12 | OTHERS | BUS | 8 | 4.75 | 5 | 10 | 5 | 14 | 6 | 9.5 | 12 | 12 | 12 | 12 |  | 50 Ohms | TOP=L2:L3=L2/L4:L6=L5/L7:BOTTOM=L7 |
| ROMA13 | OTHERS | BUS | 1 | 4.75 | 5 | 10 | 5 | 14 | 6 | 9.5 | 12 | 12 | 12 | 12 |  | 50 Ohms | TOP=L2:L3=L2/L4:L6=L5/L7:BOTTOM=L7 |
| ROMA13 | OTHERS | BUS | 2 | 5 | 5 | 10 | 5 | 14 | 6 | 10 | 12 | 12 | 12 | 12 |  | 50 Ohms | TOP=L2:L3=L2/L4:L6=L5/L7:BOTTOM=L7 |
| ROMA13 | OTHERS | BUS | 3 | 5 | 5 | 10 | 5 | 14 | 6 | 10 | 12 | 12 | 12 | 12 |  | 50 Ohms | TOP=L2:L3=L2/L4:L6=L5/L7:BOTTOM=L7 |
| ROMA13 | OTHERS | BUS | 4 | 5 | 5 | 10 | 5 | 14 | 6 | 10 | 12 | 12 | 12 | 12 |  | 50 Ohms | TOP=L2:L3=L2/L4:L6=L5/L7:BOTTOM=L7 |
| ROMA13 | OTHERS | BUS | 5 | 5 | 5 | 10 | 5 | 14 | 6 | 10 | 12 | 12 | 12 | 12 |  | 50 Ohms | TOP=L2:L3=L2/L4:L6=L5/L7:BOTTOM=L7 |
| ROMA13 | OTHERS | BUS | 6 | 5 | 5 | 10 | 5 | 14 | 6 | 10 | 12 | 12 | 12 | 12 |  | 50 Ohms | TOP=L2:L3=L2/L4:L6=L5/L7:BOTTOM=L7 |
| ROMA13 | OTHERS | BUS | 7 | 5 | 5 | 10 | 5 | 14 | 6 | 10 | 12 | 12 | 12 | 12 |  | 50 Ohms | TOP=L2:L3=L2/L4:L6=L5/L7:BOTTOM=L7 |
| ROMA13 | OTHERS | BUS | 8 | 4.75 | 5 | 10 | 5 | 14 | 6 | 9.5 | 12 | 12 | 12 | 12 |  | 50 Ohms | TOP=L2:L3=L2/L4:L6=L5/L7:BOTTOM=L7 |
| ROMA14 | OTHERS | BUS | 1 | 4.75 | 5 | 10 | 5 | 14 | 6 | 9.5 | 12 | 12 | 12 | 12 |  | 50 Ohms | TOP=L2:L3=L2/L4:L6=L5/L7:BOTTOM=L7 |
| ROMA14 | OTHERS | BUS | 2 | 5 | 5 | 10 | 5 | 14 | 6 | 10 | 12 | 12 | 12 | 12 |  | 50 Ohms | TOP=L2:L3=L2/L4:L6=L5/L7:BOTTOM=L7 |
| ROMA14 | OTHERS | BUS | 3 | 5 | 5 | 10 | 5 | 14 | 6 | 10 | 12 | 12 | 12 | 12 |  | 50 Ohms | TOP=L2:L3=L2/L4:L6=L5/L7:BOTTOM=L7 |
| ROMA14 | OTHERS | BUS | 4 | 5 | 5 | 10 | 5 | 14 | 6 | 10 | 12 | 12 | 12 | 12 |  | 50 Ohms | TOP=L2:L3=L2/L4:L6=L5/L7:BOTTOM=L7 |
| ROMA14 | OTHERS | BUS | 5 | 5 | 5 | 10 | 5 | 14 | 6 | 10 | 12 | 12 | 12 | 12 |  | 50 Ohms | TOP=L2:L3=L2/L4:L6=L5/L7:BOTTOM=L7 |
| ROMA14 | OTHERS | BUS | 6 | 5 | 5 | 10 | 5 | 14 | 6 | 10 | 12 | 12 | 12 | 12 |  | 50 Ohms | TOP=L2:L3=L2/L4:L6=L5/L7:BOTTOM=L7 |
| ROMA14 | OTHERS | BUS | 7 | 5 | 5 | 10 | 5 | 14 | 6 | 10 | 12 | 12 | 12 | 12 |  | 50 Ohms | TOP=L2:L3=L2/L4:L6=L5/L7:BOTTOM=L7 |
| ROMA14 | OTHERS | BUS | 8 | 4.75 | 5 | 10 | 5 | 14 | 6 | 9.5 | 12 | 12 | 12 | 12 |  | 50 Ohms | TOP=L2:L3=L2/L4:L6=L5/L7:BOTTOM=L7 |
| ROMA15 | OTHERS | BUS | 1 | 4.75 | 5 | 10 | 5 | 14 | 6 | 9.5 | 12 | 12 | 12 | 12 |  | 50 Ohms | TOP=L2:L3=L2/L4:L6=L5/L7:BOTTOM=L7 |
| ROMA15 | OTHERS | BUS | 2 | 5 | 5 | 10 | 5 | 14 | 6 | 10 | 12 | 12 | 12 | 12 |  | 50 Ohms | TOP=L2:L3=L2/L4:L6=L5/L7:BOTTOM=L7 |
| ROMA15 | OTHERS | BUS | 3 | 5 | 5 | 10 | 5 | 14 | 6 | 10 | 12 | 12 | 12 | 12 |  | 50 Ohms | TOP=L2:L3=L2/L4:L6=L5/L7:BOTTOM=L7 |
| ROMA15 | OTHERS | BUS | 4 | 5 | 5 | 10 | 5 | 14 | 6 | 10 | 12 | 12 | 12 | 12 |  | 50 Ohms | TOP=L2:L3=L2/L4:L6=L5/L7:BOTTOM=L7 |
| ROMA15 | OTHERS | BUS | 5 | 5 | 5 | 10 | 5 | 14 | 6 | 10 | 12 | 12 | 12 | 12 |  | 50 Ohms | TOP=L2:L3=L2/L4:L6=L5/L7:BOTTOM=L7 |
| ROMA15 | OTHERS | BUS | 6 | 5 | 5 | 10 | 5 | 14 | 6 | 10 | 12 | 12 | 12 | 12 |  | 50 Ohms | TOP=L2:L3=L2/L4:L6=L5/L7:BOTTOM=L7 |
| ROMA15 | OTHERS | BUS | 7 | 5 | 5 | 10 | 5 | 14 | 6 | 10 | 12 | 12 | 12 | 12 |  | 50 Ohms | TOP=L2:L3=L2/L4:L6=L5/L7:BOTTOM=L7 |
| ROMA15 | OTHERS | BUS | 8 | 4.75 | 5 | 10 | 5 | 14 | 6 | 9.5 | 12 | 12 | 12 | 12 |  | 50 Ohms | TOP=L2:L3=L2/L4:L6=L5/L7:BOTTOM=L7 |
| ROMA16 | OTHERS | BUS | 1 | 4.75 | 5 | 10 | 5 | 14 | 6 | 9.5 | 12 | 12 | 12 | 12 |  | 50 Ohms | TOP=L2:L3=L2/L4:L6=L5/L7:BOTTOM=L7 |
| ROMA16 | OTHERS | BUS | 2 | 5 | 5 | 10 | 5 | 14 | 6 | 10 | 12 | 12 | 12 | 12 |  | 50 Ohms | TOP=L2:L3=L2/L4:L6=L5/L7:BOTTOM=L7 |
| ROMA16 | OTHERS | BUS | 3 | 5 | 5 | 10 | 5 | 14 | 6 | 10 | 12 | 12 | 12 | 12 |  | 50 Ohms | TOP=L2:L3=L2/L4:L6=L5/L7:BOTTOM=L7 |
| ROMA16 | OTHERS | BUS | 4 | 5 | 5 | 10 | 5 | 14 | 6 | 10 | 12 | 12 | 12 | 12 |  | 50 Ohms | TOP=L2:L3=L2/L4:L6=L5/L7:BOTTOM=L7 |
| ROMA16 | OTHERS | BUS | 5 | 5 | 5 | 10 | 5 | 14 | 6 | 10 | 12 | 12 | 12 | 12 |  | 50 Ohms | TOP=L2:L3=L2/L4:L6=L5/L7:BOTTOM=L7 |
| ROMA16 | OTHERS | BUS | 6 | 5 | 5 | 10 | 5 | 14 | 6 | 10 | 12 | 12 | 12 | 12 |  | 50 Ohms | TOP=L2:L3=L2/L4:L6=L5/L7:BOTTOM=L7 |
| ROMA16 | OTHERS | BUS | 7 | 5 | 5 | 10 | 5 | 14 | 6 | 10 | 12 | 12 | 12 | 12 |  | 50 Ohms | TOP=L2:L3=L2/L4:L6=L5/L7:BOTTOM=L7 |
| ROMA16 | OTHERS | BUS | 8 | 4.75 | 5 | 10 | 5 | 14 | 6 | 9.5 | 12 | 12 | 12 | 12 |  | 50 Ohms | TOP=L2:L3=L2/L4:L6=L5/L7:BOTTOM=L7 |
| ROMA17 | OTHERS | BUS | 1 | 4.75 | 5 | 10 | 5 | 14 | 6 | 9.5 | 12 | 12 | 12 | 12 |  | 50 Ohms | TOP=L2:L3=L2/L4:L6=L5/L7:BOTTOM=L7 |
| ROMA17 | OTHERS | BUS | 2 | 5 | 5 | 10 | 5 | 14 | 6 | 10 | 12 | 12 | 12 | 12 |  | 50 Ohms | TOP=L2:L3=L2/L4:L6=L5/L7:BOTTOM=L7 |
| ROMA17 | OTHERS | BUS | 3 | 5 | 5 | 10 | 5 | 14 | 6 | 10 | 12 | 12 | 12 | 12 |  | 50 Ohms | TOP=L2:L3=L2/L4:L6=L5/L7:BOTTOM=L7 |
| ROMA17 | OTHERS | BUS | 4 | 5 | 5 | 10 | 5 | 14 | 6 | 10 | 12 | 12 | 12 | 12 |  | 50 Ohms | TOP=L2:L3=L2/L4:L6=L5/L7:BOTTOM=L7 |
| ROMA17 | OTHERS | BUS | 5 | 5 | 5 | 10 | 5 | 14 | 6 | 10 | 12 | 12 | 12 | 12 |  | 50 Ohms | TOP=L2:L3=L2/L4:L6=L5/L7:BOTTOM=L7 |
| ROMA17 | OTHERS | BUS | 6 | 5 | 5 | 10 | 5 | 14 | 6 | 10 | 12 | 12 | 12 | 12 |  | 50 Ohms | TOP=L2:L3=L2/L4:L6=L5/L7:BOTTOM=L7 |
| ROMA17 | OTHERS | BUS | 7 | 5 | 5 | 10 | 5 | 14 | 6 | 10 | 12 | 12 | 12 | 12 |  | 50 Ohms | TOP=L2:L3=L2/L4:L6=L5/L7:BOTTOM=L7 |
| ROMA17 | OTHERS | BUS | 8 | 4.75 | 5 | 10 | 5 | 14 | 6 | 9.5 | 12 | 12 | 12 | 12 |  | 50 Ohms | TOP=L2:L3=L2/L4:L6=L5/L7:BOTTOM=L7 |
| ROMA18 | OTHERS | BUS | 1 | 4.75 | 5 | 10 | 5 | 14 | 6 | 9.5 | 12 | 12 | 12 | 12 |  | 50 Ohms | TOP=L2:L3=L2/L4:L6=L5/L7:BOTTOM=L7 |
| ROMA18 | OTHERS | BUS | 2 | 5 | 5 | 10 | 5 | 14 | 6 | 10 | 12 | 12 | 12 | 12 |  | 50 Ohms | TOP=L2:L3=L2/L4:L6=L5/L7:BOTTOM=L7 |
| ROMA18 | OTHERS | BUS | 3 | 5 | 5 | 10 | 5 | 14 | 6 | 10 | 12 | 12 | 12 | 12 |  | 50 Ohms | TOP=L2:L3=L2/L4:L6=L5/L7:BOTTOM=L7 |
| ROMA18 | OTHERS | BUS | 4 | 5 | 5 | 10 | 5 | 14 | 6 | 10 | 12 | 12 | 12 | 12 |  | 50 Ohms | TOP=L2:L3=L2/L4:L6=L5/L7:BOTTOM=L7 |
| ROMA18 | OTHERS | BUS | 5 | 5 | 5 | 10 | 5 | 14 | 6 | 10 | 12 | 12 | 12 | 12 |  | 50 Ohms | TOP=L2:L3=L2/L4:L6=L5/L7:BOTTOM=L7 |
| ROMA18 | OTHERS | BUS | 6 | 5 | 5 | 10 | 5 | 14 | 6 | 10 | 12 | 12 | 12 | 12 |  | 50 Ohms | TOP=L2:L3=L2/L4:L6=L5/L7:BOTTOM=L7 |
| ROMA18 | OTHERS | BUS | 7 | 5 | 5 | 10 | 5 | 14 | 6 | 10 | 12 | 12 | 12 | 12 |  | 50 Ohms | TOP=L2:L3=L2/L4:L6=L5/L7:BOTTOM=L7 |
| ROMA18 | OTHERS | BUS | 8 | 4.75 | 5 | 10 | 5 | 14 | 6 | 9.5 | 12 | 12 | 12 | 12 |  | 50 Ohms | TOP=L2:L3=L2/L4:L6=L5/L7:BOTTOM=L7 |
| ROMA19 | OTHERS | BUS | 1 | 4.75 | 5 | 10 | 5 | 14 | 6 | 9.5 | 12 | 12 | 12 | 12 |  | 50 Ohms | TOP=L2:L3=L2/L4:L6=L5/L7:BOTTOM=L7 |
| ROMA19 | OTHERS | BUS | 2 | 5 | 5 | 10 | 5 | 14 | 6 | 10 | 12 | 12 | 12 | 12 |  | 50 Ohms | TOP=L2:L3=L2/L4:L6=L5/L7:BOTTOM=L7 |
| ROMA19 | OTHERS | BUS | 3 | 5 | 5 | 10 | 5 | 14 | 6 | 10 | 12 | 12 | 12 | 12 |  | 50 Ohms | TOP=L2:L3=L2/L4:L6=L5/L7:BOTTOM=L7 |
| ROMA19 | OTHERS | BUS | 4 | 5 | 5 | 10 | 5 | 14 | 6 | 10 | 12 | 12 | 12 | 12 |  | 50 Ohms | TOP=L2:L3=L2/L4:L6=L5/L7:BOTTOM=L7 |
| ROMA19 | OTHERS | BUS | 5 | 5 | 5 | 10 | 5 | 14 | 6 | 10 | 12 | 12 | 12 | 12 |  | 50 Ohms | TOP=L2:L3=L2/L4:L6=L5/L7:BOTTOM=L7 |
| ROMA19 | OTHERS | BUS | 6 | 5 | 5 | 10 | 5 | 14 | 6 | 10 | 12 | 12 | 12 | 12 |  | 50 Ohms | TOP=L2:L3=L2/L4:L6=L5/L7:BOTTOM=L7 |
| ROMA19 | OTHERS | BUS | 7 | 5 | 5 | 10 | 5 | 14 | 6 | 10 | 12 | 12 | 12 | 12 |  | 50 Ohms | TOP=L2:L3=L2/L4:L6=L5/L7:BOTTOM=L7 |
| ROMA19 | OTHERS | BUS | 8 | 4.75 | 5 | 10 | 5 | 14 | 6 | 9.5 | 12 | 12 | 12 | 12 |  | 50 Ohms | TOP=L2:L3=L2/L4:L6=L5/L7:BOTTOM=L7 |
| ROMA2 | OTHERS | BUS | 1 | 4.75 | 5 | 10 | 5 | 14 | 6 | 9.5 | 12 | 12 | 12 | 12 |  | 50 Ohms | TOP=L2:L3=L2/L4:L6=L5/L7:BOTTOM=L7 |
| ROMA2 | OTHERS | BUS | 2 | 5 | 5 | 10 | 5 | 14 | 6 | 10 | 12 | 12 | 12 | 12 |  | 50 Ohms | TOP=L2:L3=L2/L4:L6=L5/L7:BOTTOM=L7 |
| ROMA2 | OTHERS | BUS | 3 | 5 | 5 | 10 | 5 | 14 | 6 | 10 | 12 | 12 | 12 | 12 |  | 50 Ohms | TOP=L2:L3=L2/L4:L6=L5/L7:BOTTOM=L7 |
| ROMA2 | OTHERS | BUS | 4 | 5 | 5 | 10 | 5 | 14 | 6 | 10 | 12 | 12 | 12 | 12 |  | 50 Ohms | TOP=L2:L3=L2/L4:L6=L5/L7:BOTTOM=L7 |
| ROMA2 | OTHERS | BUS | 5 | 5 | 5 | 10 | 5 | 14 | 6 | 10 | 12 | 12 | 12 | 12 |  | 50 Ohms | TOP=L2:L3=L2/L4:L6=L5/L7:BOTTOM=L7 |
| ROMA2 | OTHERS | BUS | 6 | 5 | 5 | 10 | 5 | 14 | 6 | 10 | 12 | 12 | 12 | 12 |  | 50 Ohms | TOP=L2:L3=L2/L4:L6=L5/L7:BOTTOM=L7 |
| ROMA2 | OTHERS | BUS | 7 | 5 | 5 | 10 | 5 | 14 | 6 | 10 | 12 | 12 | 12 | 12 |  | 50 Ohms | TOP=L2:L3=L2/L4:L6=L5/L7:BOTTOM=L7 |
| ROMA2 | OTHERS | BUS | 8 | 4.75 | 5 | 10 | 5 | 14 | 6 | 9.5 | 12 | 12 | 12 | 12 |  | 50 Ohms | TOP=L2:L3=L2/L4:L6=L5/L7:BOTTOM=L7 |
| ROMA20 | OTHERS | BUS | 1 | 4.75 | 5 | 10 | 5 | 14 | 6 | 9.5 | 12 | 12 | 12 | 12 |  | 50 Ohms | TOP=L2:L3=L2/L4:L6=L5/L7:BOTTOM=L7 |
| ROMA20 | OTHERS | BUS | 2 | 5 | 5 | 10 | 5 | 14 | 6 | 10 | 12 | 12 | 12 | 12 |  | 50 Ohms | TOP=L2:L3=L2/L4:L6=L5/L7:BOTTOM=L7 |
| ROMA20 | OTHERS | BUS | 3 | 5 | 5 | 10 | 5 | 14 | 6 | 10 | 12 | 12 | 12 | 12 |  | 50 Ohms | TOP=L2:L3=L2/L4:L6=L5/L7:BOTTOM=L7 |
| ROMA20 | OTHERS | BUS | 4 | 5 | 5 | 10 | 5 | 14 | 6 | 10 | 12 | 12 | 12 | 12 |  | 50 Ohms | TOP=L2:L3=L2/L4:L6=L5/L7:BOTTOM=L7 |
| ROMA20 | OTHERS | BUS | 5 | 5 | 5 | 10 | 5 | 14 | 6 | 10 | 12 | 12 | 12 | 12 |  | 50 Ohms | TOP=L2:L3=L2/L4:L6=L5/L7:BOTTOM=L7 |
| ROMA20 | OTHERS | BUS | 6 | 5 | 5 | 10 | 5 | 14 | 6 | 10 | 12 | 12 | 12 | 12 |  | 50 Ohms | TOP=L2:L3=L2/L4:L6=L5/L7:BOTTOM=L7 |
| ROMA20 | OTHERS | BUS | 7 | 5 | 5 | 10 | 5 | 14 | 6 | 10 | 12 | 12 | 12 | 12 |  | 50 Ohms | TOP=L2:L3=L2/L4:L6=L5/L7:BOTTOM=L7 |
| ROMA20 | OTHERS | BUS | 8 | 4.75 | 5 | 10 | 5 | 14 | 6 | 9.5 | 12 | 12 | 12 | 12 |  | 50 Ohms | TOP=L2:L3=L2/L4:L6=L5/L7:BOTTOM=L7 |
| ROMA21 | OTHERS | BUS | 1 | 4.75 | 5 | 10 | 5 | 14 | 6 | 9.5 | 12 | 12 | 12 | 12 |  | 50 Ohms | TOP=L2:L3=L2/L4:L6=L5/L7:BOTTOM=L7 |
| ROMA21 | OTHERS | BUS | 2 | 5 | 5 | 10 | 5 | 14 | 6 | 10 | 12 | 12 | 12 | 12 |  | 50 Ohms | TOP=L2:L3=L2/L4:L6=L5/L7:BOTTOM=L7 |
| ROMA21 | OTHERS | BUS | 3 | 5 | 5 | 10 | 5 | 14 | 6 | 10 | 12 | 12 | 12 | 12 |  | 50 Ohms | TOP=L2:L3=L2/L4:L6=L5/L7:BOTTOM=L7 |
| ROMA21 | OTHERS | BUS | 4 | 5 | 5 | 10 | 5 | 14 | 6 | 10 | 12 | 12 | 12 | 12 |  | 50 Ohms | TOP=L2:L3=L2/L4:L6=L5/L7:BOTTOM=L7 |
| ROMA21 | OTHERS | BUS | 5 | 5 | 5 | 10 | 5 | 14 | 6 | 10 | 12 | 12 | 12 | 12 |  | 50 Ohms | TOP=L2:L3=L2/L4:L6=L5/L7:BOTTOM=L7 |
| ROMA21 | OTHERS | BUS | 6 | 5 | 5 | 10 | 5 | 14 | 6 | 10 | 12 | 12 | 12 | 12 |  | 50 Ohms | TOP=L2:L3=L2/L4:L6=L5/L7:BOTTOM=L7 |
| ROMA21 | OTHERS | BUS | 7 | 5 | 5 | 10 | 5 | 14 | 6 | 10 | 12 | 12 | 12 | 12 |  | 50 Ohms | TOP=L2:L3=L2/L4:L6=L5/L7:BOTTOM=L7 |
| ROMA21 | OTHERS | BUS | 8 | 4.75 | 5 | 10 | 5 | 14 | 6 | 9.5 | 12 | 12 | 12 | 12 |  | 50 Ohms | TOP=L2:L3=L2/L4:L6=L5/L7:BOTTOM=L7 |
| ROMA22 | OTHERS | BUS | 1 | 4.75 | 5 | 10 | 5 | 14 | 6 | 9.5 | 12 | 12 | 12 | 12 |  | 50 Ohms | TOP=L2:L3=L2/L4:L6=L5/L7:BOTTOM=L7 |
| ROMA22 | OTHERS | BUS | 2 | 5 | 5 | 10 | 5 | 14 | 6 | 10 | 12 | 12 | 12 | 12 |  | 50 Ohms | TOP=L2:L3=L2/L4:L6=L5/L7:BOTTOM=L7 |
| ROMA22 | OTHERS | BUS | 3 | 5 | 5 | 10 | 5 | 14 | 6 | 10 | 12 | 12 | 12 | 12 |  | 50 Ohms | TOP=L2:L3=L2/L4:L6=L5/L7:BOTTOM=L7 |
| ROMA22 | OTHERS | BUS | 4 | 5 | 5 | 10 | 5 | 14 | 6 | 10 | 12 | 12 | 12 | 12 |  | 50 Ohms | TOP=L2:L3=L2/L4:L6=L5/L7:BOTTOM=L7 |
| ROMA22 | OTHERS | BUS | 5 | 5 | 5 | 10 | 5 | 14 | 6 | 10 | 12 | 12 | 12 | 12 |  | 50 Ohms | TOP=L2:L3=L2/L4:L6=L5/L7:BOTTOM=L7 |
| ROMA22 | OTHERS | BUS | 6 | 5 | 5 | 10 | 5 | 14 | 6 | 10 | 12 | 12 | 12 | 12 |  | 50 Ohms | TOP=L2:L3=L2/L4:L6=L5/L7:BOTTOM=L7 |
| ROMA22 | OTHERS | BUS | 7 | 5 | 5 | 10 | 5 | 14 | 6 | 10 | 12 | 12 | 12 | 12 |  | 50 Ohms | TOP=L2:L3=L2/L4:L6=L5/L7:BOTTOM=L7 |
| ROMA22 | OTHERS | BUS | 8 | 4.75 | 5 | 10 | 5 | 14 | 6 | 9.5 | 12 | 12 | 12 | 12 |  | 50 Ohms | TOP=L2:L3=L2/L4:L6=L5/L7:BOTTOM=L7 |
| ROMA23 | OTHERS | BUS | 1 | 4.75 | 5 | 10 | 5 | 14 | 6 | 9.5 | 12 | 12 | 12 | 12 |  | 50 Ohms | TOP=L2:L3=L2/L4:L6=L5/L7:BOTTOM=L7 |
| ROMA23 | OTHERS | BUS | 2 | 5 | 5 | 10 | 5 | 14 | 6 | 10 | 12 | 12 | 12 | 12 |  | 50 Ohms | TOP=L2:L3=L2/L4:L6=L5/L7:BOTTOM=L7 |
| ROMA23 | OTHERS | BUS | 3 | 5 | 5 | 10 | 5 | 14 | 6 | 10 | 12 | 12 | 12 | 12 |  | 50 Ohms | TOP=L2:L3=L2/L4:L6=L5/L7:BOTTOM=L7 |
| ROMA23 | OTHERS | BUS | 4 | 5 | 5 | 10 | 5 | 14 | 6 | 10 | 12 | 12 | 12 | 12 |  | 50 Ohms | TOP=L2:L3=L2/L4:L6=L5/L7:BOTTOM=L7 |
| ROMA23 | OTHERS | BUS | 5 | 5 | 5 | 10 | 5 | 14 | 6 | 10 | 12 | 12 | 12 | 12 |  | 50 Ohms | TOP=L2:L3=L2/L4:L6=L5/L7:BOTTOM=L7 |
| ROMA23 | OTHERS | BUS | 6 | 5 | 5 | 10 | 5 | 14 | 6 | 10 | 12 | 12 | 12 | 12 |  | 50 Ohms | TOP=L2:L3=L2/L4:L6=L5/L7:BOTTOM=L7 |
| ROMA23 | OTHERS | BUS | 7 | 5 | 5 | 10 | 5 | 14 | 6 | 10 | 12 | 12 | 12 | 12 |  | 50 Ohms | TOP=L2:L3=L2/L4:L6=L5/L7:BOTTOM=L7 |
| ROMA23 | OTHERS | BUS | 8 | 4.75 | 5 | 10 | 5 | 14 | 6 | 9.5 | 12 | 12 | 12 | 12 |  | 50 Ohms | TOP=L2:L3=L2/L4:L6=L5/L7:BOTTOM=L7 |
| ROMA3 | OTHERS | BUS | 1 | 4.75 | 5 | 10 | 5 | 14 | 6 | 9.5 | 12 | 12 | 12 | 12 |  | 50 Ohms | TOP=L2:L3=L2/L4:L6=L5/L7:BOTTOM=L7 |
| ROMA3 | OTHERS | BUS | 2 | 5 | 5 | 10 | 5 | 14 | 6 | 10 | 12 | 12 | 12 | 12 |  | 50 Ohms | TOP=L2:L3=L2/L4:L6=L5/L7:BOTTOM=L7 |
| ROMA3 | OTHERS | BUS | 3 | 5 | 5 | 10 | 5 | 14 | 6 | 10 | 12 | 12 | 12 | 12 |  | 50 Ohms | TOP=L2:L3=L2/L4:L6=L5/L7:BOTTOM=L7 |
| ROMA3 | OTHERS | BUS | 4 | 5 | 5 | 10 | 5 | 14 | 6 | 10 | 12 | 12 | 12 | 12 |  | 50 Ohms | TOP=L2:L3=L2/L4:L6=L5/L7:BOTTOM=L7 |
| ROMA3 | OTHERS | BUS | 5 | 5 | 5 | 10 | 5 | 14 | 6 | 10 | 12 | 12 | 12 | 12 |  | 50 Ohms | TOP=L2:L3=L2/L4:L6=L5/L7:BOTTOM=L7 |
| ROMA3 | OTHERS | BUS | 6 | 5 | 5 | 10 | 5 | 14 | 6 | 10 | 12 | 12 | 12 | 12 |  | 50 Ohms | TOP=L2:L3=L2/L4:L6=L5/L7:BOTTOM=L7 |
| ROMA3 | OTHERS | BUS | 7 | 5 | 5 | 10 | 5 | 14 | 6 | 10 | 12 | 12 | 12 | 12 |  | 50 Ohms | TOP=L2:L3=L2/L4:L6=L5/L7:BOTTOM=L7 |
| ROMA3 | OTHERS | BUS | 8 | 4.75 | 5 | 10 | 5 | 14 | 6 | 9.5 | 12 | 12 | 12 | 12 |  | 50 Ohms | TOP=L2:L3=L2/L4:L6=L5/L7:BOTTOM=L7 |
| ROMA4 | OTHERS | BUS | 1 | 4.75 | 5 | 10 | 5 | 14 | 6 | 9.5 | 12 | 12 | 12 | 12 |  | 50 Ohms | TOP=L2:L3=L2/L4:L6=L5/L7:BOTTOM=L7 |
| ROMA4 | OTHERS | BUS | 2 | 5 | 5 | 10 | 5 | 14 | 6 | 10 | 12 | 12 | 12 | 12 |  | 50 Ohms | TOP=L2:L3=L2/L4:L6=L5/L7:BOTTOM=L7 |
| ROMA4 | OTHERS | BUS | 3 | 5 | 5 | 10 | 5 | 14 | 6 | 10 | 12 | 12 | 12 | 12 |  | 50 Ohms | TOP=L2:L3=L2/L4:L6=L5/L7:BOTTOM=L7 |
| ROMA4 | OTHERS | BUS | 4 | 5 | 5 | 10 | 5 | 14 | 6 | 10 | 12 | 12 | 12 | 12 |  | 50 Ohms | TOP=L2:L3=L2/L4:L6=L5/L7:BOTTOM=L7 |
| ROMA4 | OTHERS | BUS | 5 | 5 | 5 | 10 | 5 | 14 | 6 | 10 | 12 | 12 | 12 | 12 |  | 50 Ohms | TOP=L2:L3=L2/L4:L6=L5/L7:BOTTOM=L7 |
| ROMA4 | OTHERS | BUS | 6 | 5 | 5 | 10 | 5 | 14 | 6 | 10 | 12 | 12 | 12 | 12 |  | 50 Ohms | TOP=L2:L3=L2/L4:L6=L5/L7:BOTTOM=L7 |
| ROMA4 | OTHERS | BUS | 7 | 5 | 5 | 10 | 5 | 14 | 6 | 10 | 12 | 12 | 12 | 12 |  | 50 Ohms | TOP=L2:L3=L2/L4:L6=L5/L7:BOTTOM=L7 |
| ROMA4 | OTHERS | BUS | 8 | 4.75 | 5 | 10 | 5 | 14 | 6 | 9.5 | 12 | 12 | 12 | 12 |  | 50 Ohms | TOP=L2:L3=L2/L4:L6=L5/L7:BOTTOM=L7 |
| ROMA5 | OTHERS | BUS | 1 | 4.75 | 5 | 10 | 5 | 14 | 6 | 9.5 | 12 | 12 | 12 | 12 |  | 50 Ohms | TOP=L2:L3=L2/L4:L6=L5/L7:BOTTOM=L7 |
| ROMA5 | OTHERS | BUS | 2 | 5 | 5 | 10 | 5 | 14 | 6 | 10 | 12 | 12 | 12 | 12 |  | 50 Ohms | TOP=L2:L3=L2/L4:L6=L5/L7:BOTTOM=L7 |
| ROMA5 | OTHERS | BUS | 3 | 5 | 5 | 10 | 5 | 14 | 6 | 10 | 12 | 12 | 12 | 12 |  | 50 Ohms | TOP=L2:L3=L2/L4:L6=L5/L7:BOTTOM=L7 |
| ROMA5 | OTHERS | BUS | 4 | 5 | 5 | 10 | 5 | 14 | 6 | 10 | 12 | 12 | 12 | 12 |  | 50 Ohms | TOP=L2:L3=L2/L4:L6=L5/L7:BOTTOM=L7 |
| ROMA5 | OTHERS | BUS | 5 | 5 | 5 | 10 | 5 | 14 | 6 | 10 | 12 | 12 | 12 | 12 |  | 50 Ohms | TOP=L2:L3=L2/L4:L6=L5/L7:BOTTOM=L7 |
| ROMA5 | OTHERS | BUS | 6 | 5 | 5 | 10 | 5 | 14 | 6 | 10 | 12 | 12 | 12 | 12 |  | 50 Ohms | TOP=L2:L3=L2/L4:L6=L5/L7:BOTTOM=L7 |
| ROMA5 | OTHERS | BUS | 7 | 5 | 5 | 10 | 5 | 14 | 6 | 10 | 12 | 12 | 12 | 12 |  | 50 Ohms | TOP=L2:L3=L2/L4:L6=L5/L7:BOTTOM=L7 |
| ROMA5 | OTHERS | BUS | 8 | 4.75 | 5 | 10 | 5 | 14 | 6 | 9.5 | 12 | 12 | 12 | 12 |  | 50 Ohms | TOP=L2:L3=L2/L4:L6=L5/L7:BOTTOM=L7 |
| ROMA6 | OTHERS | BUS | 1 | 4.75 | 5 | 10 | 5 | 14 | 6 | 9.5 | 12 | 12 | 12 | 12 |  | 50 Ohms | TOP=L2:L3=L2/L4:L6=L5/L7:BOTTOM=L7 |
| ROMA6 | OTHERS | BUS | 2 | 5 | 5 | 10 | 5 | 14 | 6 | 10 | 12 | 12 | 12 | 12 |  | 50 Ohms | TOP=L2:L3=L2/L4:L6=L5/L7:BOTTOM=L7 |
| ROMA6 | OTHERS | BUS | 3 | 5 | 5 | 10 | 5 | 14 | 6 | 10 | 12 | 12 | 12 | 12 |  | 50 Ohms | TOP=L2:L3=L2/L4:L6=L5/L7:BOTTOM=L7 |
| ROMA6 | OTHERS | BUS | 4 | 5 | 5 | 10 | 5 | 14 | 6 | 10 | 12 | 12 | 12 | 12 |  | 50 Ohms | TOP=L2:L3=L2/L4:L6=L5/L7:BOTTOM=L7 |
| ROMA6 | OTHERS | BUS | 5 | 5 | 5 | 10 | 5 | 14 | 6 | 10 | 12 | 12 | 12 | 12 |  | 50 Ohms | TOP=L2:L3=L2/L4:L6=L5/L7:BOTTOM=L7 |
| ROMA6 | OTHERS | BUS | 6 | 5 | 5 | 10 | 5 | 14 | 6 | 10 | 12 | 12 | 12 | 12 |  | 50 Ohms | TOP=L2:L3=L2/L4:L6=L5/L7:BOTTOM=L7 |
| ROMA6 | OTHERS | BUS | 7 | 5 | 5 | 10 | 5 | 14 | 6 | 10 | 12 | 12 | 12 | 12 |  | 50 Ohms | TOP=L2:L3=L2/L4:L6=L5/L7:BOTTOM=L7 |
| ROMA6 | OTHERS | BUS | 8 | 4.75 | 5 | 10 | 5 | 14 | 6 | 9.5 | 12 | 12 | 12 | 12 |  | 50 Ohms | TOP=L2:L3=L2/L4:L6=L5/L7:BOTTOM=L7 |
| ROMA7 | OTHERS | BUS | 1 | 4.75 | 5 | 10 | 5 | 14 | 6 | 9.5 | 12 | 12 | 12 | 12 |  | 50 Ohms | TOP=L2:L3=L2/L4:L6=L5/L7:BOTTOM=L7 |
| ROMA7 | OTHERS | BUS | 2 | 5 | 5 | 10 | 5 | 14 | 6 | 10 | 12 | 12 | 12 | 12 |  | 50 Ohms | TOP=L2:L3=L2/L4:L6=L5/L7:BOTTOM=L7 |
| ROMA7 | OTHERS | BUS | 3 | 5 | 5 | 10 | 5 | 14 | 6 | 10 | 12 | 12 | 12 | 12 |  | 50 Ohms | TOP=L2:L3=L2/L4:L6=L5/L7:BOTTOM=L7 |
| ROMA7 | OTHERS | BUS | 4 | 5 | 5 | 10 | 5 | 14 | 6 | 10 | 12 | 12 | 12 | 12 |  | 50 Ohms | TOP=L2:L3=L2/L4:L6=L5/L7:BOTTOM=L7 |
| ROMA7 | OTHERS | BUS | 5 | 5 | 5 | 10 | 5 | 14 | 6 | 10 | 12 | 12 | 12 | 12 |  | 50 Ohms | TOP=L2:L3=L2/L4:L6=L5/L7:BOTTOM=L7 |
| ROMA7 | OTHERS | BUS | 6 | 5 | 5 | 10 | 5 | 14 | 6 | 10 | 12 | 12 | 12 | 12 |  | 50 Ohms | TOP=L2:L3=L2/L4:L6=L5/L7:BOTTOM=L7 |
| ROMA7 | OTHERS | BUS | 7 | 5 | 5 | 10 | 5 | 14 | 6 | 10 | 12 | 12 | 12 | 12 |  | 50 Ohms | TOP=L2:L3=L2/L4:L6=L5/L7:BOTTOM=L7 |
| ROMA7 | OTHERS | BUS | 8 | 4.75 | 5 | 10 | 5 | 14 | 6 | 9.5 | 12 | 12 | 12 | 12 |  | 50 Ohms | TOP=L2:L3=L2/L4:L6=L5/L7:BOTTOM=L7 |
| ROMA8 | OTHERS | BUS | 1 | 4.75 | 5 | 10 | 5 | 14 | 6 | 9.5 | 12 | 12 | 12 | 12 |  | 50 Ohms | TOP=L2:L3=L2/L4:L6=L5/L7:BOTTOM=L7 |
| ROMA8 | OTHERS | BUS | 2 | 5 | 5 | 10 | 5 | 14 | 6 | 10 | 12 | 12 | 12 | 12 |  | 50 Ohms | TOP=L2:L3=L2/L4:L6=L5/L7:BOTTOM=L7 |
| ROMA8 | OTHERS | BUS | 3 | 5 | 5 | 10 | 5 | 14 | 6 | 10 | 12 | 12 | 12 | 12 |  | 50 Ohms | TOP=L2:L3=L2/L4:L6=L5/L7:BOTTOM=L7 |
| ROMA8 | OTHERS | BUS | 4 | 5 | 5 | 10 | 5 | 14 | 6 | 10 | 12 | 12 | 12 | 12 |  | 50 Ohms | TOP=L2:L3=L2/L4:L6=L5/L7:BOTTOM=L7 |
| ROMA8 | OTHERS | BUS | 5 | 5 | 5 | 10 | 5 | 14 | 6 | 10 | 12 | 12 | 12 | 12 |  | 50 Ohms | TOP=L2:L3=L2/L4:L6=L5/L7:BOTTOM=L7 |
| ROMA8 | OTHERS | BUS | 6 | 5 | 5 | 10 | 5 | 14 | 6 | 10 | 12 | 12 | 12 | 12 |  | 50 Ohms | TOP=L2:L3=L2/L4:L6=L5/L7:BOTTOM=L7 |
| ROMA8 | OTHERS | BUS | 7 | 5 | 5 | 10 | 5 | 14 | 6 | 10 | 12 | 12 | 12 | 12 |  | 50 Ohms | TOP=L2:L3=L2/L4:L6=L5/L7:BOTTOM=L7 |
| ROMA8 | OTHERS | BUS | 8 | 4.75 | 5 | 10 | 5 | 14 | 6 | 9.5 | 12 | 12 | 12 | 12 |  | 50 Ohms | TOP=L2:L3=L2/L4:L6=L5/L7:BOTTOM=L7 |
| ROMA9 | OTHERS | BUS | 1 | 4.75 | 5 | 10 | 5 | 14 | 6 | 9.5 | 12 | 12 | 12 | 12 |  | 50 Ohms | TOP=L2:L3=L2/L4:L6=L5/L7:BOTTOM=L7 |
| ROMA9 | OTHERS | BUS | 2 | 5 | 5 | 10 | 5 | 14 | 6 | 10 | 12 | 12 | 12 | 12 |  | 50 Ohms | TOP=L2:L3=L2/L4:L6=L5/L7:BOTTOM=L7 |
| ROMA9 | OTHERS | BUS | 3 | 5 | 5 | 10 | 5 | 14 | 6 | 10 | 12 | 12 | 12 | 12 |  | 50 Ohms | TOP=L2:L3=L2/L4:L6=L5/L7:BOTTOM=L7 |
| ROMA9 | OTHERS | BUS | 4 | 5 | 5 | 10 | 5 | 14 | 6 | 10 | 12 | 12 | 12 | 12 |  | 50 Ohms | TOP=L2:L3=L2/L4:L6=L5/L7:BOTTOM=L7 |
| ROMA9 | OTHERS | BUS | 5 | 5 | 5 | 10 | 5 | 14 | 6 | 10 | 12 | 12 | 12 | 12 |  | 50 Ohms | TOP=L2:L3=L2/L4:L6=L5/L7:BOTTOM=L7 |
| ROMA9 | OTHERS | BUS | 6 | 5 | 5 | 10 | 5 | 14 | 6 | 10 | 12 | 12 | 12 | 12 |  | 50 Ohms | TOP=L2:L3=L2/L4:L6=L5/L7:BOTTOM=L7 |
| ROMA9 | OTHERS | BUS | 7 | 5 | 5 | 10 | 5 | 14 | 6 | 10 | 12 | 12 | 12 | 12 |  | 50 Ohms | TOP=L2:L3=L2/L4:L6=L5/L7:BOTTOM=L7 |
| ROMA9 | OTHERS | BUS | 8 | 4.75 | 5 | 10 | 5 | 14 | 6 | 9.5 | 12 | 12 | 12 | 12 |  | 50 Ohms | TOP=L2:L3=L2/L4:L6=L5/L7:BOTTOM=L7 |
| ROMD2_SEC | OTHERS | BUS | 1 | 4.75 | 5 | 10 | 5 | 14 | 6 | 9.5 | 12 | 12 | 12 | 12 |  | 50 Ohms | TOP=L2:L3=L2/L4:L6=L5/L7:BOTTOM=L7 |
| ROMD2_SEC | OTHERS | BUS | 2 | 5 | 5 | 10 | 5 | 14 | 6 | 10 | 12 | 12 | 12 | 12 |  | 50 Ohms | TOP=L2:L3=L2/L4:L6=L5/L7:BOTTOM=L7 |
| ROMD2_SEC | OTHERS | BUS | 3 | 5 | 5 | 10 | 5 | 14 | 6 | 10 | 12 | 12 | 12 | 12 |  | 50 Ohms | TOP=L2:L3=L2/L4:L6=L5/L7:BOTTOM=L7 |
| ROMD2_SEC | OTHERS | BUS | 4 | 5 | 5 | 10 | 5 | 14 | 6 | 10 | 12 | 12 | 12 | 12 |  | 50 Ohms | TOP=L2:L3=L2/L4:L6=L5/L7:BOTTOM=L7 |
| ROMD2_SEC | OTHERS | BUS | 5 | 5 | 5 | 10 | 5 | 14 | 6 | 10 | 12 | 12 | 12 | 12 |  | 50 Ohms | TOP=L2:L3=L2/L4:L6=L5/L7:BOTTOM=L7 |
| ROMD2_SEC | OTHERS | BUS | 6 | 5 | 5 | 10 | 5 | 14 | 6 | 10 | 12 | 12 | 12 | 12 |  | 50 Ohms | TOP=L2:L3=L2/L4:L6=L5/L7:BOTTOM=L7 |
| ROMD2_SEC | OTHERS | BUS | 7 | 5 | 5 | 10 | 5 | 14 | 6 | 10 | 12 | 12 | 12 | 12 |  | 50 Ohms | TOP=L2:L3=L2/L4:L6=L5/L7:BOTTOM=L7 |
| ROMD2_SEC | OTHERS | BUS | 8 | 4.75 | 5 | 10 | 5 | 14 | 6 | 9.5 | 12 | 12 | 12 | 12 |  | 50 Ohms | TOP=L2:L3=L2/L4:L6=L5/L7:BOTTOM=L7 |
| ROMD3 | OTHERS | BUS | 1 | 4.75 | 5 | 10 | 5 | 14 | 6 | 9.5 | 12 | 12 | 12 | 12 |  | 50 Ohms | TOP=L2:L3=L2/L4:L6=L5/L7:BOTTOM=L7 |
| ROMD3 | OTHERS | BUS | 2 | 5 | 5 | 10 | 5 | 14 | 6 | 10 | 12 | 12 | 12 | 12 |  | 50 Ohms | TOP=L2:L3=L2/L4:L6=L5/L7:BOTTOM=L7 |
| ROMD3 | OTHERS | BUS | 3 | 5 | 5 | 10 | 5 | 14 | 6 | 10 | 12 | 12 | 12 | 12 |  | 50 Ohms | TOP=L2:L3=L2/L4:L6=L5/L7:BOTTOM=L7 |
| ROMD3 | OTHERS | BUS | 4 | 5 | 5 | 10 | 5 | 14 | 6 | 10 | 12 | 12 | 12 | 12 |  | 50 Ohms | TOP=L2:L3=L2/L4:L6=L5/L7:BOTTOM=L7 |
| ROMD3 | OTHERS | BUS | 5 | 5 | 5 | 10 | 5 | 14 | 6 | 10 | 12 | 12 | 12 | 12 |  | 50 Ohms | TOP=L2:L3=L2/L4:L6=L5/L7:BOTTOM=L7 |
| ROMD3 | OTHERS | BUS | 6 | 5 | 5 | 10 | 5 | 14 | 6 | 10 | 12 | 12 | 12 | 12 |  | 50 Ohms | TOP=L2:L3=L2/L4:L6=L5/L7:BOTTOM=L7 |
| ROMD3 | OTHERS | BUS | 7 | 5 | 5 | 10 | 5 | 14 | 6 | 10 | 12 | 12 | 12 | 12 |  | 50 Ohms | TOP=L2:L3=L2/L4:L6=L5/L7:BOTTOM=L7 |
| ROMD3 | OTHERS | BUS | 8 | 4.75 | 5 | 10 | 5 | 14 | 6 | 9.5 | 12 | 12 | 12 | 12 |  | 50 Ohms | TOP=L2:L3=L2/L4:L6=L5/L7:BOTTOM=L7 |
| ROMD4 | OTHERS | BUS | 1 | 4.75 | 5 | 10 | 5 | 14 | 6 | 9.5 | 12 | 12 | 12 | 12 |  | 50 Ohms | TOP=L2:L3=L2/L4:L6=L5/L7:BOTTOM=L7 |
| ROMD4 | OTHERS | BUS | 2 | 5 | 5 | 10 | 5 | 14 | 6 | 10 | 12 | 12 | 12 | 12 |  | 50 Ohms | TOP=L2:L3=L2/L4:L6=L5/L7:BOTTOM=L7 |
| ROMD4 | OTHERS | BUS | 3 | 5 | 5 | 10 | 5 | 14 | 6 | 10 | 12 | 12 | 12 | 12 |  | 50 Ohms | TOP=L2:L3=L2/L4:L6=L5/L7:BOTTOM=L7 |
| ROMD4 | OTHERS | BUS | 4 | 5 | 5 | 10 | 5 | 14 | 6 | 10 | 12 | 12 | 12 | 12 |  | 50 Ohms | TOP=L2:L3=L2/L4:L6=L5/L7:BOTTOM=L7 |
| ROMD4 | OTHERS | BUS | 5 | 5 | 5 | 10 | 5 | 14 | 6 | 10 | 12 | 12 | 12 | 12 |  | 50 Ohms | TOP=L2:L3=L2/L4:L6=L5/L7:BOTTOM=L7 |
| ROMD4 | OTHERS | BUS | 6 | 5 | 5 | 10 | 5 | 14 | 6 | 10 | 12 | 12 | 12 | 12 |  | 50 Ohms | TOP=L2:L3=L2/L4:L6=L5/L7:BOTTOM=L7 |
| ROMD4 | OTHERS | BUS | 7 | 5 | 5 | 10 | 5 | 14 | 6 | 10 | 12 | 12 | 12 | 12 |  | 50 Ohms | TOP=L2:L3=L2/L4:L6=L5/L7:BOTTOM=L7 |
| ROMD4 | OTHERS | BUS | 8 | 4.75 | 5 | 10 | 5 | 14 | 6 | 9.5 | 12 | 12 | 12 | 12 |  | 50 Ohms | TOP=L2:L3=L2/L4:L6=L5/L7:BOTTOM=L7 |
| ROMD5 | OTHERS | BUS | 1 | 4.75 | 5 | 10 | 5 | 14 | 6 | 9.5 | 12 | 12 | 12 | 12 |  | 50 Ohms | TOP=L2:L3=L2/L4:L6=L5/L7:BOTTOM=L7 |
| ROMD5 | OTHERS | BUS | 2 | 5 | 5 | 10 | 5 | 14 | 6 | 10 | 12 | 12 | 12 | 12 |  | 50 Ohms | TOP=L2:L3=L2/L4:L6=L5/L7:BOTTOM=L7 |
| ROMD5 | OTHERS | BUS | 3 | 5 | 5 | 10 | 5 | 14 | 6 | 10 | 12 | 12 | 12 | 12 |  | 50 Ohms | TOP=L2:L3=L2/L4:L6=L5/L7:BOTTOM=L7 |
| ROMD5 | OTHERS | BUS | 4 | 5 | 5 | 10 | 5 | 14 | 6 | 10 | 12 | 12 | 12 | 12 |  | 50 Ohms | TOP=L2:L3=L2/L4:L6=L5/L7:BOTTOM=L7 |
| ROMD5 | OTHERS | BUS | 5 | 5 | 5 | 10 | 5 | 14 | 6 | 10 | 12 | 12 | 12 | 12 |  | 50 Ohms | TOP=L2:L3=L2/L4:L6=L5/L7:BOTTOM=L7 |
| ROMD5 | OTHERS | BUS | 6 | 5 | 5 | 10 | 5 | 14 | 6 | 10 | 12 | 12 | 12 | 12 |  | 50 Ohms | TOP=L2:L3=L2/L4:L6=L5/L7:BOTTOM=L7 |
| ROMD5 | OTHERS | BUS | 7 | 5 | 5 | 10 | 5 | 14 | 6 | 10 | 12 | 12 | 12 | 12 |  | 50 Ohms | TOP=L2:L3=L2/L4:L6=L5/L7:BOTTOM=L7 |
| ROMD5 | OTHERS | BUS | 8 | 4.75 | 5 | 10 | 5 | 14 | 6 | 9.5 | 12 | 12 | 12 | 12 |  | 50 Ohms | TOP=L2:L3=L2/L4:L6=L5/L7:BOTTOM=L7 |
| ROMD6 | OTHERS | BUS | 1 | 4.75 | 5 | 10 | 5 | 14 | 6 | 9.5 | 12 | 12 | 12 | 12 |  | 50 Ohms | TOP=L2:L3=L2/L4:L6=L5/L7:BOTTOM=L7 |
| ROMD6 | OTHERS | BUS | 2 | 5 | 5 | 10 | 5 | 14 | 6 | 10 | 12 | 12 | 12 | 12 |  | 50 Ohms | TOP=L2:L3=L2/L4:L6=L5/L7:BOTTOM=L7 |
| ROMD6 | OTHERS | BUS | 3 | 5 | 5 | 10 | 5 | 14 | 6 | 10 | 12 | 12 | 12 | 12 |  | 50 Ohms | TOP=L2:L3=L2/L4:L6=L5/L7:BOTTOM=L7 |
| ROMD6 | OTHERS | BUS | 4 | 5 | 5 | 10 | 5 | 14 | 6 | 10 | 12 | 12 | 12 | 12 |  | 50 Ohms | TOP=L2:L3=L2/L4:L6=L5/L7:BOTTOM=L7 |
| ROMD6 | OTHERS | BUS | 5 | 5 | 5 | 10 | 5 | 14 | 6 | 10 | 12 | 12 | 12 | 12 |  | 50 Ohms | TOP=L2:L3=L2/L4:L6=L5/L7:BOTTOM=L7 |
| ROMD6 | OTHERS | BUS | 6 | 5 | 5 | 10 | 5 | 14 | 6 | 10 | 12 | 12 | 12 | 12 |  | 50 Ohms | TOP=L2:L3=L2/L4:L6=L5/L7:BOTTOM=L7 |
| ROMD6 | OTHERS | BUS | 7 | 5 | 5 | 10 | 5 | 14 | 6 | 10 | 12 | 12 | 12 | 12 |  | 50 Ohms | TOP=L2:L3=L2/L4:L6=L5/L7:BOTTOM=L7 |
| ROMD6 | OTHERS | BUS | 8 | 4.75 | 5 | 10 | 5 | 14 | 6 | 9.5 | 12 | 12 | 12 | 12 |  | 50 Ohms | TOP=L2:L3=L2/L4:L6=L5/L7:BOTTOM=L7 |
| ROMD7 | OTHERS | BUS | 1 | 4.75 | 5 | 10 | 5 | 14 | 6 | 9.5 | 12 | 12 | 12 | 12 |  | 50 Ohms | TOP=L2:L3=L2/L4:L6=L5/L7:BOTTOM=L7 |
| ROMD7 | OTHERS | BUS | 2 | 5 | 5 | 10 | 5 | 14 | 6 | 10 | 12 | 12 | 12 | 12 |  | 50 Ohms | TOP=L2:L3=L2/L4:L6=L5/L7:BOTTOM=L7 |
| ROMD7 | OTHERS | BUS | 3 | 5 | 5 | 10 | 5 | 14 | 6 | 10 | 12 | 12 | 12 | 12 |  | 50 Ohms | TOP=L2:L3=L2/L4:L6=L5/L7:BOTTOM=L7 |
| ROMD7 | OTHERS | BUS | 4 | 5 | 5 | 10 | 5 | 14 | 6 | 10 | 12 | 12 | 12 | 12 |  | 50 Ohms | TOP=L2:L3=L2/L4:L6=L5/L7:BOTTOM=L7 |
| ROMD7 | OTHERS | BUS | 5 | 5 | 5 | 10 | 5 | 14 | 6 | 10 | 12 | 12 | 12 | 12 |  | 50 Ohms | TOP=L2:L3=L2/L4:L6=L5/L7:BOTTOM=L7 |
| ROMD7 | OTHERS | BUS | 6 | 5 | 5 | 10 | 5 | 14 | 6 | 10 | 12 | 12 | 12 | 12 |  | 50 Ohms | TOP=L2:L3=L2/L4:L6=L5/L7:BOTTOM=L7 |
| ROMD7 | OTHERS | BUS | 7 | 5 | 5 | 10 | 5 | 14 | 6 | 10 | 12 | 12 | 12 | 12 |  | 50 Ohms | TOP=L2:L3=L2/L4:L6=L5/L7:BOTTOM=L7 |
| ROMD7 | OTHERS | BUS | 8 | 4.75 | 5 | 10 | 5 | 14 | 6 | 9.5 | 12 | 12 | 12 | 12 |  | 50 Ohms | TOP=L2:L3=L2/L4:L6=L5/L7:BOTTOM=L7 |
| RS232_UCTSB0 | OTHERS | BUS | 1 | 4.75 | 5 | 10 | 5 | 14 | 6 | 9.5 | 12 | 12 | 12 | 12 |  | 50 Ohms | TOP=L2:L3=L2/L4:L6=L5/L7:BOTTOM=L7 |
| RS232_UCTSB0 | OTHERS | BUS | 2 | 5 | 5 | 10 | 5 | 14 | 6 | 10 | 12 | 12 | 12 | 12 |  | 50 Ohms | TOP=L2:L3=L2/L4:L6=L5/L7:BOTTOM=L7 |
| RS232_UCTSB0 | OTHERS | BUS | 3 | 5 | 5 | 10 | 5 | 14 | 6 | 10 | 12 | 12 | 12 | 12 |  | 50 Ohms | TOP=L2:L3=L2/L4:L6=L5/L7:BOTTOM=L7 |
| RS232_UCTSB0 | OTHERS | BUS | 4 | 5 | 5 | 10 | 5 | 14 | 6 | 10 | 12 | 12 | 12 | 12 |  | 50 Ohms | TOP=L2:L3=L2/L4:L6=L5/L7:BOTTOM=L7 |
| RS232_UCTSB0 | OTHERS | BUS | 5 | 5 | 5 | 10 | 5 | 14 | 6 | 10 | 12 | 12 | 12 | 12 |  | 50 Ohms | TOP=L2:L3=L2/L4:L6=L5/L7:BOTTOM=L7 |
| RS232_UCTSB0 | OTHERS | BUS | 6 | 5 | 5 | 10 | 5 | 14 | 6 | 10 | 12 | 12 | 12 | 12 |  | 50 Ohms | TOP=L2:L3=L2/L4:L6=L5/L7:BOTTOM=L7 |
| RS232_UCTSB0 | OTHERS | BUS | 7 | 5 | 5 | 10 | 5 | 14 | 6 | 10 | 12 | 12 | 12 | 12 |  | 50 Ohms | TOP=L2:L3=L2/L4:L6=L5/L7:BOTTOM=L7 |
| RS232_UCTSB0 | OTHERS | BUS | 8 | 4.75 | 5 | 10 | 5 | 14 | 6 | 9.5 | 12 | 12 | 12 | 12 |  | 50 Ohms | TOP=L2:L3=L2/L4:L6=L5/L7:BOTTOM=L7 |
| RS232_URTSB0 | OTHERS | BUS | 1 | 4.75 | 5 | 10 | 5 | 14 | 6 | 9.5 | 12 | 12 | 12 | 12 |  | 50 Ohms | TOP=L2:L3=L2/L4:L6=L5/L7:BOTTOM=L7 |
| RS232_URTSB0 | OTHERS | BUS | 2 | 5 | 5 | 10 | 5 | 14 | 6 | 10 | 12 | 12 | 12 | 12 |  | 50 Ohms | TOP=L2:L3=L2/L4:L6=L5/L7:BOTTOM=L7 |
| RS232_URTSB0 | OTHERS | BUS | 3 | 5 | 5 | 10 | 5 | 14 | 6 | 10 | 12 | 12 | 12 | 12 |  | 50 Ohms | TOP=L2:L3=L2/L4:L6=L5/L7:BOTTOM=L7 |
| RS232_URTSB0 | OTHERS | BUS | 4 | 5 | 5 | 10 | 5 | 14 | 6 | 10 | 12 | 12 | 12 | 12 |  | 50 Ohms | TOP=L2:L3=L2/L4:L6=L5/L7:BOTTOM=L7 |
| RS232_URTSB0 | OTHERS | BUS | 5 | 5 | 5 | 10 | 5 | 14 | 6 | 10 | 12 | 12 | 12 | 12 |  | 50 Ohms | TOP=L2:L3=L2/L4:L6=L5/L7:BOTTOM=L7 |
| RS232_URTSB0 | OTHERS | BUS | 6 | 5 | 5 | 10 | 5 | 14 | 6 | 10 | 12 | 12 | 12 | 12 |  | 50 Ohms | TOP=L2:L3=L2/L4:L6=L5/L7:BOTTOM=L7 |
| RS232_URTSB0 | OTHERS | BUS | 7 | 5 | 5 | 10 | 5 | 14 | 6 | 10 | 12 | 12 | 12 | 12 |  | 50 Ohms | TOP=L2:L3=L2/L4:L6=L5/L7:BOTTOM=L7 |
| RS232_URTSB0 | OTHERS | BUS | 8 | 4.75 | 5 | 10 | 5 | 14 | 6 | 9.5 | 12 | 12 | 12 | 12 |  | 50 Ohms | TOP=L2:L3=L2/L4:L6=L5/L7:BOTTOM=L7 |
| RST_BMC_DDR3_R_N | OTHERS | BUS | 1 | 4.75 | 5 | 10 | 5 | 14 | 6 | 9.5 | 12 | 12 | 12 | 12 |  | 50 Ohms | TOP=L2:L3=L2/L4:L6=L5/L7:BOTTOM=L7 |
| RST_BMC_DDR3_R_N | OTHERS | BUS | 2 | 5 | 5 | 10 | 5 | 14 | 6 | 10 | 12 | 12 | 12 | 12 |  | 50 Ohms | TOP=L2:L3=L2/L4:L6=L5/L7:BOTTOM=L7 |
| RST_BMC_DDR3_R_N | OTHERS | BUS | 3 | 5 | 5 | 10 | 5 | 14 | 6 | 10 | 12 | 12 | 12 | 12 |  | 50 Ohms | TOP=L2:L3=L2/L4:L6=L5/L7:BOTTOM=L7 |
| RST_BMC_DDR3_R_N | OTHERS | BUS | 4 | 5 | 5 | 10 | 5 | 14 | 6 | 10 | 12 | 12 | 12 | 12 |  | 50 Ohms | TOP=L2:L3=L2/L4:L6=L5/L7:BOTTOM=L7 |
| RST_BMC_DDR3_R_N | OTHERS | BUS | 5 | 5 | 5 | 10 | 5 | 14 | 6 | 10 | 12 | 12 | 12 | 12 |  | 50 Ohms | TOP=L2:L3=L2/L4:L6=L5/L7:BOTTOM=L7 |
| RST_BMC_DDR3_R_N | OTHERS | BUS | 6 | 5 | 5 | 10 | 5 | 14 | 6 | 10 | 12 | 12 | 12 | 12 |  | 50 Ohms | TOP=L2:L3=L2/L4:L6=L5/L7:BOTTOM=L7 |
| RST_BMC_DDR3_R_N | OTHERS | BUS | 7 | 5 | 5 | 10 | 5 | 14 | 6 | 10 | 12 | 12 | 12 | 12 |  | 50 Ohms | TOP=L2:L3=L2/L4:L6=L5/L7:BOTTOM=L7 |
| RST_BMC_DDR3_R_N | OTHERS | BUS | 8 | 4.75 | 5 | 10 | 5 | 14 | 6 | 9.5 | 12 | 12 | 12 | 12 |  | 50 Ohms | TOP=L2:L3=L2/L4:L6=L5/L7:BOTTOM=L7 |
| RST_BMC_EXTRST_N | OTHERS | BUS | 1 | 4.75 | 5 | 10 | 5 | 14 | 6 | 9.5 | 12 | 12 | 12 | 12 |  | 50 Ohms | TOP=L2:L3=L2/L4:L6=L5/L7:BOTTOM=L7 |
| RST_BMC_EXTRST_N | OTHERS | BUS | 2 | 5 | 5 | 10 | 5 | 14 | 6 | 10 | 12 | 12 | 12 | 12 |  | 50 Ohms | TOP=L2:L3=L2/L4:L6=L5/L7:BOTTOM=L7 |
| RST_BMC_EXTRST_N | OTHERS | BUS | 3 | 5 | 5 | 10 | 5 | 14 | 6 | 10 | 12 | 12 | 12 | 12 |  | 50 Ohms | TOP=L2:L3=L2/L4:L6=L5/L7:BOTTOM=L7 |
| RST_BMC_EXTRST_N | OTHERS | BUS | 4 | 5 | 5 | 10 | 5 | 14 | 6 | 10 | 12 | 12 | 12 | 12 |  | 50 Ohms | TOP=L2:L3=L2/L4:L6=L5/L7:BOTTOM=L7 |
| RST_BMC_EXTRST_N | OTHERS | BUS | 5 | 5 | 5 | 10 | 5 | 14 | 6 | 10 | 12 | 12 | 12 | 12 |  | 50 Ohms | TOP=L2:L3=L2/L4:L6=L5/L7:BOTTOM=L7 |
| RST_BMC_EXTRST_N | OTHERS | BUS | 6 | 5 | 5 | 10 | 5 | 14 | 6 | 10 | 12 | 12 | 12 | 12 |  | 50 Ohms | TOP=L2:L3=L2/L4:L6=L5/L7:BOTTOM=L7 |
| RST_BMC_EXTRST_N | OTHERS | BUS | 7 | 5 | 5 | 10 | 5 | 14 | 6 | 10 | 12 | 12 | 12 | 12 |  | 50 Ohms | TOP=L2:L3=L2/L4:L6=L5/L7:BOTTOM=L7 |
| RST_BMC_EXTRST_N | OTHERS | BUS | 8 | 4.75 | 5 | 10 | 5 | 14 | 6 | 9.5 | 12 | 12 | 12 | 12 |  | 50 Ohms | TOP=L2:L3=L2/L4:L6=L5/L7:BOTTOM=L7 |
| RST_BMC_EXTRST_N_R | OTHERS | BUS | 1 | 4.75 | 5 | 10 | 5 | 14 | 6 | 9.5 | 12 | 12 | 12 | 12 |  | 50 Ohms | TOP=L2:L3=L2/L4:L6=L5/L7:BOTTOM=L7 |
| RST_BMC_EXTRST_N_R | OTHERS | BUS | 2 | 5 | 5 | 10 | 5 | 14 | 6 | 10 | 12 | 12 | 12 | 12 |  | 50 Ohms | TOP=L2:L3=L2/L4:L6=L5/L7:BOTTOM=L7 |
| RST_BMC_EXTRST_N_R | OTHERS | BUS | 3 | 5 | 5 | 10 | 5 | 14 | 6 | 10 | 12 | 12 | 12 | 12 |  | 50 Ohms | TOP=L2:L3=L2/L4:L6=L5/L7:BOTTOM=L7 |
| RST_BMC_EXTRST_N_R | OTHERS | BUS | 4 | 5 | 5 | 10 | 5 | 14 | 6 | 10 | 12 | 12 | 12 | 12 |  | 50 Ohms | TOP=L2:L3=L2/L4:L6=L5/L7:BOTTOM=L7 |
| RST_BMC_EXTRST_N_R | OTHERS | BUS | 5 | 5 | 5 | 10 | 5 | 14 | 6 | 10 | 12 | 12 | 12 | 12 |  | 50 Ohms | TOP=L2:L3=L2/L4:L6=L5/L7:BOTTOM=L7 |
| RST_BMC_EXTRST_N_R | OTHERS | BUS | 6 | 5 | 5 | 10 | 5 | 14 | 6 | 10 | 12 | 12 | 12 | 12 |  | 50 Ohms | TOP=L2:L3=L2/L4:L6=L5/L7:BOTTOM=L7 |
| RST_BMC_EXTRST_N_R | OTHERS | BUS | 7 | 5 | 5 | 10 | 5 | 14 | 6 | 10 | 12 | 12 | 12 | 12 |  | 50 Ohms | TOP=L2:L3=L2/L4:L6=L5/L7:BOTTOM=L7 |
| RST_BMC_EXTRST_N_R | OTHERS | BUS | 8 | 4.75 | 5 | 10 | 5 | 14 | 6 | 9.5 | 12 | 12 | 12 | 12 |  | 50 Ohms | TOP=L2:L3=L2/L4:L6=L5/L7:BOTTOM=L7 |
| RST_BTN# | OTHERS | BUS | 1 | 4.75 | 5 | 10 | 5 | 14 | 6 | 9.5 | 12 | 12 | 12 | 12 |  | 50 Ohms | TOP=L2:L3=L2/L4:L6=L5/L7:BOTTOM=L7 |
| RST_BTN# | OTHERS | BUS | 2 | 5 | 5 | 10 | 5 | 14 | 6 | 10 | 12 | 12 | 12 | 12 |  | 50 Ohms | TOP=L2:L3=L2/L4:L6=L5/L7:BOTTOM=L7 |
| RST_BTN# | OTHERS | BUS | 3 | 5 | 5 | 10 | 5 | 14 | 6 | 10 | 12 | 12 | 12 | 12 |  | 50 Ohms | TOP=L2:L3=L2/L4:L6=L5/L7:BOTTOM=L7 |
| RST_BTN# | OTHERS | BUS | 4 | 5 | 5 | 10 | 5 | 14 | 6 | 10 | 12 | 12 | 12 | 12 |  | 50 Ohms | TOP=L2:L3=L2/L4:L6=L5/L7:BOTTOM=L7 |
| RST_BTN# | OTHERS | BUS | 5 | 5 | 5 | 10 | 5 | 14 | 6 | 10 | 12 | 12 | 12 | 12 |  | 50 Ohms | TOP=L2:L3=L2/L4:L6=L5/L7:BOTTOM=L7 |
| RST_BTN# | OTHERS | BUS | 6 | 5 | 5 | 10 | 5 | 14 | 6 | 10 | 12 | 12 | 12 | 12 |  | 50 Ohms | TOP=L2:L3=L2/L4:L6=L5/L7:BOTTOM=L7 |
| RST_BTN# | OTHERS | BUS | 7 | 5 | 5 | 10 | 5 | 14 | 6 | 10 | 12 | 12 | 12 | 12 |  | 50 Ohms | TOP=L2:L3=L2/L4:L6=L5/L7:BOTTOM=L7 |
| RST_BTN# | OTHERS | BUS | 8 | 4.75 | 5 | 10 | 5 | 14 | 6 | 9.5 | 12 | 12 | 12 | 12 |  | 50 Ohms | TOP=L2:L3=L2/L4:L6=L5/L7:BOTTOM=L7 |
| RST_BTN#_R | OTHERS | BUS | 1 | 4.75 | 5 | 10 | 5 | 14 | 6 | 9.5 | 12 | 12 | 12 | 12 |  | 50 Ohms | TOP=L2:L3=L2/L4:L6=L5/L7:BOTTOM=L7 |
| RST_BTN#_R | OTHERS | BUS | 2 | 5 | 5 | 10 | 5 | 14 | 6 | 10 | 12 | 12 | 12 | 12 |  | 50 Ohms | TOP=L2:L3=L2/L4:L6=L5/L7:BOTTOM=L7 |
| RST_BTN#_R | OTHERS | BUS | 3 | 5 | 5 | 10 | 5 | 14 | 6 | 10 | 12 | 12 | 12 | 12 |  | 50 Ohms | TOP=L2:L3=L2/L4:L6=L5/L7:BOTTOM=L7 |
| RST_BTN#_R | OTHERS | BUS | 4 | 5 | 5 | 10 | 5 | 14 | 6 | 10 | 12 | 12 | 12 | 12 |  | 50 Ohms | TOP=L2:L3=L2/L4:L6=L5/L7:BOTTOM=L7 |
| RST_BTN#_R | OTHERS | BUS | 5 | 5 | 5 | 10 | 5 | 14 | 6 | 10 | 12 | 12 | 12 | 12 |  | 50 Ohms | TOP=L2:L3=L2/L4:L6=L5/L7:BOTTOM=L7 |
| RST_BTN#_R | OTHERS | BUS | 6 | 5 | 5 | 10 | 5 | 14 | 6 | 10 | 12 | 12 | 12 | 12 |  | 50 Ohms | TOP=L2:L3=L2/L4:L6=L5/L7:BOTTOM=L7 |
| RST_BTN#_R | OTHERS | BUS | 7 | 5 | 5 | 10 | 5 | 14 | 6 | 10 | 12 | 12 | 12 | 12 |  | 50 Ohms | TOP=L2:L3=L2/L4:L6=L5/L7:BOTTOM=L7 |
| RST_BTN#_R | OTHERS | BUS | 8 | 4.75 | 5 | 10 | 5 | 14 | 6 | 9.5 | 12 | 12 | 12 | 12 |  | 50 Ohms | TOP=L2:L3=L2/L4:L6=L5/L7:BOTTOM=L7 |
| SAS_SMART_R_RX | OTHERS | BUS | 1 | 4.75 | 5 | 10 | 5 | 14 | 6 | 9.5 | 12 | 12 | 12 | 12 |  | 50 Ohms | TOP=L2:L3=L2/L4:L6=L5/L7:BOTTOM=L7 |
| SAS_SMART_R_RX | OTHERS | BUS | 2 | 5 | 5 | 10 | 5 | 14 | 6 | 10 | 12 | 12 | 12 | 12 |  | 50 Ohms | TOP=L2:L3=L2/L4:L6=L5/L7:BOTTOM=L7 |
| SAS_SMART_R_RX | OTHERS | BUS | 3 | 5 | 5 | 10 | 5 | 14 | 6 | 10 | 12 | 12 | 12 | 12 |  | 50 Ohms | TOP=L2:L3=L2/L4:L6=L5/L7:BOTTOM=L7 |
| SAS_SMART_R_RX | OTHERS | BUS | 4 | 5 | 5 | 10 | 5 | 14 | 6 | 10 | 12 | 12 | 12 | 12 |  | 50 Ohms | TOP=L2:L3=L2/L4:L6=L5/L7:BOTTOM=L7 |
| SAS_SMART_R_RX | OTHERS | BUS | 5 | 5 | 5 | 10 | 5 | 14 | 6 | 10 | 12 | 12 | 12 | 12 |  | 50 Ohms | TOP=L2:L3=L2/L4:L6=L5/L7:BOTTOM=L7 |
| SAS_SMART_R_RX | OTHERS | BUS | 6 | 5 | 5 | 10 | 5 | 14 | 6 | 10 | 12 | 12 | 12 | 12 |  | 50 Ohms | TOP=L2:L3=L2/L4:L6=L5/L7:BOTTOM=L7 |
| SAS_SMART_R_RX | OTHERS | BUS | 7 | 5 | 5 | 10 | 5 | 14 | 6 | 10 | 12 | 12 | 12 | 12 |  | 50 Ohms | TOP=L2:L3=L2/L4:L6=L5/L7:BOTTOM=L7 |
| SAS_SMART_R_RX | OTHERS | BUS | 8 | 4.75 | 5 | 10 | 5 | 14 | 6 | 9.5 | 12 | 12 | 12 | 12 |  | 50 Ohms | TOP=L2:L3=L2/L4:L6=L5/L7:BOTTOM=L7 |
| SAS_SMART_R_TX | OTHERS | BUS | 1 | 4.75 | 5 | 10 | 5 | 14 | 6 | 9.5 | 12 | 12 | 12 | 12 |  | 50 Ohms | TOP=L2:L3=L2/L4:L6=L5/L7:BOTTOM=L7 |
| SAS_SMART_R_TX | OTHERS | BUS | 2 | 5 | 5 | 10 | 5 | 14 | 6 | 10 | 12 | 12 | 12 | 12 |  | 50 Ohms | TOP=L2:L3=L2/L4:L6=L5/L7:BOTTOM=L7 |
| SAS_SMART_R_TX | OTHERS | BUS | 3 | 5 | 5 | 10 | 5 | 14 | 6 | 10 | 12 | 12 | 12 | 12 |  | 50 Ohms | TOP=L2:L3=L2/L4:L6=L5/L7:BOTTOM=L7 |
| SAS_SMART_R_TX | OTHERS | BUS | 4 | 5 | 5 | 10 | 5 | 14 | 6 | 10 | 12 | 12 | 12 | 12 |  | 50 Ohms | TOP=L2:L3=L2/L4:L6=L5/L7:BOTTOM=L7 |
| SAS_SMART_R_TX | OTHERS | BUS | 5 | 5 | 5 | 10 | 5 | 14 | 6 | 10 | 12 | 12 | 12 | 12 |  | 50 Ohms | TOP=L2:L3=L2/L4:L6=L5/L7:BOTTOM=L7 |
| SAS_SMART_R_TX | OTHERS | BUS | 6 | 5 | 5 | 10 | 5 | 14 | 6 | 10 | 12 | 12 | 12 | 12 |  | 50 Ohms | TOP=L2:L3=L2/L4:L6=L5/L7:BOTTOM=L7 |
| SAS_SMART_R_TX | OTHERS | BUS | 7 | 5 | 5 | 10 | 5 | 14 | 6 | 10 | 12 | 12 | 12 | 12 |  | 50 Ohms | TOP=L2:L3=L2/L4:L6=L5/L7:BOTTOM=L7 |
| SAS_SMART_R_TX | OTHERS | BUS | 8 | 4.75 | 5 | 10 | 5 | 14 | 6 | 9.5 | 12 | 12 | 12 | 12 |  | 50 Ohms | TOP=L2:L3=L2/L4:L6=L5/L7:BOTTOM=L7 |
| SEC_RST_N_R | OTHERS | BUS | 1 | 4.75 | 5 | 10 | 5 | 14 | 6 | 9.5 | 12 | 12 | 12 | 12 |  | 50 Ohms | TOP=L2:L3=L2/L4:L6=L5/L7:BOTTOM=L7 |
| SEC_RST_N_R | OTHERS | BUS | 2 | 5 | 5 | 10 | 5 | 14 | 6 | 10 | 12 | 12 | 12 | 12 |  | 50 Ohms | TOP=L2:L3=L2/L4:L6=L5/L7:BOTTOM=L7 |
| SEC_RST_N_R | OTHERS | BUS | 3 | 5 | 5 | 10 | 5 | 14 | 6 | 10 | 12 | 12 | 12 | 12 |  | 50 Ohms | TOP=L2:L3=L2/L4:L6=L5/L7:BOTTOM=L7 |
| SEC_RST_N_R | OTHERS | BUS | 4 | 5 | 5 | 10 | 5 | 14 | 6 | 10 | 12 | 12 | 12 | 12 |  | 50 Ohms | TOP=L2:L3=L2/L4:L6=L5/L7:BOTTOM=L7 |
| SEC_RST_N_R | OTHERS | BUS | 5 | 5 | 5 | 10 | 5 | 14 | 6 | 10 | 12 | 12 | 12 | 12 |  | 50 Ohms | TOP=L2:L3=L2/L4:L6=L5/L7:BOTTOM=L7 |
| SEC_RST_N_R | OTHERS | BUS | 6 | 5 | 5 | 10 | 5 | 14 | 6 | 10 | 12 | 12 | 12 | 12 |  | 50 Ohms | TOP=L2:L3=L2/L4:L6=L5/L7:BOTTOM=L7 |
| SEC_RST_N_R | OTHERS | BUS | 7 | 5 | 5 | 10 | 5 | 14 | 6 | 10 | 12 | 12 | 12 | 12 |  | 50 Ohms | TOP=L2:L3=L2/L4:L6=L5/L7:BOTTOM=L7 |
| SEC_RST_N_R | OTHERS | BUS | 8 | 4.75 | 5 | 10 | 5 | 14 | 6 | 9.5 | 12 | 12 | 12 | 12 |  | 50 Ohms | TOP=L2:L3=L2/L4:L6=L5/L7:BOTTOM=L7 |
| SEC_SPI_HOLD_N | OTHERS | BUS | 1 | 4.75 | 5 | 10 | 5 | 14 | 6 | 9.5 | 12 | 12 | 12 | 12 |  | 50 Ohms | TOP=L2:L3=L2/L4:L6=L5/L7:BOTTOM=L7 |
| SEC_SPI_HOLD_N | OTHERS | BUS | 2 | 5 | 5 | 10 | 5 | 14 | 6 | 10 | 12 | 12 | 12 | 12 |  | 50 Ohms | TOP=L2:L3=L2/L4:L6=L5/L7:BOTTOM=L7 |
| SEC_SPI_HOLD_N | OTHERS | BUS | 3 | 5 | 5 | 10 | 5 | 14 | 6 | 10 | 12 | 12 | 12 | 12 |  | 50 Ohms | TOP=L2:L3=L2/L4:L6=L5/L7:BOTTOM=L7 |
| SEC_SPI_HOLD_N | OTHERS | BUS | 4 | 5 | 5 | 10 | 5 | 14 | 6 | 10 | 12 | 12 | 12 | 12 |  | 50 Ohms | TOP=L2:L3=L2/L4:L6=L5/L7:BOTTOM=L7 |
| SEC_SPI_HOLD_N | OTHERS | BUS | 5 | 5 | 5 | 10 | 5 | 14 | 6 | 10 | 12 | 12 | 12 | 12 |  | 50 Ohms | TOP=L2:L3=L2/L4:L6=L5/L7:BOTTOM=L7 |
| SEC_SPI_HOLD_N | OTHERS | BUS | 6 | 5 | 5 | 10 | 5 | 14 | 6 | 10 | 12 | 12 | 12 | 12 |  | 50 Ohms | TOP=L2:L3=L2/L4:L6=L5/L7:BOTTOM=L7 |
| SEC_SPI_HOLD_N | OTHERS | BUS | 7 | 5 | 5 | 10 | 5 | 14 | 6 | 10 | 12 | 12 | 12 | 12 |  | 50 Ohms | TOP=L2:L3=L2/L4:L6=L5/L7:BOTTOM=L7 |
| SEC_SPI_HOLD_N | OTHERS | BUS | 8 | 4.75 | 5 | 10 | 5 | 14 | 6 | 9.5 | 12 | 12 | 12 | 12 |  | 50 Ohms | TOP=L2:L3=L2/L4:L6=L5/L7:BOTTOM=L7 |
| SHUTDOWN_RELEASE | OTHERS | BUS | 1 | 4.75 | 5 | 10 | 5 | 14 | 6 | 9.5 | 12 | 12 | 12 | 12 |  | 50 Ohms | TOP=L2:L3=L2/L4:L6=L5/L7:BOTTOM=L7 |
| SHUTDOWN_RELEASE | OTHERS | BUS | 2 | 5 | 5 | 10 | 5 | 14 | 6 | 10 | 12 | 12 | 12 | 12 |  | 50 Ohms | TOP=L2:L3=L2/L4:L6=L5/L7:BOTTOM=L7 |
| SHUTDOWN_RELEASE | OTHERS | BUS | 3 | 5 | 5 | 10 | 5 | 14 | 6 | 10 | 12 | 12 | 12 | 12 |  | 50 Ohms | TOP=L2:L3=L2/L4:L6=L5/L7:BOTTOM=L7 |
| SHUTDOWN_RELEASE | OTHERS | BUS | 4 | 5 | 5 | 10 | 5 | 14 | 6 | 10 | 12 | 12 | 12 | 12 |  | 50 Ohms | TOP=L2:L3=L2/L4:L6=L5/L7:BOTTOM=L7 |
| SHUTDOWN_RELEASE | OTHERS | BUS | 5 | 5 | 5 | 10 | 5 | 14 | 6 | 10 | 12 | 12 | 12 | 12 |  | 50 Ohms | TOP=L2:L3=L2/L4:L6=L5/L7:BOTTOM=L7 |
| SHUTDOWN_RELEASE | OTHERS | BUS | 6 | 5 | 5 | 10 | 5 | 14 | 6 | 10 | 12 | 12 | 12 | 12 |  | 50 Ohms | TOP=L2:L3=L2/L4:L6=L5/L7:BOTTOM=L7 |
| SHUTDOWN_RELEASE | OTHERS | BUS | 7 | 5 | 5 | 10 | 5 | 14 | 6 | 10 | 12 | 12 | 12 | 12 |  | 50 Ohms | TOP=L2:L3=L2/L4:L6=L5/L7:BOTTOM=L7 |
| SHUTDOWN_RELEASE | OTHERS | BUS | 8 | 4.75 | 5 | 10 | 5 | 14 | 6 | 9.5 | 12 | 12 | 12 | 12 |  | 50 Ohms | TOP=L2:L3=L2/L4:L6=L5/L7:BOTTOM=L7 |
| SLED29_A | OTHERS | BUS | 1 | 4.75 | 5 | 10 | 5 | 14 | 6 | 9.5 | 12 | 12 | 12 | 12 |  | 50 Ohms | TOP=L2:L3=L2/L4:L6=L5/L7:BOTTOM=L7 |
| SLED29_A | OTHERS | BUS | 2 | 5 | 5 | 10 | 5 | 14 | 6 | 10 | 12 | 12 | 12 | 12 |  | 50 Ohms | TOP=L2:L3=L2/L4:L6=L5/L7:BOTTOM=L7 |
| SLED29_A | OTHERS | BUS | 3 | 5 | 5 | 10 | 5 | 14 | 6 | 10 | 12 | 12 | 12 | 12 |  | 50 Ohms | TOP=L2:L3=L2/L4:L6=L5/L7:BOTTOM=L7 |
| SLED29_A | OTHERS | BUS | 4 | 5 | 5 | 10 | 5 | 14 | 6 | 10 | 12 | 12 | 12 | 12 |  | 50 Ohms | TOP=L2:L3=L2/L4:L6=L5/L7:BOTTOM=L7 |
| SLED29_A | OTHERS | BUS | 5 | 5 | 5 | 10 | 5 | 14 | 6 | 10 | 12 | 12 | 12 | 12 |  | 50 Ohms | TOP=L2:L3=L2/L4:L6=L5/L7:BOTTOM=L7 |
| SLED29_A | OTHERS | BUS | 6 | 5 | 5 | 10 | 5 | 14 | 6 | 10 | 12 | 12 | 12 | 12 |  | 50 Ohms | TOP=L2:L3=L2/L4:L6=L5/L7:BOTTOM=L7 |
| SLED29_A | OTHERS | BUS | 7 | 5 | 5 | 10 | 5 | 14 | 6 | 10 | 12 | 12 | 12 | 12 |  | 50 Ohms | TOP=L2:L3=L2/L4:L6=L5/L7:BOTTOM=L7 |
| SLED29_A | OTHERS | BUS | 8 | 4.75 | 5 | 10 | 5 | 14 | 6 | 9.5 | 12 | 12 | 12 | 12 |  | 50 Ohms | TOP=L2:L3=L2/L4:L6=L5/L7:BOTTOM=L7 |
| SLIDE_SW_PMC_RST# | OTHERS | BUS | 1 | 4.75 | 5 | 10 | 5 | 14 | 6 | 9.5 | 12 | 12 | 12 | 12 |  | 50 Ohms | TOP=L2:L3=L2/L4:L6=L5/L7:BOTTOM=L7 |
| SLIDE_SW_PMC_RST# | OTHERS | BUS | 2 | 5 | 5 | 10 | 5 | 14 | 6 | 10 | 12 | 12 | 12 | 12 |  | 50 Ohms | TOP=L2:L3=L2/L4:L6=L5/L7:BOTTOM=L7 |
| SLIDE_SW_PMC_RST# | OTHERS | BUS | 3 | 5 | 5 | 10 | 5 | 14 | 6 | 10 | 12 | 12 | 12 | 12 |  | 50 Ohms | TOP=L2:L3=L2/L4:L6=L5/L7:BOTTOM=L7 |
| SLIDE_SW_PMC_RST# | OTHERS | BUS | 4 | 5 | 5 | 10 | 5 | 14 | 6 | 10 | 12 | 12 | 12 | 12 |  | 50 Ohms | TOP=L2:L3=L2/L4:L6=L5/L7:BOTTOM=L7 |
| SLIDE_SW_PMC_RST# | OTHERS | BUS | 5 | 5 | 5 | 10 | 5 | 14 | 6 | 10 | 12 | 12 | 12 | 12 |  | 50 Ohms | TOP=L2:L3=L2/L4:L6=L5/L7:BOTTOM=L7 |
| SLIDE_SW_PMC_RST# | OTHERS | BUS | 6 | 5 | 5 | 10 | 5 | 14 | 6 | 10 | 12 | 12 | 12 | 12 |  | 50 Ohms | TOP=L2:L3=L2/L4:L6=L5/L7:BOTTOM=L7 |
| SLIDE_SW_PMC_RST# | OTHERS | BUS | 7 | 5 | 5 | 10 | 5 | 14 | 6 | 10 | 12 | 12 | 12 | 12 |  | 50 Ohms | TOP=L2:L3=L2/L4:L6=L5/L7:BOTTOM=L7 |
| SLIDE_SW_PMC_RST# | OTHERS | BUS | 8 | 4.75 | 5 | 10 | 5 | 14 | 6 | 9.5 | 12 | 12 | 12 | 12 |  | 50 Ohms | TOP=L2:L3=L2/L4:L6=L5/L7:BOTTOM=L7 |
| SMART_UART_EN | OTHERS | BUS | 1 | 4.75 | 5 | 10 | 5 | 14 | 6 | 9.5 | 12 | 12 | 12 | 12 |  | 50 Ohms | TOP=L2:L3=L2/L4:L6=L5/L7:BOTTOM=L7 |
| SMART_UART_EN | OTHERS | BUS | 2 | 5 | 5 | 10 | 5 | 14 | 6 | 10 | 12 | 12 | 12 | 12 |  | 50 Ohms | TOP=L2:L3=L2/L4:L6=L5/L7:BOTTOM=L7 |
| SMART_UART_EN | OTHERS | BUS | 3 | 5 | 5 | 10 | 5 | 14 | 6 | 10 | 12 | 12 | 12 | 12 |  | 50 Ohms | TOP=L2:L3=L2/L4:L6=L5/L7:BOTTOM=L7 |
| SMART_UART_EN | OTHERS | BUS | 4 | 5 | 5 | 10 | 5 | 14 | 6 | 10 | 12 | 12 | 12 | 12 |  | 50 Ohms | TOP=L2:L3=L2/L4:L6=L5/L7:BOTTOM=L7 |
| SMART_UART_EN | OTHERS | BUS | 5 | 5 | 5 | 10 | 5 | 14 | 6 | 10 | 12 | 12 | 12 | 12 |  | 50 Ohms | TOP=L2:L3=L2/L4:L6=L5/L7:BOTTOM=L7 |
| SMART_UART_EN | OTHERS | BUS | 6 | 5 | 5 | 10 | 5 | 14 | 6 | 10 | 12 | 12 | 12 | 12 |  | 50 Ohms | TOP=L2:L3=L2/L4:L6=L5/L7:BOTTOM=L7 |
| SMART_UART_EN | OTHERS | BUS | 7 | 5 | 5 | 10 | 5 | 14 | 6 | 10 | 12 | 12 | 12 | 12 |  | 50 Ohms | TOP=L2:L3=L2/L4:L6=L5/L7:BOTTOM=L7 |
| SMART_UART_EN | OTHERS | BUS | 8 | 4.75 | 5 | 10 | 5 | 14 | 6 | 9.5 | 12 | 12 | 12 | 12 |  | 50 Ohms | TOP=L2:L3=L2/L4:L6=L5/L7:BOTTOM=L7 |
| SPI_FLASH_SELECT | OTHERS | BUS | 1 | 4.75 | 5 | 10 | 5 | 14 | 6 | 9.5 | 12 | 12 | 12 | 12 |  | 50 Ohms | TOP=L2:L3=L2/L4:L6=L5/L7:BOTTOM=L7 |
| SPI_FLASH_SELECT | OTHERS | BUS | 2 | 5 | 5 | 10 | 5 | 14 | 6 | 10 | 12 | 12 | 12 | 12 |  | 50 Ohms | TOP=L2:L3=L2/L4:L6=L5/L7:BOTTOM=L7 |
| SPI_FLASH_SELECT | OTHERS | BUS | 3 | 5 | 5 | 10 | 5 | 14 | 6 | 10 | 12 | 12 | 12 | 12 |  | 50 Ohms | TOP=L2:L3=L2/L4:L6=L5/L7:BOTTOM=L7 |
| SPI_FLASH_SELECT | OTHERS | BUS | 4 | 5 | 5 | 10 | 5 | 14 | 6 | 10 | 12 | 12 | 12 | 12 |  | 50 Ohms | TOP=L2:L3=L2/L4:L6=L5/L7:BOTTOM=L7 |
| SPI_FLASH_SELECT | OTHERS | BUS | 5 | 5 | 5 | 10 | 5 | 14 | 6 | 10 | 12 | 12 | 12 | 12 |  | 50 Ohms | TOP=L2:L3=L2/L4:L6=L5/L7:BOTTOM=L7 |
| SPI_FLASH_SELECT | OTHERS | BUS | 6 | 5 | 5 | 10 | 5 | 14 | 6 | 10 | 12 | 12 | 12 | 12 |  | 50 Ohms | TOP=L2:L3=L2/L4:L6=L5/L7:BOTTOM=L7 |
| SPI_FLASH_SELECT | OTHERS | BUS | 7 | 5 | 5 | 10 | 5 | 14 | 6 | 10 | 12 | 12 | 12 | 12 |  | 50 Ohms | TOP=L2:L3=L2/L4:L6=L5/L7:BOTTOM=L7 |
| SPI_FLASH_SELECT | OTHERS | BUS | 8 | 4.75 | 5 | 10 | 5 | 14 | 6 | 9.5 | 12 | 12 | 12 | 12 |  | 50 Ohms | TOP=L2:L3=L2/L4:L6=L5/L7:BOTTOM=L7 |
| SPI_FLASH_SELECT_R | OTHERS | BUS | 1 | 4.75 | 5 | 10 | 5 | 14 | 6 | 9.5 | 12 | 12 | 12 | 12 |  | 50 Ohms | TOP=L2:L3=L2/L4:L6=L5/L7:BOTTOM=L7 |
| SPI_FLASH_SELECT_R | OTHERS | BUS | 2 | 5 | 5 | 10 | 5 | 14 | 6 | 10 | 12 | 12 | 12 | 12 |  | 50 Ohms | TOP=L2:L3=L2/L4:L6=L5/L7:BOTTOM=L7 |
| SPI_FLASH_SELECT_R | OTHERS | BUS | 3 | 5 | 5 | 10 | 5 | 14 | 6 | 10 | 12 | 12 | 12 | 12 |  | 50 Ohms | TOP=L2:L3=L2/L4:L6=L5/L7:BOTTOM=L7 |
| SPI_FLASH_SELECT_R | OTHERS | BUS | 4 | 5 | 5 | 10 | 5 | 14 | 6 | 10 | 12 | 12 | 12 | 12 |  | 50 Ohms | TOP=L2:L3=L2/L4:L6=L5/L7:BOTTOM=L7 |
| SPI_FLASH_SELECT_R | OTHERS | BUS | 5 | 5 | 5 | 10 | 5 | 14 | 6 | 10 | 12 | 12 | 12 | 12 |  | 50 Ohms | TOP=L2:L3=L2/L4:L6=L5/L7:BOTTOM=L7 |
| SPI_FLASH_SELECT_R | OTHERS | BUS | 6 | 5 | 5 | 10 | 5 | 14 | 6 | 10 | 12 | 12 | 12 | 12 |  | 50 Ohms | TOP=L2:L3=L2/L4:L6=L5/L7:BOTTOM=L7 |
| SPI_FLASH_SELECT_R | OTHERS | BUS | 7 | 5 | 5 | 10 | 5 | 14 | 6 | 10 | 12 | 12 | 12 | 12 |  | 50 Ohms | TOP=L2:L3=L2/L4:L6=L5/L7:BOTTOM=L7 |
| SPI_FLASH_SELECT_R | OTHERS | BUS | 8 | 4.75 | 5 | 10 | 5 | 14 | 6 | 9.5 | 12 | 12 | 12 | 12 |  | 50 Ohms | TOP=L2:L3=L2/L4:L6=L5/L7:BOTTOM=L7 |
| SSD_ATNLED#0 | OTHERS | BUS | 1 | 4.75 | 5 | 10 | 5 | 14 | 6 | 9.5 | 12 | 12 | 12 | 12 |  | 50 Ohms | TOP=L2:L3=L2/L4:L6=L5/L7:BOTTOM=L7 |
| SSD_ATNLED#0 | OTHERS | BUS | 2 | 5 | 5 | 10 | 5 | 14 | 6 | 10 | 12 | 12 | 12 | 12 |  | 50 Ohms | TOP=L2:L3=L2/L4:L6=L5/L7:BOTTOM=L7 |
| SSD_ATNLED#0 | OTHERS | BUS | 3 | 5 | 5 | 10 | 5 | 14 | 6 | 10 | 12 | 12 | 12 | 12 |  | 50 Ohms | TOP=L2:L3=L2/L4:L6=L5/L7:BOTTOM=L7 |
| SSD_ATNLED#0 | OTHERS | BUS | 4 | 5 | 5 | 10 | 5 | 14 | 6 | 10 | 12 | 12 | 12 | 12 |  | 50 Ohms | TOP=L2:L3=L2/L4:L6=L5/L7:BOTTOM=L7 |
| SSD_ATNLED#0 | OTHERS | BUS | 5 | 5 | 5 | 10 | 5 | 14 | 6 | 10 | 12 | 12 | 12 | 12 |  | 50 Ohms | TOP=L2:L3=L2/L4:L6=L5/L7:BOTTOM=L7 |
| SSD_ATNLED#0 | OTHERS | BUS | 6 | 5 | 5 | 10 | 5 | 14 | 6 | 10 | 12 | 12 | 12 | 12 |  | 50 Ohms | TOP=L2:L3=L2/L4:L6=L5/L7:BOTTOM=L7 |
| SSD_ATNLED#0 | OTHERS | BUS | 7 | 5 | 5 | 10 | 5 | 14 | 6 | 10 | 12 | 12 | 12 | 12 |  | 50 Ohms | TOP=L2:L3=L2/L4:L6=L5/L7:BOTTOM=L7 |
| SSD_ATNLED#0 | OTHERS | BUS | 8 | 4.75 | 5 | 10 | 5 | 14 | 6 | 9.5 | 12 | 12 | 12 | 12 |  | 50 Ohms | TOP=L2:L3=L2/L4:L6=L5/L7:BOTTOM=L7 |
| SSD_ATNLED#0_R | OTHERS | BUS | 1 | 4.75 | 5 | 10 | 5 | 14 | 6 | 9.5 | 12 | 12 | 12 | 12 |  | 50 Ohms | TOP=L2:L3=L2/L4:L6=L5/L7:BOTTOM=L7 |
| SSD_ATNLED#0_R | OTHERS | BUS | 2 | 5 | 5 | 10 | 5 | 14 | 6 | 10 | 12 | 12 | 12 | 12 |  | 50 Ohms | TOP=L2:L3=L2/L4:L6=L5/L7:BOTTOM=L7 |
| SSD_ATNLED#0_R | OTHERS | BUS | 3 | 5 | 5 | 10 | 5 | 14 | 6 | 10 | 12 | 12 | 12 | 12 |  | 50 Ohms | TOP=L2:L3=L2/L4:L6=L5/L7:BOTTOM=L7 |
| SSD_ATNLED#0_R | OTHERS | BUS | 4 | 5 | 5 | 10 | 5 | 14 | 6 | 10 | 12 | 12 | 12 | 12 |  | 50 Ohms | TOP=L2:L3=L2/L4:L6=L5/L7:BOTTOM=L7 |
| SSD_ATNLED#0_R | OTHERS | BUS | 5 | 5 | 5 | 10 | 5 | 14 | 6 | 10 | 12 | 12 | 12 | 12 |  | 50 Ohms | TOP=L2:L3=L2/L4:L6=L5/L7:BOTTOM=L7 |
| SSD_ATNLED#0_R | OTHERS | BUS | 6 | 5 | 5 | 10 | 5 | 14 | 6 | 10 | 12 | 12 | 12 | 12 |  | 50 Ohms | TOP=L2:L3=L2/L4:L6=L5/L7:BOTTOM=L7 |
| SSD_ATNLED#0_R | OTHERS | BUS | 7 | 5 | 5 | 10 | 5 | 14 | 6 | 10 | 12 | 12 | 12 | 12 |  | 50 Ohms | TOP=L2:L3=L2/L4:L6=L5/L7:BOTTOM=L7 |
| SSD_ATNLED#0_R | OTHERS | BUS | 8 | 4.75 | 5 | 10 | 5 | 14 | 6 | 9.5 | 12 | 12 | 12 | 12 |  | 50 Ohms | TOP=L2:L3=L2/L4:L6=L5/L7:BOTTOM=L7 |
| SSD_ATNLED#1 | OTHERS | BUS | 1 | 4.75 | 5 | 10 | 5 | 14 | 6 | 9.5 | 12 | 12 | 12 | 12 |  | 50 Ohms | TOP=L2:L3=L2/L4:L6=L5/L7:BOTTOM=L7 |
| SSD_ATNLED#1 | OTHERS | BUS | 2 | 5 | 5 | 10 | 5 | 14 | 6 | 10 | 12 | 12 | 12 | 12 |  | 50 Ohms | TOP=L2:L3=L2/L4:L6=L5/L7:BOTTOM=L7 |
| SSD_ATNLED#1 | OTHERS | BUS | 3 | 5 | 5 | 10 | 5 | 14 | 6 | 10 | 12 | 12 | 12 | 12 |  | 50 Ohms | TOP=L2:L3=L2/L4:L6=L5/L7:BOTTOM=L7 |
| SSD_ATNLED#1 | OTHERS | BUS | 4 | 5 | 5 | 10 | 5 | 14 | 6 | 10 | 12 | 12 | 12 | 12 |  | 50 Ohms | TOP=L2:L3=L2/L4:L6=L5/L7:BOTTOM=L7 |
| SSD_ATNLED#1 | OTHERS | BUS | 5 | 5 | 5 | 10 | 5 | 14 | 6 | 10 | 12 | 12 | 12 | 12 |  | 50 Ohms | TOP=L2:L3=L2/L4:L6=L5/L7:BOTTOM=L7 |
| SSD_ATNLED#1 | OTHERS | BUS | 6 | 5 | 5 | 10 | 5 | 14 | 6 | 10 | 12 | 12 | 12 | 12 |  | 50 Ohms | TOP=L2:L3=L2/L4:L6=L5/L7:BOTTOM=L7 |
| SSD_ATNLED#1 | OTHERS | BUS | 7 | 5 | 5 | 10 | 5 | 14 | 6 | 10 | 12 | 12 | 12 | 12 |  | 50 Ohms | TOP=L2:L3=L2/L4:L6=L5/L7:BOTTOM=L7 |
| SSD_ATNLED#1 | OTHERS | BUS | 8 | 4.75 | 5 | 10 | 5 | 14 | 6 | 9.5 | 12 | 12 | 12 | 12 |  | 50 Ohms | TOP=L2:L3=L2/L4:L6=L5/L7:BOTTOM=L7 |
| SSD_ATNLED#1_R | OTHERS | BUS | 1 | 4.75 | 5 | 10 | 5 | 14 | 6 | 9.5 | 12 | 12 | 12 | 12 |  | 50 Ohms | TOP=L2:L3=L2/L4:L6=L5/L7:BOTTOM=L7 |
| SSD_ATNLED#1_R | OTHERS | BUS | 2 | 5 | 5 | 10 | 5 | 14 | 6 | 10 | 12 | 12 | 12 | 12 |  | 50 Ohms | TOP=L2:L3=L2/L4:L6=L5/L7:BOTTOM=L7 |
| SSD_ATNLED#1_R | OTHERS | BUS | 3 | 5 | 5 | 10 | 5 | 14 | 6 | 10 | 12 | 12 | 12 | 12 |  | 50 Ohms | TOP=L2:L3=L2/L4:L6=L5/L7:BOTTOM=L7 |
| SSD_ATNLED#1_R | OTHERS | BUS | 4 | 5 | 5 | 10 | 5 | 14 | 6 | 10 | 12 | 12 | 12 | 12 |  | 50 Ohms | TOP=L2:L3=L2/L4:L6=L5/L7:BOTTOM=L7 |
| SSD_ATNLED#1_R | OTHERS | BUS | 5 | 5 | 5 | 10 | 5 | 14 | 6 | 10 | 12 | 12 | 12 | 12 |  | 50 Ohms | TOP=L2:L3=L2/L4:L6=L5/L7:BOTTOM=L7 |
| SSD_ATNLED#1_R | OTHERS | BUS | 6 | 5 | 5 | 10 | 5 | 14 | 6 | 10 | 12 | 12 | 12 | 12 |  | 50 Ohms | TOP=L2:L3=L2/L4:L6=L5/L7:BOTTOM=L7 |
| SSD_ATNLED#1_R | OTHERS | BUS | 7 | 5 | 5 | 10 | 5 | 14 | 6 | 10 | 12 | 12 | 12 | 12 |  | 50 Ohms | TOP=L2:L3=L2/L4:L6=L5/L7:BOTTOM=L7 |
| SSD_ATNLED#1_R | OTHERS | BUS | 8 | 4.75 | 5 | 10 | 5 | 14 | 6 | 9.5 | 12 | 12 | 12 | 12 |  | 50 Ohms | TOP=L2:L3=L2/L4:L6=L5/L7:BOTTOM=L7 |
| SSD_ATNLED#10 | OTHERS | BUS | 1 | 4.75 | 5 | 10 | 5 | 14 | 6 | 9.5 | 12 | 12 | 12 | 12 |  | 50 Ohms | TOP=L2:L3=L2/L4:L6=L5/L7:BOTTOM=L7 |
| SSD_ATNLED#10 | OTHERS | BUS | 2 | 5 | 5 | 10 | 5 | 14 | 6 | 10 | 12 | 12 | 12 | 12 |  | 50 Ohms | TOP=L2:L3=L2/L4:L6=L5/L7:BOTTOM=L7 |
| SSD_ATNLED#10 | OTHERS | BUS | 3 | 5 | 5 | 10 | 5 | 14 | 6 | 10 | 12 | 12 | 12 | 12 |  | 50 Ohms | TOP=L2:L3=L2/L4:L6=L5/L7:BOTTOM=L7 |
| SSD_ATNLED#10 | OTHERS | BUS | 4 | 5 | 5 | 10 | 5 | 14 | 6 | 10 | 12 | 12 | 12 | 12 |  | 50 Ohms | TOP=L2:L3=L2/L4:L6=L5/L7:BOTTOM=L7 |
| SSD_ATNLED#10 | OTHERS | BUS | 5 | 5 | 5 | 10 | 5 | 14 | 6 | 10 | 12 | 12 | 12 | 12 |  | 50 Ohms | TOP=L2:L3=L2/L4:L6=L5/L7:BOTTOM=L7 |
| SSD_ATNLED#10 | OTHERS | BUS | 6 | 5 | 5 | 10 | 5 | 14 | 6 | 10 | 12 | 12 | 12 | 12 |  | 50 Ohms | TOP=L2:L3=L2/L4:L6=L5/L7:BOTTOM=L7 |
| SSD_ATNLED#10 | OTHERS | BUS | 7 | 5 | 5 | 10 | 5 | 14 | 6 | 10 | 12 | 12 | 12 | 12 |  | 50 Ohms | TOP=L2:L3=L2/L4:L6=L5/L7:BOTTOM=L7 |
| SSD_ATNLED#10 | OTHERS | BUS | 8 | 4.75 | 5 | 10 | 5 | 14 | 6 | 9.5 | 12 | 12 | 12 | 12 |  | 50 Ohms | TOP=L2:L3=L2/L4:L6=L5/L7:BOTTOM=L7 |
| SSD_ATNLED#10_R | OTHERS | BUS | 1 | 4.75 | 5 | 10 | 5 | 14 | 6 | 9.5 | 12 | 12 | 12 | 12 |  | 50 Ohms | TOP=L2:L3=L2/L4:L6=L5/L7:BOTTOM=L7 |
| SSD_ATNLED#10_R | OTHERS | BUS | 2 | 5 | 5 | 10 | 5 | 14 | 6 | 10 | 12 | 12 | 12 | 12 |  | 50 Ohms | TOP=L2:L3=L2/L4:L6=L5/L7:BOTTOM=L7 |
| SSD_ATNLED#10_R | OTHERS | BUS | 3 | 5 | 5 | 10 | 5 | 14 | 6 | 10 | 12 | 12 | 12 | 12 |  | 50 Ohms | TOP=L2:L3=L2/L4:L6=L5/L7:BOTTOM=L7 |
| SSD_ATNLED#10_R | OTHERS | BUS | 4 | 5 | 5 | 10 | 5 | 14 | 6 | 10 | 12 | 12 | 12 | 12 |  | 50 Ohms | TOP=L2:L3=L2/L4:L6=L5/L7:BOTTOM=L7 |
| SSD_ATNLED#10_R | OTHERS | BUS | 5 | 5 | 5 | 10 | 5 | 14 | 6 | 10 | 12 | 12 | 12 | 12 |  | 50 Ohms | TOP=L2:L3=L2/L4:L6=L5/L7:BOTTOM=L7 |
| SSD_ATNLED#10_R | OTHERS | BUS | 6 | 5 | 5 | 10 | 5 | 14 | 6 | 10 | 12 | 12 | 12 | 12 |  | 50 Ohms | TOP=L2:L3=L2/L4:L6=L5/L7:BOTTOM=L7 |
| SSD_ATNLED#10_R | OTHERS | BUS | 7 | 5 | 5 | 10 | 5 | 14 | 6 | 10 | 12 | 12 | 12 | 12 |  | 50 Ohms | TOP=L2:L3=L2/L4:L6=L5/L7:BOTTOM=L7 |
| SSD_ATNLED#10_R | OTHERS | BUS | 8 | 4.75 | 5 | 10 | 5 | 14 | 6 | 9.5 | 12 | 12 | 12 | 12 |  | 50 Ohms | TOP=L2:L3=L2/L4:L6=L5/L7:BOTTOM=L7 |
| SSD_ATNLED#11 | OTHERS | BUS | 1 | 4.75 | 5 | 10 | 5 | 14 | 6 | 9.5 | 12 | 12 | 12 | 12 |  | 50 Ohms | TOP=L2:L3=L2/L4:L6=L5/L7:BOTTOM=L7 |
| SSD_ATNLED#11 | OTHERS | BUS | 2 | 5 | 5 | 10 | 5 | 14 | 6 | 10 | 12 | 12 | 12 | 12 |  | 50 Ohms | TOP=L2:L3=L2/L4:L6=L5/L7:BOTTOM=L7 |
| SSD_ATNLED#11 | OTHERS | BUS | 3 | 5 | 5 | 10 | 5 | 14 | 6 | 10 | 12 | 12 | 12 | 12 |  | 50 Ohms | TOP=L2:L3=L2/L4:L6=L5/L7:BOTTOM=L7 |
| SSD_ATNLED#11 | OTHERS | BUS | 4 | 5 | 5 | 10 | 5 | 14 | 6 | 10 | 12 | 12 | 12 | 12 |  | 50 Ohms | TOP=L2:L3=L2/L4:L6=L5/L7:BOTTOM=L7 |
| SSD_ATNLED#11 | OTHERS | BUS | 5 | 5 | 5 | 10 | 5 | 14 | 6 | 10 | 12 | 12 | 12 | 12 |  | 50 Ohms | TOP=L2:L3=L2/L4:L6=L5/L7:BOTTOM=L7 |
| SSD_ATNLED#11 | OTHERS | BUS | 6 | 5 | 5 | 10 | 5 | 14 | 6 | 10 | 12 | 12 | 12 | 12 |  | 50 Ohms | TOP=L2:L3=L2/L4:L6=L5/L7:BOTTOM=L7 |
| SSD_ATNLED#11 | OTHERS | BUS | 7 | 5 | 5 | 10 | 5 | 14 | 6 | 10 | 12 | 12 | 12 | 12 |  | 50 Ohms | TOP=L2:L3=L2/L4:L6=L5/L7:BOTTOM=L7 |
| SSD_ATNLED#11 | OTHERS | BUS | 8 | 4.75 | 5 | 10 | 5 | 14 | 6 | 9.5 | 12 | 12 | 12 | 12 |  | 50 Ohms | TOP=L2:L3=L2/L4:L6=L5/L7:BOTTOM=L7 |
| SSD_ATNLED#11_R | OTHERS | BUS | 1 | 4.75 | 5 | 10 | 5 | 14 | 6 | 9.5 | 12 | 12 | 12 | 12 |  | 50 Ohms | TOP=L2:L3=L2/L4:L6=L5/L7:BOTTOM=L7 |
| SSD_ATNLED#11_R | OTHERS | BUS | 2 | 5 | 5 | 10 | 5 | 14 | 6 | 10 | 12 | 12 | 12 | 12 |  | 50 Ohms | TOP=L2:L3=L2/L4:L6=L5/L7:BOTTOM=L7 |
| SSD_ATNLED#11_R | OTHERS | BUS | 3 | 5 | 5 | 10 | 5 | 14 | 6 | 10 | 12 | 12 | 12 | 12 |  | 50 Ohms | TOP=L2:L3=L2/L4:L6=L5/L7:BOTTOM=L7 |
| SSD_ATNLED#11_R | OTHERS | BUS | 4 | 5 | 5 | 10 | 5 | 14 | 6 | 10 | 12 | 12 | 12 | 12 |  | 50 Ohms | TOP=L2:L3=L2/L4:L6=L5/L7:BOTTOM=L7 |
| SSD_ATNLED#11_R | OTHERS | BUS | 5 | 5 | 5 | 10 | 5 | 14 | 6 | 10 | 12 | 12 | 12 | 12 |  | 50 Ohms | TOP=L2:L3=L2/L4:L6=L5/L7:BOTTOM=L7 |
| SSD_ATNLED#11_R | OTHERS | BUS | 6 | 5 | 5 | 10 | 5 | 14 | 6 | 10 | 12 | 12 | 12 | 12 |  | 50 Ohms | TOP=L2:L3=L2/L4:L6=L5/L7:BOTTOM=L7 |
| SSD_ATNLED#11_R | OTHERS | BUS | 7 | 5 | 5 | 10 | 5 | 14 | 6 | 10 | 12 | 12 | 12 | 12 |  | 50 Ohms | TOP=L2:L3=L2/L4:L6=L5/L7:BOTTOM=L7 |
| SSD_ATNLED#11_R | OTHERS | BUS | 8 | 4.75 | 5 | 10 | 5 | 14 | 6 | 9.5 | 12 | 12 | 12 | 12 |  | 50 Ohms | TOP=L2:L3=L2/L4:L6=L5/L7:BOTTOM=L7 |
| SSD_ATNLED#12 | OTHERS | BUS | 1 | 4.75 | 5 | 10 | 5 | 14 | 6 | 9.5 | 12 | 12 | 12 | 12 |  | 50 Ohms | TOP=L2:L3=L2/L4:L6=L5/L7:BOTTOM=L7 |
| SSD_ATNLED#12 | OTHERS | BUS | 2 | 5 | 5 | 10 | 5 | 14 | 6 | 10 | 12 | 12 | 12 | 12 |  | 50 Ohms | TOP=L2:L3=L2/L4:L6=L5/L7:BOTTOM=L7 |
| SSD_ATNLED#12 | OTHERS | BUS | 3 | 5 | 5 | 10 | 5 | 14 | 6 | 10 | 12 | 12 | 12 | 12 |  | 50 Ohms | TOP=L2:L3=L2/L4:L6=L5/L7:BOTTOM=L7 |
| SSD_ATNLED#12 | OTHERS | BUS | 4 | 5 | 5 | 10 | 5 | 14 | 6 | 10 | 12 | 12 | 12 | 12 |  | 50 Ohms | TOP=L2:L3=L2/L4:L6=L5/L7:BOTTOM=L7 |
| SSD_ATNLED#12 | OTHERS | BUS | 5 | 5 | 5 | 10 | 5 | 14 | 6 | 10 | 12 | 12 | 12 | 12 |  | 50 Ohms | TOP=L2:L3=L2/L4:L6=L5/L7:BOTTOM=L7 |
| SSD_ATNLED#12 | OTHERS | BUS | 6 | 5 | 5 | 10 | 5 | 14 | 6 | 10 | 12 | 12 | 12 | 12 |  | 50 Ohms | TOP=L2:L3=L2/L4:L6=L5/L7:BOTTOM=L7 |
| SSD_ATNLED#12 | OTHERS | BUS | 7 | 5 | 5 | 10 | 5 | 14 | 6 | 10 | 12 | 12 | 12 | 12 |  | 50 Ohms | TOP=L2:L3=L2/L4:L6=L5/L7:BOTTOM=L7 |
| SSD_ATNLED#12 | OTHERS | BUS | 8 | 4.75 | 5 | 10 | 5 | 14 | 6 | 9.5 | 12 | 12 | 12 | 12 |  | 50 Ohms | TOP=L2:L3=L2/L4:L6=L5/L7:BOTTOM=L7 |
| SSD_ATNLED#12_R | OTHERS | BUS | 1 | 4.75 | 5 | 10 | 5 | 14 | 6 | 9.5 | 12 | 12 | 12 | 12 |  | 50 Ohms | TOP=L2:L3=L2/L4:L6=L5/L7:BOTTOM=L7 |
| SSD_ATNLED#12_R | OTHERS | BUS | 2 | 5 | 5 | 10 | 5 | 14 | 6 | 10 | 12 | 12 | 12 | 12 |  | 50 Ohms | TOP=L2:L3=L2/L4:L6=L5/L7:BOTTOM=L7 |
| SSD_ATNLED#12_R | OTHERS | BUS | 3 | 5 | 5 | 10 | 5 | 14 | 6 | 10 | 12 | 12 | 12 | 12 |  | 50 Ohms | TOP=L2:L3=L2/L4:L6=L5/L7:BOTTOM=L7 |
| SSD_ATNLED#12_R | OTHERS | BUS | 4 | 5 | 5 | 10 | 5 | 14 | 6 | 10 | 12 | 12 | 12 | 12 |  | 50 Ohms | TOP=L2:L3=L2/L4:L6=L5/L7:BOTTOM=L7 |
| SSD_ATNLED#12_R | OTHERS | BUS | 5 | 5 | 5 | 10 | 5 | 14 | 6 | 10 | 12 | 12 | 12 | 12 |  | 50 Ohms | TOP=L2:L3=L2/L4:L6=L5/L7:BOTTOM=L7 |
| SSD_ATNLED#12_R | OTHERS | BUS | 6 | 5 | 5 | 10 | 5 | 14 | 6 | 10 | 12 | 12 | 12 | 12 |  | 50 Ohms | TOP=L2:L3=L2/L4:L6=L5/L7:BOTTOM=L7 |
| SSD_ATNLED#12_R | OTHERS | BUS | 7 | 5 | 5 | 10 | 5 | 14 | 6 | 10 | 12 | 12 | 12 | 12 |  | 50 Ohms | TOP=L2:L3=L2/L4:L6=L5/L7:BOTTOM=L7 |
| SSD_ATNLED#12_R | OTHERS | BUS | 8 | 4.75 | 5 | 10 | 5 | 14 | 6 | 9.5 | 12 | 12 | 12 | 12 |  | 50 Ohms | TOP=L2:L3=L2/L4:L6=L5/L7:BOTTOM=L7 |
| SSD_ATNLED#13 | OTHERS | BUS | 1 | 4.75 | 5 | 10 | 5 | 14 | 6 | 9.5 | 12 | 12 | 12 | 12 |  | 50 Ohms | TOP=L2:L3=L2/L4:L6=L5/L7:BOTTOM=L7 |
| SSD_ATNLED#13 | OTHERS | BUS | 2 | 5 | 5 | 10 | 5 | 14 | 6 | 10 | 12 | 12 | 12 | 12 |  | 50 Ohms | TOP=L2:L3=L2/L4:L6=L5/L7:BOTTOM=L7 |
| SSD_ATNLED#13 | OTHERS | BUS | 3 | 5 | 5 | 10 | 5 | 14 | 6 | 10 | 12 | 12 | 12 | 12 |  | 50 Ohms | TOP=L2:L3=L2/L4:L6=L5/L7:BOTTOM=L7 |
| SSD_ATNLED#13 | OTHERS | BUS | 4 | 5 | 5 | 10 | 5 | 14 | 6 | 10 | 12 | 12 | 12 | 12 |  | 50 Ohms | TOP=L2:L3=L2/L4:L6=L5/L7:BOTTOM=L7 |
| SSD_ATNLED#13 | OTHERS | BUS | 5 | 5 | 5 | 10 | 5 | 14 | 6 | 10 | 12 | 12 | 12 | 12 |  | 50 Ohms | TOP=L2:L3=L2/L4:L6=L5/L7:BOTTOM=L7 |
| SSD_ATNLED#13 | OTHERS | BUS | 6 | 5 | 5 | 10 | 5 | 14 | 6 | 10 | 12 | 12 | 12 | 12 |  | 50 Ohms | TOP=L2:L3=L2/L4:L6=L5/L7:BOTTOM=L7 |
| SSD_ATNLED#13 | OTHERS | BUS | 7 | 5 | 5 | 10 | 5 | 14 | 6 | 10 | 12 | 12 | 12 | 12 |  | 50 Ohms | TOP=L2:L3=L2/L4:L6=L5/L7:BOTTOM=L7 |
| SSD_ATNLED#13 | OTHERS | BUS | 8 | 4.75 | 5 | 10 | 5 | 14 | 6 | 9.5 | 12 | 12 | 12 | 12 |  | 50 Ohms | TOP=L2:L3=L2/L4:L6=L5/L7:BOTTOM=L7 |
| SSD_ATNLED#13_R | OTHERS | BUS | 1 | 4.75 | 5 | 10 | 5 | 14 | 6 | 9.5 | 12 | 12 | 12 | 12 |  | 50 Ohms | TOP=L2:L3=L2/L4:L6=L5/L7:BOTTOM=L7 |
| SSD_ATNLED#13_R | OTHERS | BUS | 2 | 5 | 5 | 10 | 5 | 14 | 6 | 10 | 12 | 12 | 12 | 12 |  | 50 Ohms | TOP=L2:L3=L2/L4:L6=L5/L7:BOTTOM=L7 |
| SSD_ATNLED#13_R | OTHERS | BUS | 3 | 5 | 5 | 10 | 5 | 14 | 6 | 10 | 12 | 12 | 12 | 12 |  | 50 Ohms | TOP=L2:L3=L2/L4:L6=L5/L7:BOTTOM=L7 |
| SSD_ATNLED#13_R | OTHERS | BUS | 4 | 5 | 5 | 10 | 5 | 14 | 6 | 10 | 12 | 12 | 12 | 12 |  | 50 Ohms | TOP=L2:L3=L2/L4:L6=L5/L7:BOTTOM=L7 |
| SSD_ATNLED#13_R | OTHERS | BUS | 5 | 5 | 5 | 10 | 5 | 14 | 6 | 10 | 12 | 12 | 12 | 12 |  | 50 Ohms | TOP=L2:L3=L2/L4:L6=L5/L7:BOTTOM=L7 |
| SSD_ATNLED#13_R | OTHERS | BUS | 6 | 5 | 5 | 10 | 5 | 14 | 6 | 10 | 12 | 12 | 12 | 12 |  | 50 Ohms | TOP=L2:L3=L2/L4:L6=L5/L7:BOTTOM=L7 |
| SSD_ATNLED#13_R | OTHERS | BUS | 7 | 5 | 5 | 10 | 5 | 14 | 6 | 10 | 12 | 12 | 12 | 12 |  | 50 Ohms | TOP=L2:L3=L2/L4:L6=L5/L7:BOTTOM=L7 |
| SSD_ATNLED#13_R | OTHERS | BUS | 8 | 4.75 | 5 | 10 | 5 | 14 | 6 | 9.5 | 12 | 12 | 12 | 12 |  | 50 Ohms | TOP=L2:L3=L2/L4:L6=L5/L7:BOTTOM=L7 |
| SSD_ATNLED#14 | OTHERS | BUS | 1 | 4.75 | 5 | 10 | 5 | 14 | 6 | 9.5 | 12 | 12 | 12 | 12 |  | 50 Ohms | TOP=L2:L3=L2/L4:L6=L5/L7:BOTTOM=L7 |
| SSD_ATNLED#14 | OTHERS | BUS | 2 | 5 | 5 | 10 | 5 | 14 | 6 | 10 | 12 | 12 | 12 | 12 |  | 50 Ohms | TOP=L2:L3=L2/L4:L6=L5/L7:BOTTOM=L7 |
| SSD_ATNLED#14 | OTHERS | BUS | 3 | 5 | 5 | 10 | 5 | 14 | 6 | 10 | 12 | 12 | 12 | 12 |  | 50 Ohms | TOP=L2:L3=L2/L4:L6=L5/L7:BOTTOM=L7 |
| SSD_ATNLED#14 | OTHERS | BUS | 4 | 5 | 5 | 10 | 5 | 14 | 6 | 10 | 12 | 12 | 12 | 12 |  | 50 Ohms | TOP=L2:L3=L2/L4:L6=L5/L7:BOTTOM=L7 |
| SSD_ATNLED#14 | OTHERS | BUS | 5 | 5 | 5 | 10 | 5 | 14 | 6 | 10 | 12 | 12 | 12 | 12 |  | 50 Ohms | TOP=L2:L3=L2/L4:L6=L5/L7:BOTTOM=L7 |
| SSD_ATNLED#14 | OTHERS | BUS | 6 | 5 | 5 | 10 | 5 | 14 | 6 | 10 | 12 | 12 | 12 | 12 |  | 50 Ohms | TOP=L2:L3=L2/L4:L6=L5/L7:BOTTOM=L7 |
| SSD_ATNLED#14 | OTHERS | BUS | 7 | 5 | 5 | 10 | 5 | 14 | 6 | 10 | 12 | 12 | 12 | 12 |  | 50 Ohms | TOP=L2:L3=L2/L4:L6=L5/L7:BOTTOM=L7 |
| SSD_ATNLED#14 | OTHERS | BUS | 8 | 4.75 | 5 | 10 | 5 | 14 | 6 | 9.5 | 12 | 12 | 12 | 12 |  | 50 Ohms | TOP=L2:L3=L2/L4:L6=L5/L7:BOTTOM=L7 |
| SSD_ATNLED#14_R | OTHERS | BUS | 1 | 4.75 | 5 | 10 | 5 | 14 | 6 | 9.5 | 12 | 12 | 12 | 12 |  | 50 Ohms | TOP=L2:L3=L2/L4:L6=L5/L7:BOTTOM=L7 |
| SSD_ATNLED#14_R | OTHERS | BUS | 2 | 5 | 5 | 10 | 5 | 14 | 6 | 10 | 12 | 12 | 12 | 12 |  | 50 Ohms | TOP=L2:L3=L2/L4:L6=L5/L7:BOTTOM=L7 |
| SSD_ATNLED#14_R | OTHERS | BUS | 3 | 5 | 5 | 10 | 5 | 14 | 6 | 10 | 12 | 12 | 12 | 12 |  | 50 Ohms | TOP=L2:L3=L2/L4:L6=L5/L7:BOTTOM=L7 |
| SSD_ATNLED#14_R | OTHERS | BUS | 4 | 5 | 5 | 10 | 5 | 14 | 6 | 10 | 12 | 12 | 12 | 12 |  | 50 Ohms | TOP=L2:L3=L2/L4:L6=L5/L7:BOTTOM=L7 |
| SSD_ATNLED#14_R | OTHERS | BUS | 5 | 5 | 5 | 10 | 5 | 14 | 6 | 10 | 12 | 12 | 12 | 12 |  | 50 Ohms | TOP=L2:L3=L2/L4:L6=L5/L7:BOTTOM=L7 |
| SSD_ATNLED#14_R | OTHERS | BUS | 6 | 5 | 5 | 10 | 5 | 14 | 6 | 10 | 12 | 12 | 12 | 12 |  | 50 Ohms | TOP=L2:L3=L2/L4:L6=L5/L7:BOTTOM=L7 |
| SSD_ATNLED#14_R | OTHERS | BUS | 7 | 5 | 5 | 10 | 5 | 14 | 6 | 10 | 12 | 12 | 12 | 12 |  | 50 Ohms | TOP=L2:L3=L2/L4:L6=L5/L7:BOTTOM=L7 |
| SSD_ATNLED#14_R | OTHERS | BUS | 8 | 4.75 | 5 | 10 | 5 | 14 | 6 | 9.5 | 12 | 12 | 12 | 12 |  | 50 Ohms | TOP=L2:L3=L2/L4:L6=L5/L7:BOTTOM=L7 |
| SSD_ATNLED#2 | OTHERS | BUS | 1 | 4.75 | 5 | 10 | 5 | 14 | 6 | 9.5 | 12 | 12 | 12 | 12 |  | 50 Ohms | TOP=L2:L3=L2/L4:L6=L5/L7:BOTTOM=L7 |
| SSD_ATNLED#2 | OTHERS | BUS | 2 | 5 | 5 | 10 | 5 | 14 | 6 | 10 | 12 | 12 | 12 | 12 |  | 50 Ohms | TOP=L2:L3=L2/L4:L6=L5/L7:BOTTOM=L7 |
| SSD_ATNLED#2 | OTHERS | BUS | 3 | 5 | 5 | 10 | 5 | 14 | 6 | 10 | 12 | 12 | 12 | 12 |  | 50 Ohms | TOP=L2:L3=L2/L4:L6=L5/L7:BOTTOM=L7 |
| SSD_ATNLED#2 | OTHERS | BUS | 4 | 5 | 5 | 10 | 5 | 14 | 6 | 10 | 12 | 12 | 12 | 12 |  | 50 Ohms | TOP=L2:L3=L2/L4:L6=L5/L7:BOTTOM=L7 |
| SSD_ATNLED#2 | OTHERS | BUS | 5 | 5 | 5 | 10 | 5 | 14 | 6 | 10 | 12 | 12 | 12 | 12 |  | 50 Ohms | TOP=L2:L3=L2/L4:L6=L5/L7:BOTTOM=L7 |
| SSD_ATNLED#2 | OTHERS | BUS | 6 | 5 | 5 | 10 | 5 | 14 | 6 | 10 | 12 | 12 | 12 | 12 |  | 50 Ohms | TOP=L2:L3=L2/L4:L6=L5/L7:BOTTOM=L7 |
| SSD_ATNLED#2 | OTHERS | BUS | 7 | 5 | 5 | 10 | 5 | 14 | 6 | 10 | 12 | 12 | 12 | 12 |  | 50 Ohms | TOP=L2:L3=L2/L4:L6=L5/L7:BOTTOM=L7 |
| SSD_ATNLED#2 | OTHERS | BUS | 8 | 4.75 | 5 | 10 | 5 | 14 | 6 | 9.5 | 12 | 12 | 12 | 12 |  | 50 Ohms | TOP=L2:L3=L2/L4:L6=L5/L7:BOTTOM=L7 |
| SSD_ATNLED#2_R | OTHERS | BUS | 1 | 4.75 | 5 | 10 | 5 | 14 | 6 | 9.5 | 12 | 12 | 12 | 12 |  | 50 Ohms | TOP=L2:L3=L2/L4:L6=L5/L7:BOTTOM=L7 |
| SSD_ATNLED#2_R | OTHERS | BUS | 2 | 5 | 5 | 10 | 5 | 14 | 6 | 10 | 12 | 12 | 12 | 12 |  | 50 Ohms | TOP=L2:L3=L2/L4:L6=L5/L7:BOTTOM=L7 |
| SSD_ATNLED#2_R | OTHERS | BUS | 3 | 5 | 5 | 10 | 5 | 14 | 6 | 10 | 12 | 12 | 12 | 12 |  | 50 Ohms | TOP=L2:L3=L2/L4:L6=L5/L7:BOTTOM=L7 |
| SSD_ATNLED#2_R | OTHERS | BUS | 4 | 5 | 5 | 10 | 5 | 14 | 6 | 10 | 12 | 12 | 12 | 12 |  | 50 Ohms | TOP=L2:L3=L2/L4:L6=L5/L7:BOTTOM=L7 |
| SSD_ATNLED#2_R | OTHERS | BUS | 5 | 5 | 5 | 10 | 5 | 14 | 6 | 10 | 12 | 12 | 12 | 12 |  | 50 Ohms | TOP=L2:L3=L2/L4:L6=L5/L7:BOTTOM=L7 |
| SSD_ATNLED#2_R | OTHERS | BUS | 6 | 5 | 5 | 10 | 5 | 14 | 6 | 10 | 12 | 12 | 12 | 12 |  | 50 Ohms | TOP=L2:L3=L2/L4:L6=L5/L7:BOTTOM=L7 |
| SSD_ATNLED#2_R | OTHERS | BUS | 7 | 5 | 5 | 10 | 5 | 14 | 6 | 10 | 12 | 12 | 12 | 12 |  | 50 Ohms | TOP=L2:L3=L2/L4:L6=L5/L7:BOTTOM=L7 |
| SSD_ATNLED#2_R | OTHERS | BUS | 8 | 4.75 | 5 | 10 | 5 | 14 | 6 | 9.5 | 12 | 12 | 12 | 12 |  | 50 Ohms | TOP=L2:L3=L2/L4:L6=L5/L7:BOTTOM=L7 |
| SSD_ATNLED#3 | OTHERS | BUS | 1 | 4.75 | 5 | 10 | 5 | 14 | 6 | 9.5 | 12 | 12 | 12 | 12 |  | 50 Ohms | TOP=L2:L3=L2/L4:L6=L5/L7:BOTTOM=L7 |
| SSD_ATNLED#3 | OTHERS | BUS | 2 | 5 | 5 | 10 | 5 | 14 | 6 | 10 | 12 | 12 | 12 | 12 |  | 50 Ohms | TOP=L2:L3=L2/L4:L6=L5/L7:BOTTOM=L7 |
| SSD_ATNLED#3 | OTHERS | BUS | 3 | 5 | 5 | 10 | 5 | 14 | 6 | 10 | 12 | 12 | 12 | 12 |  | 50 Ohms | TOP=L2:L3=L2/L4:L6=L5/L7:BOTTOM=L7 |
| SSD_ATNLED#3 | OTHERS | BUS | 4 | 5 | 5 | 10 | 5 | 14 | 6 | 10 | 12 | 12 | 12 | 12 |  | 50 Ohms | TOP=L2:L3=L2/L4:L6=L5/L7:BOTTOM=L7 |
| SSD_ATNLED#3 | OTHERS | BUS | 5 | 5 | 5 | 10 | 5 | 14 | 6 | 10 | 12 | 12 | 12 | 12 |  | 50 Ohms | TOP=L2:L3=L2/L4:L6=L5/L7:BOTTOM=L7 |
| SSD_ATNLED#3 | OTHERS | BUS | 6 | 5 | 5 | 10 | 5 | 14 | 6 | 10 | 12 | 12 | 12 | 12 |  | 50 Ohms | TOP=L2:L3=L2/L4:L6=L5/L7:BOTTOM=L7 |
| SSD_ATNLED#3 | OTHERS | BUS | 7 | 5 | 5 | 10 | 5 | 14 | 6 | 10 | 12 | 12 | 12 | 12 |  | 50 Ohms | TOP=L2:L3=L2/L4:L6=L5/L7:BOTTOM=L7 |
| SSD_ATNLED#3 | OTHERS | BUS | 8 | 4.75 | 5 | 10 | 5 | 14 | 6 | 9.5 | 12 | 12 | 12 | 12 |  | 50 Ohms | TOP=L2:L3=L2/L4:L6=L5/L7:BOTTOM=L7 |
| SSD_ATNLED#3_R | OTHERS | BUS | 1 | 4.75 | 5 | 10 | 5 | 14 | 6 | 9.5 | 12 | 12 | 12 | 12 |  | 50 Ohms | TOP=L2:L3=L2/L4:L6=L5/L7:BOTTOM=L7 |
| SSD_ATNLED#3_R | OTHERS | BUS | 2 | 5 | 5 | 10 | 5 | 14 | 6 | 10 | 12 | 12 | 12 | 12 |  | 50 Ohms | TOP=L2:L3=L2/L4:L6=L5/L7:BOTTOM=L7 |
| SSD_ATNLED#3_R | OTHERS | BUS | 3 | 5 | 5 | 10 | 5 | 14 | 6 | 10 | 12 | 12 | 12 | 12 |  | 50 Ohms | TOP=L2:L3=L2/L4:L6=L5/L7:BOTTOM=L7 |
| SSD_ATNLED#3_R | OTHERS | BUS | 4 | 5 | 5 | 10 | 5 | 14 | 6 | 10 | 12 | 12 | 12 | 12 |  | 50 Ohms | TOP=L2:L3=L2/L4:L6=L5/L7:BOTTOM=L7 |
| SSD_ATNLED#3_R | OTHERS | BUS | 5 | 5 | 5 | 10 | 5 | 14 | 6 | 10 | 12 | 12 | 12 | 12 |  | 50 Ohms | TOP=L2:L3=L2/L4:L6=L5/L7:BOTTOM=L7 |
| SSD_ATNLED#3_R | OTHERS | BUS | 6 | 5 | 5 | 10 | 5 | 14 | 6 | 10 | 12 | 12 | 12 | 12 |  | 50 Ohms | TOP=L2:L3=L2/L4:L6=L5/L7:BOTTOM=L7 |
| SSD_ATNLED#3_R | OTHERS | BUS | 7 | 5 | 5 | 10 | 5 | 14 | 6 | 10 | 12 | 12 | 12 | 12 |  | 50 Ohms | TOP=L2:L3=L2/L4:L6=L5/L7:BOTTOM=L7 |
| SSD_ATNLED#3_R | OTHERS | BUS | 8 | 4.75 | 5 | 10 | 5 | 14 | 6 | 9.5 | 12 | 12 | 12 | 12 |  | 50 Ohms | TOP=L2:L3=L2/L4:L6=L5/L7:BOTTOM=L7 |
| SSD_ATNLED#4 | OTHERS | BUS | 1 | 4.75 | 5 | 10 | 5 | 14 | 6 | 9.5 | 12 | 12 | 12 | 12 |  | 50 Ohms | TOP=L2:L3=L2/L4:L6=L5/L7:BOTTOM=L7 |
| SSD_ATNLED#4 | OTHERS | BUS | 2 | 5 | 5 | 10 | 5 | 14 | 6 | 10 | 12 | 12 | 12 | 12 |  | 50 Ohms | TOP=L2:L3=L2/L4:L6=L5/L7:BOTTOM=L7 |
| SSD_ATNLED#4 | OTHERS | BUS | 3 | 5 | 5 | 10 | 5 | 14 | 6 | 10 | 12 | 12 | 12 | 12 |  | 50 Ohms | TOP=L2:L3=L2/L4:L6=L5/L7:BOTTOM=L7 |
| SSD_ATNLED#4 | OTHERS | BUS | 4 | 5 | 5 | 10 | 5 | 14 | 6 | 10 | 12 | 12 | 12 | 12 |  | 50 Ohms | TOP=L2:L3=L2/L4:L6=L5/L7:BOTTOM=L7 |
| SSD_ATNLED#4 | OTHERS | BUS | 5 | 5 | 5 | 10 | 5 | 14 | 6 | 10 | 12 | 12 | 12 | 12 |  | 50 Ohms | TOP=L2:L3=L2/L4:L6=L5/L7:BOTTOM=L7 |
| SSD_ATNLED#4 | OTHERS | BUS | 6 | 5 | 5 | 10 | 5 | 14 | 6 | 10 | 12 | 12 | 12 | 12 |  | 50 Ohms | TOP=L2:L3=L2/L4:L6=L5/L7:BOTTOM=L7 |
| SSD_ATNLED#4 | OTHERS | BUS | 7 | 5 | 5 | 10 | 5 | 14 | 6 | 10 | 12 | 12 | 12 | 12 |  | 50 Ohms | TOP=L2:L3=L2/L4:L6=L5/L7:BOTTOM=L7 |
| SSD_ATNLED#4 | OTHERS | BUS | 8 | 4.75 | 5 | 10 | 5 | 14 | 6 | 9.5 | 12 | 12 | 12 | 12 |  | 50 Ohms | TOP=L2:L3=L2/L4:L6=L5/L7:BOTTOM=L7 |
| SSD_ATNLED#4_R | OTHERS | BUS | 1 | 4.75 | 5 | 10 | 5 | 14 | 6 | 9.5 | 12 | 12 | 12 | 12 |  | 50 Ohms | TOP=L2:L3=L2/L4:L6=L5/L7:BOTTOM=L7 |
| SSD_ATNLED#4_R | OTHERS | BUS | 2 | 5 | 5 | 10 | 5 | 14 | 6 | 10 | 12 | 12 | 12 | 12 |  | 50 Ohms | TOP=L2:L3=L2/L4:L6=L5/L7:BOTTOM=L7 |
| SSD_ATNLED#4_R | OTHERS | BUS | 3 | 5 | 5 | 10 | 5 | 14 | 6 | 10 | 12 | 12 | 12 | 12 |  | 50 Ohms | TOP=L2:L3=L2/L4:L6=L5/L7:BOTTOM=L7 |
| SSD_ATNLED#4_R | OTHERS | BUS | 4 | 5 | 5 | 10 | 5 | 14 | 6 | 10 | 12 | 12 | 12 | 12 |  | 50 Ohms | TOP=L2:L3=L2/L4:L6=L5/L7:BOTTOM=L7 |
| SSD_ATNLED#4_R | OTHERS | BUS | 5 | 5 | 5 | 10 | 5 | 14 | 6 | 10 | 12 | 12 | 12 | 12 |  | 50 Ohms | TOP=L2:L3=L2/L4:L6=L5/L7:BOTTOM=L7 |
| SSD_ATNLED#4_R | OTHERS | BUS | 6 | 5 | 5 | 10 | 5 | 14 | 6 | 10 | 12 | 12 | 12 | 12 |  | 50 Ohms | TOP=L2:L3=L2/L4:L6=L5/L7:BOTTOM=L7 |
| SSD_ATNLED#4_R | OTHERS | BUS | 7 | 5 | 5 | 10 | 5 | 14 | 6 | 10 | 12 | 12 | 12 | 12 |  | 50 Ohms | TOP=L2:L3=L2/L4:L6=L5/L7:BOTTOM=L7 |
| SSD_ATNLED#4_R | OTHERS | BUS | 8 | 4.75 | 5 | 10 | 5 | 14 | 6 | 9.5 | 12 | 12 | 12 | 12 |  | 50 Ohms | TOP=L2:L3=L2/L4:L6=L5/L7:BOTTOM=L7 |
| SSD_ATNLED#5 | OTHERS | BUS | 1 | 4.75 | 5 | 10 | 5 | 14 | 6 | 9.5 | 12 | 12 | 12 | 12 |  | 50 Ohms | TOP=L2:L3=L2/L4:L6=L5/L7:BOTTOM=L7 |
| SSD_ATNLED#5 | OTHERS | BUS | 2 | 5 | 5 | 10 | 5 | 14 | 6 | 10 | 12 | 12 | 12 | 12 |  | 50 Ohms | TOP=L2:L3=L2/L4:L6=L5/L7:BOTTOM=L7 |
| SSD_ATNLED#5 | OTHERS | BUS | 3 | 5 | 5 | 10 | 5 | 14 | 6 | 10 | 12 | 12 | 12 | 12 |  | 50 Ohms | TOP=L2:L3=L2/L4:L6=L5/L7:BOTTOM=L7 |
| SSD_ATNLED#5 | OTHERS | BUS | 4 | 5 | 5 | 10 | 5 | 14 | 6 | 10 | 12 | 12 | 12 | 12 |  | 50 Ohms | TOP=L2:L3=L2/L4:L6=L5/L7:BOTTOM=L7 |
| SSD_ATNLED#5 | OTHERS | BUS | 5 | 5 | 5 | 10 | 5 | 14 | 6 | 10 | 12 | 12 | 12 | 12 |  | 50 Ohms | TOP=L2:L3=L2/L4:L6=L5/L7:BOTTOM=L7 |
| SSD_ATNLED#5 | OTHERS | BUS | 6 | 5 | 5 | 10 | 5 | 14 | 6 | 10 | 12 | 12 | 12 | 12 |  | 50 Ohms | TOP=L2:L3=L2/L4:L6=L5/L7:BOTTOM=L7 |
| SSD_ATNLED#5 | OTHERS | BUS | 7 | 5 | 5 | 10 | 5 | 14 | 6 | 10 | 12 | 12 | 12 | 12 |  | 50 Ohms | TOP=L2:L3=L2/L4:L6=L5/L7:BOTTOM=L7 |
| SSD_ATNLED#5 | OTHERS | BUS | 8 | 4.75 | 5 | 10 | 5 | 14 | 6 | 9.5 | 12 | 12 | 12 | 12 |  | 50 Ohms | TOP=L2:L3=L2/L4:L6=L5/L7:BOTTOM=L7 |
| SSD_ATNLED#5_R | OTHERS | BUS | 1 | 4.75 | 5 | 10 | 5 | 14 | 6 | 9.5 | 12 | 12 | 12 | 12 |  | 50 Ohms | TOP=L2:L3=L2/L4:L6=L5/L7:BOTTOM=L7 |
| SSD_ATNLED#5_R | OTHERS | BUS | 2 | 5 | 5 | 10 | 5 | 14 | 6 | 10 | 12 | 12 | 12 | 12 |  | 50 Ohms | TOP=L2:L3=L2/L4:L6=L5/L7:BOTTOM=L7 |
| SSD_ATNLED#5_R | OTHERS | BUS | 3 | 5 | 5 | 10 | 5 | 14 | 6 | 10 | 12 | 12 | 12 | 12 |  | 50 Ohms | TOP=L2:L3=L2/L4:L6=L5/L7:BOTTOM=L7 |
| SSD_ATNLED#5_R | OTHERS | BUS | 4 | 5 | 5 | 10 | 5 | 14 | 6 | 10 | 12 | 12 | 12 | 12 |  | 50 Ohms | TOP=L2:L3=L2/L4:L6=L5/L7:BOTTOM=L7 |
| SSD_ATNLED#5_R | OTHERS | BUS | 5 | 5 | 5 | 10 | 5 | 14 | 6 | 10 | 12 | 12 | 12 | 12 |  | 50 Ohms | TOP=L2:L3=L2/L4:L6=L5/L7:BOTTOM=L7 |
| SSD_ATNLED#5_R | OTHERS | BUS | 6 | 5 | 5 | 10 | 5 | 14 | 6 | 10 | 12 | 12 | 12 | 12 |  | 50 Ohms | TOP=L2:L3=L2/L4:L6=L5/L7:BOTTOM=L7 |
| SSD_ATNLED#5_R | OTHERS | BUS | 7 | 5 | 5 | 10 | 5 | 14 | 6 | 10 | 12 | 12 | 12 | 12 |  | 50 Ohms | TOP=L2:L3=L2/L4:L6=L5/L7:BOTTOM=L7 |
| SSD_ATNLED#5_R | OTHERS | BUS | 8 | 4.75 | 5 | 10 | 5 | 14 | 6 | 9.5 | 12 | 12 | 12 | 12 |  | 50 Ohms | TOP=L2:L3=L2/L4:L6=L5/L7:BOTTOM=L7 |
| SSD_ATNLED#6 | OTHERS | BUS | 1 | 4.75 | 5 | 10 | 5 | 14 | 6 | 9.5 | 12 | 12 | 12 | 12 |  | 50 Ohms | TOP=L2:L3=L2/L4:L6=L5/L7:BOTTOM=L7 |
| SSD_ATNLED#6 | OTHERS | BUS | 2 | 5 | 5 | 10 | 5 | 14 | 6 | 10 | 12 | 12 | 12 | 12 |  | 50 Ohms | TOP=L2:L3=L2/L4:L6=L5/L7:BOTTOM=L7 |
| SSD_ATNLED#6 | OTHERS | BUS | 3 | 5 | 5 | 10 | 5 | 14 | 6 | 10 | 12 | 12 | 12 | 12 |  | 50 Ohms | TOP=L2:L3=L2/L4:L6=L5/L7:BOTTOM=L7 |
| SSD_ATNLED#6 | OTHERS | BUS | 4 | 5 | 5 | 10 | 5 | 14 | 6 | 10 | 12 | 12 | 12 | 12 |  | 50 Ohms | TOP=L2:L3=L2/L4:L6=L5/L7:BOTTOM=L7 |
| SSD_ATNLED#6 | OTHERS | BUS | 5 | 5 | 5 | 10 | 5 | 14 | 6 | 10 | 12 | 12 | 12 | 12 |  | 50 Ohms | TOP=L2:L3=L2/L4:L6=L5/L7:BOTTOM=L7 |
| SSD_ATNLED#6 | OTHERS | BUS | 6 | 5 | 5 | 10 | 5 | 14 | 6 | 10 | 12 | 12 | 12 | 12 |  | 50 Ohms | TOP=L2:L3=L2/L4:L6=L5/L7:BOTTOM=L7 |
| SSD_ATNLED#6 | OTHERS | BUS | 7 | 5 | 5 | 10 | 5 | 14 | 6 | 10 | 12 | 12 | 12 | 12 |  | 50 Ohms | TOP=L2:L3=L2/L4:L6=L5/L7:BOTTOM=L7 |
| SSD_ATNLED#6 | OTHERS | BUS | 8 | 4.75 | 5 | 10 | 5 | 14 | 6 | 9.5 | 12 | 12 | 12 | 12 |  | 50 Ohms | TOP=L2:L3=L2/L4:L6=L5/L7:BOTTOM=L7 |
| SSD_ATNLED#6_R | OTHERS | BUS | 1 | 4.75 | 5 | 10 | 5 | 14 | 6 | 9.5 | 12 | 12 | 12 | 12 |  | 50 Ohms | TOP=L2:L3=L2/L4:L6=L5/L7:BOTTOM=L7 |
| SSD_ATNLED#6_R | OTHERS | BUS | 2 | 5 | 5 | 10 | 5 | 14 | 6 | 10 | 12 | 12 | 12 | 12 |  | 50 Ohms | TOP=L2:L3=L2/L4:L6=L5/L7:BOTTOM=L7 |
| SSD_ATNLED#6_R | OTHERS | BUS | 3 | 5 | 5 | 10 | 5 | 14 | 6 | 10 | 12 | 12 | 12 | 12 |  | 50 Ohms | TOP=L2:L3=L2/L4:L6=L5/L7:BOTTOM=L7 |
| SSD_ATNLED#6_R | OTHERS | BUS | 4 | 5 | 5 | 10 | 5 | 14 | 6 | 10 | 12 | 12 | 12 | 12 |  | 50 Ohms | TOP=L2:L3=L2/L4:L6=L5/L7:BOTTOM=L7 |
| SSD_ATNLED#6_R | OTHERS | BUS | 5 | 5 | 5 | 10 | 5 | 14 | 6 | 10 | 12 | 12 | 12 | 12 |  | 50 Ohms | TOP=L2:L3=L2/L4:L6=L5/L7:BOTTOM=L7 |
| SSD_ATNLED#6_R | OTHERS | BUS | 6 | 5 | 5 | 10 | 5 | 14 | 6 | 10 | 12 | 12 | 12 | 12 |  | 50 Ohms | TOP=L2:L3=L2/L4:L6=L5/L7:BOTTOM=L7 |
| SSD_ATNLED#6_R | OTHERS | BUS | 7 | 5 | 5 | 10 | 5 | 14 | 6 | 10 | 12 | 12 | 12 | 12 |  | 50 Ohms | TOP=L2:L3=L2/L4:L6=L5/L7:BOTTOM=L7 |
| SSD_ATNLED#6_R | OTHERS | BUS | 8 | 4.75 | 5 | 10 | 5 | 14 | 6 | 9.5 | 12 | 12 | 12 | 12 |  | 50 Ohms | TOP=L2:L3=L2/L4:L6=L5/L7:BOTTOM=L7 |
| SSD_ATNLED#7 | OTHERS | BUS | 1 | 4.75 | 5 | 10 | 5 | 14 | 6 | 9.5 | 12 | 12 | 12 | 12 |  | 50 Ohms | TOP=L2:L3=L2/L4:L6=L5/L7:BOTTOM=L7 |
| SSD_ATNLED#7 | OTHERS | BUS | 2 | 5 | 5 | 10 | 5 | 14 | 6 | 10 | 12 | 12 | 12 | 12 |  | 50 Ohms | TOP=L2:L3=L2/L4:L6=L5/L7:BOTTOM=L7 |
| SSD_ATNLED#7 | OTHERS | BUS | 3 | 5 | 5 | 10 | 5 | 14 | 6 | 10 | 12 | 12 | 12 | 12 |  | 50 Ohms | TOP=L2:L3=L2/L4:L6=L5/L7:BOTTOM=L7 |
| SSD_ATNLED#7 | OTHERS | BUS | 4 | 5 | 5 | 10 | 5 | 14 | 6 | 10 | 12 | 12 | 12 | 12 |  | 50 Ohms | TOP=L2:L3=L2/L4:L6=L5/L7:BOTTOM=L7 |
| SSD_ATNLED#7 | OTHERS | BUS | 5 | 5 | 5 | 10 | 5 | 14 | 6 | 10 | 12 | 12 | 12 | 12 |  | 50 Ohms | TOP=L2:L3=L2/L4:L6=L5/L7:BOTTOM=L7 |
| SSD_ATNLED#7 | OTHERS | BUS | 6 | 5 | 5 | 10 | 5 | 14 | 6 | 10 | 12 | 12 | 12 | 12 |  | 50 Ohms | TOP=L2:L3=L2/L4:L6=L5/L7:BOTTOM=L7 |
| SSD_ATNLED#7 | OTHERS | BUS | 7 | 5 | 5 | 10 | 5 | 14 | 6 | 10 | 12 | 12 | 12 | 12 |  | 50 Ohms | TOP=L2:L3=L2/L4:L6=L5/L7:BOTTOM=L7 |
| SSD_ATNLED#7 | OTHERS | BUS | 8 | 4.75 | 5 | 10 | 5 | 14 | 6 | 9.5 | 12 | 12 | 12 | 12 |  | 50 Ohms | TOP=L2:L3=L2/L4:L6=L5/L7:BOTTOM=L7 |
| SSD_ATNLED#7_R | OTHERS | BUS | 1 | 4.75 | 5 | 10 | 5 | 14 | 6 | 9.5 | 12 | 12 | 12 | 12 |  | 50 Ohms | TOP=L2:L3=L2/L4:L6=L5/L7:BOTTOM=L7 |
| SSD_ATNLED#7_R | OTHERS | BUS | 2 | 5 | 5 | 10 | 5 | 14 | 6 | 10 | 12 | 12 | 12 | 12 |  | 50 Ohms | TOP=L2:L3=L2/L4:L6=L5/L7:BOTTOM=L7 |
| SSD_ATNLED#7_R | OTHERS | BUS | 3 | 5 | 5 | 10 | 5 | 14 | 6 | 10 | 12 | 12 | 12 | 12 |  | 50 Ohms | TOP=L2:L3=L2/L4:L6=L5/L7:BOTTOM=L7 |
| SSD_ATNLED#7_R | OTHERS | BUS | 4 | 5 | 5 | 10 | 5 | 14 | 6 | 10 | 12 | 12 | 12 | 12 |  | 50 Ohms | TOP=L2:L3=L2/L4:L6=L5/L7:BOTTOM=L7 |
| SSD_ATNLED#7_R | OTHERS | BUS | 5 | 5 | 5 | 10 | 5 | 14 | 6 | 10 | 12 | 12 | 12 | 12 |  | 50 Ohms | TOP=L2:L3=L2/L4:L6=L5/L7:BOTTOM=L7 |
| SSD_ATNLED#7_R | OTHERS | BUS | 6 | 5 | 5 | 10 | 5 | 14 | 6 | 10 | 12 | 12 | 12 | 12 |  | 50 Ohms | TOP=L2:L3=L2/L4:L6=L5/L7:BOTTOM=L7 |
| SSD_ATNLED#7_R | OTHERS | BUS | 7 | 5 | 5 | 10 | 5 | 14 | 6 | 10 | 12 | 12 | 12 | 12 |  | 50 Ohms | TOP=L2:L3=L2/L4:L6=L5/L7:BOTTOM=L7 |
| SSD_ATNLED#7_R | OTHERS | BUS | 8 | 4.75 | 5 | 10 | 5 | 14 | 6 | 9.5 | 12 | 12 | 12 | 12 |  | 50 Ohms | TOP=L2:L3=L2/L4:L6=L5/L7:BOTTOM=L7 |
| SSD_ATNLED#8 | OTHERS | BUS | 1 | 4.75 | 5 | 10 | 5 | 14 | 6 | 9.5 | 12 | 12 | 12 | 12 |  | 50 Ohms | TOP=L2:L3=L2/L4:L6=L5/L7:BOTTOM=L7 |
| SSD_ATNLED#8 | OTHERS | BUS | 2 | 5 | 5 | 10 | 5 | 14 | 6 | 10 | 12 | 12 | 12 | 12 |  | 50 Ohms | TOP=L2:L3=L2/L4:L6=L5/L7:BOTTOM=L7 |
| SSD_ATNLED#8 | OTHERS | BUS | 3 | 5 | 5 | 10 | 5 | 14 | 6 | 10 | 12 | 12 | 12 | 12 |  | 50 Ohms | TOP=L2:L3=L2/L4:L6=L5/L7:BOTTOM=L7 |
| SSD_ATNLED#8 | OTHERS | BUS | 4 | 5 | 5 | 10 | 5 | 14 | 6 | 10 | 12 | 12 | 12 | 12 |  | 50 Ohms | TOP=L2:L3=L2/L4:L6=L5/L7:BOTTOM=L7 |
| SSD_ATNLED#8 | OTHERS | BUS | 5 | 5 | 5 | 10 | 5 | 14 | 6 | 10 | 12 | 12 | 12 | 12 |  | 50 Ohms | TOP=L2:L3=L2/L4:L6=L5/L7:BOTTOM=L7 |
| SSD_ATNLED#8 | OTHERS | BUS | 6 | 5 | 5 | 10 | 5 | 14 | 6 | 10 | 12 | 12 | 12 | 12 |  | 50 Ohms | TOP=L2:L3=L2/L4:L6=L5/L7:BOTTOM=L7 |
| SSD_ATNLED#8 | OTHERS | BUS | 7 | 5 | 5 | 10 | 5 | 14 | 6 | 10 | 12 | 12 | 12 | 12 |  | 50 Ohms | TOP=L2:L3=L2/L4:L6=L5/L7:BOTTOM=L7 |
| SSD_ATNLED#8 | OTHERS | BUS | 8 | 4.75 | 5 | 10 | 5 | 14 | 6 | 9.5 | 12 | 12 | 12 | 12 |  | 50 Ohms | TOP=L2:L3=L2/L4:L6=L5/L7:BOTTOM=L7 |
| SSD_ATNLED#8_R | OTHERS | BUS | 1 | 4.75 | 5 | 10 | 5 | 14 | 6 | 9.5 | 12 | 12 | 12 | 12 |  | 50 Ohms | TOP=L2:L3=L2/L4:L6=L5/L7:BOTTOM=L7 |
| SSD_ATNLED#8_R | OTHERS | BUS | 2 | 5 | 5 | 10 | 5 | 14 | 6 | 10 | 12 | 12 | 12 | 12 |  | 50 Ohms | TOP=L2:L3=L2/L4:L6=L5/L7:BOTTOM=L7 |
| SSD_ATNLED#8_R | OTHERS | BUS | 3 | 5 | 5 | 10 | 5 | 14 | 6 | 10 | 12 | 12 | 12 | 12 |  | 50 Ohms | TOP=L2:L3=L2/L4:L6=L5/L7:BOTTOM=L7 |
| SSD_ATNLED#8_R | OTHERS | BUS | 4 | 5 | 5 | 10 | 5 | 14 | 6 | 10 | 12 | 12 | 12 | 12 |  | 50 Ohms | TOP=L2:L3=L2/L4:L6=L5/L7:BOTTOM=L7 |
| SSD_ATNLED#8_R | OTHERS | BUS | 5 | 5 | 5 | 10 | 5 | 14 | 6 | 10 | 12 | 12 | 12 | 12 |  | 50 Ohms | TOP=L2:L3=L2/L4:L6=L5/L7:BOTTOM=L7 |
| SSD_ATNLED#8_R | OTHERS | BUS | 6 | 5 | 5 | 10 | 5 | 14 | 6 | 10 | 12 | 12 | 12 | 12 |  | 50 Ohms | TOP=L2:L3=L2/L4:L6=L5/L7:BOTTOM=L7 |
| SSD_ATNLED#8_R | OTHERS | BUS | 7 | 5 | 5 | 10 | 5 | 14 | 6 | 10 | 12 | 12 | 12 | 12 |  | 50 Ohms | TOP=L2:L3=L2/L4:L6=L5/L7:BOTTOM=L7 |
| SSD_ATNLED#8_R | OTHERS | BUS | 8 | 4.75 | 5 | 10 | 5 | 14 | 6 | 9.5 | 12 | 12 | 12 | 12 |  | 50 Ohms | TOP=L2:L3=L2/L4:L6=L5/L7:BOTTOM=L7 |
| SSD_ATNLED#9 | OTHERS | BUS | 1 | 4.75 | 5 | 10 | 5 | 14 | 6 | 9.5 | 12 | 12 | 12 | 12 |  | 50 Ohms | TOP=L2:L3=L2/L4:L6=L5/L7:BOTTOM=L7 |
| SSD_ATNLED#9 | OTHERS | BUS | 2 | 5 | 5 | 10 | 5 | 14 | 6 | 10 | 12 | 12 | 12 | 12 |  | 50 Ohms | TOP=L2:L3=L2/L4:L6=L5/L7:BOTTOM=L7 |
| SSD_ATNLED#9 | OTHERS | BUS | 3 | 5 | 5 | 10 | 5 | 14 | 6 | 10 | 12 | 12 | 12 | 12 |  | 50 Ohms | TOP=L2:L3=L2/L4:L6=L5/L7:BOTTOM=L7 |
| SSD_ATNLED#9 | OTHERS | BUS | 4 | 5 | 5 | 10 | 5 | 14 | 6 | 10 | 12 | 12 | 12 | 12 |  | 50 Ohms | TOP=L2:L3=L2/L4:L6=L5/L7:BOTTOM=L7 |
| SSD_ATNLED#9 | OTHERS | BUS | 5 | 5 | 5 | 10 | 5 | 14 | 6 | 10 | 12 | 12 | 12 | 12 |  | 50 Ohms | TOP=L2:L3=L2/L4:L6=L5/L7:BOTTOM=L7 |
| SSD_ATNLED#9 | OTHERS | BUS | 6 | 5 | 5 | 10 | 5 | 14 | 6 | 10 | 12 | 12 | 12 | 12 |  | 50 Ohms | TOP=L2:L3=L2/L4:L6=L5/L7:BOTTOM=L7 |
| SSD_ATNLED#9 | OTHERS | BUS | 7 | 5 | 5 | 10 | 5 | 14 | 6 | 10 | 12 | 12 | 12 | 12 |  | 50 Ohms | TOP=L2:L3=L2/L4:L6=L5/L7:BOTTOM=L7 |
| SSD_ATNLED#9 | OTHERS | BUS | 8 | 4.75 | 5 | 10 | 5 | 14 | 6 | 9.5 | 12 | 12 | 12 | 12 |  | 50 Ohms | TOP=L2:L3=L2/L4:L6=L5/L7:BOTTOM=L7 |
| SSD_ATNLED#9_R | OTHERS | BUS | 1 | 4.75 | 5 | 10 | 5 | 14 | 6 | 9.5 | 12 | 12 | 12 | 12 |  | 50 Ohms | TOP=L2:L3=L2/L4:L6=L5/L7:BOTTOM=L7 |
| SSD_ATNLED#9_R | OTHERS | BUS | 2 | 5 | 5 | 10 | 5 | 14 | 6 | 10 | 12 | 12 | 12 | 12 |  | 50 Ohms | TOP=L2:L3=L2/L4:L6=L5/L7:BOTTOM=L7 |
| SSD_ATNLED#9_R | OTHERS | BUS | 3 | 5 | 5 | 10 | 5 | 14 | 6 | 10 | 12 | 12 | 12 | 12 |  | 50 Ohms | TOP=L2:L3=L2/L4:L6=L5/L7:BOTTOM=L7 |
| SSD_ATNLED#9_R | OTHERS | BUS | 4 | 5 | 5 | 10 | 5 | 14 | 6 | 10 | 12 | 12 | 12 | 12 |  | 50 Ohms | TOP=L2:L3=L2/L4:L6=L5/L7:BOTTOM=L7 |
| SSD_ATNLED#9_R | OTHERS | BUS | 5 | 5 | 5 | 10 | 5 | 14 | 6 | 10 | 12 | 12 | 12 | 12 |  | 50 Ohms | TOP=L2:L3=L2/L4:L6=L5/L7:BOTTOM=L7 |
| SSD_ATNLED#9_R | OTHERS | BUS | 6 | 5 | 5 | 10 | 5 | 14 | 6 | 10 | 12 | 12 | 12 | 12 |  | 50 Ohms | TOP=L2:L3=L2/L4:L6=L5/L7:BOTTOM=L7 |
| SSD_ATNLED#9_R | OTHERS | BUS | 7 | 5 | 5 | 10 | 5 | 14 | 6 | 10 | 12 | 12 | 12 | 12 |  | 50 Ohms | TOP=L2:L3=L2/L4:L6=L5/L7:BOTTOM=L7 |
| SSD_ATNLED#9_R | OTHERS | BUS | 8 | 4.75 | 5 | 10 | 5 | 14 | 6 | 9.5 | 12 | 12 | 12 | 12 |  | 50 Ohms | TOP=L2:L3=L2/L4:L6=L5/L7:BOTTOM=L7 |
| SSD_PERST#0 | OTHERS | BUS | 1 | 4.75 | 5 | 10 | 5 | 14 | 6 | 9.5 | 12 | 12 | 12 | 12 |  | 50 Ohms | TOP=L2:L3=L2/L4:L6=L5/L7:BOTTOM=L7 |
| SSD_PERST#0 | OTHERS | BUS | 2 | 5 | 5 | 10 | 5 | 14 | 6 | 10 | 12 | 12 | 12 | 12 |  | 50 Ohms | TOP=L2:L3=L2/L4:L6=L5/L7:BOTTOM=L7 |
| SSD_PERST#0 | OTHERS | BUS | 3 | 5 | 5 | 10 | 5 | 14 | 6 | 10 | 12 | 12 | 12 | 12 |  | 50 Ohms | TOP=L2:L3=L2/L4:L6=L5/L7:BOTTOM=L7 |
| SSD_PERST#0 | OTHERS | BUS | 4 | 5 | 5 | 10 | 5 | 14 | 6 | 10 | 12 | 12 | 12 | 12 |  | 50 Ohms | TOP=L2:L3=L2/L4:L6=L5/L7:BOTTOM=L7 |
| SSD_PERST#0 | OTHERS | BUS | 5 | 5 | 5 | 10 | 5 | 14 | 6 | 10 | 12 | 12 | 12 | 12 |  | 50 Ohms | TOP=L2:L3=L2/L4:L6=L5/L7:BOTTOM=L7 |
| SSD_PERST#0 | OTHERS | BUS | 6 | 5 | 5 | 10 | 5 | 14 | 6 | 10 | 12 | 12 | 12 | 12 |  | 50 Ohms | TOP=L2:L3=L2/L4:L6=L5/L7:BOTTOM=L7 |
| SSD_PERST#0 | OTHERS | BUS | 7 | 5 | 5 | 10 | 5 | 14 | 6 | 10 | 12 | 12 | 12 | 12 |  | 50 Ohms | TOP=L2:L3=L2/L4:L6=L5/L7:BOTTOM=L7 |
| SSD_PERST#0 | OTHERS | BUS | 8 | 4.75 | 5 | 10 | 5 | 14 | 6 | 9.5 | 12 | 12 | 12 | 12 |  | 50 Ohms | TOP=L2:L3=L2/L4:L6=L5/L7:BOTTOM=L7 |
| SSD_PERST#0_B0 | OTHERS | BUS | 1 | 4.75 | 5 | 10 | 5 | 14 | 6 | 9.5 | 12 | 12 | 12 | 12 |  | 50 Ohms | TOP=L2:L3=L2/L4:L6=L5/L7:BOTTOM=L7 |
| SSD_PERST#0_B0 | OTHERS | BUS | 2 | 5 | 5 | 10 | 5 | 14 | 6 | 10 | 12 | 12 | 12 | 12 |  | 50 Ohms | TOP=L2:L3=L2/L4:L6=L5/L7:BOTTOM=L7 |
| SSD_PERST#0_B0 | OTHERS | BUS | 3 | 5 | 5 | 10 | 5 | 14 | 6 | 10 | 12 | 12 | 12 | 12 |  | 50 Ohms | TOP=L2:L3=L2/L4:L6=L5/L7:BOTTOM=L7 |
| SSD_PERST#0_B0 | OTHERS | BUS | 4 | 5 | 5 | 10 | 5 | 14 | 6 | 10 | 12 | 12 | 12 | 12 |  | 50 Ohms | TOP=L2:L3=L2/L4:L6=L5/L7:BOTTOM=L7 |
| SSD_PERST#0_B0 | OTHERS | BUS | 5 | 5 | 5 | 10 | 5 | 14 | 6 | 10 | 12 | 12 | 12 | 12 |  | 50 Ohms | TOP=L2:L3=L2/L4:L6=L5/L7:BOTTOM=L7 |
| SSD_PERST#0_B0 | OTHERS | BUS | 6 | 5 | 5 | 10 | 5 | 14 | 6 | 10 | 12 | 12 | 12 | 12 |  | 50 Ohms | TOP=L2:L3=L2/L4:L6=L5/L7:BOTTOM=L7 |
| SSD_PERST#0_B0 | OTHERS | BUS | 7 | 5 | 5 | 10 | 5 | 14 | 6 | 10 | 12 | 12 | 12 | 12 |  | 50 Ohms | TOP=L2:L3=L2/L4:L6=L5/L7:BOTTOM=L7 |
| SSD_PERST#0_B0 | OTHERS | BUS | 8 | 4.75 | 5 | 10 | 5 | 14 | 6 | 9.5 | 12 | 12 | 12 | 12 |  | 50 Ohms | TOP=L2:L3=L2/L4:L6=L5/L7:BOTTOM=L7 |
| SSD_PERST#0_B1 | OTHERS | BUS | 1 | 4.75 | 5 | 10 | 5 | 14 | 6 | 9.5 | 12 | 12 | 12 | 12 |  | 50 Ohms | TOP=L2:L3=L2/L4:L6=L5/L7:BOTTOM=L7 |
| SSD_PERST#0_B1 | OTHERS | BUS | 2 | 5 | 5 | 10 | 5 | 14 | 6 | 10 | 12 | 12 | 12 | 12 |  | 50 Ohms | TOP=L2:L3=L2/L4:L6=L5/L7:BOTTOM=L7 |
| SSD_PERST#0_B1 | OTHERS | BUS | 3 | 5 | 5 | 10 | 5 | 14 | 6 | 10 | 12 | 12 | 12 | 12 |  | 50 Ohms | TOP=L2:L3=L2/L4:L6=L5/L7:BOTTOM=L7 |
| SSD_PERST#0_B1 | OTHERS | BUS | 4 | 5 | 5 | 10 | 5 | 14 | 6 | 10 | 12 | 12 | 12 | 12 |  | 50 Ohms | TOP=L2:L3=L2/L4:L6=L5/L7:BOTTOM=L7 |
| SSD_PERST#0_B1 | OTHERS | BUS | 5 | 5 | 5 | 10 | 5 | 14 | 6 | 10 | 12 | 12 | 12 | 12 |  | 50 Ohms | TOP=L2:L3=L2/L4:L6=L5/L7:BOTTOM=L7 |
| SSD_PERST#0_B1 | OTHERS | BUS | 6 | 5 | 5 | 10 | 5 | 14 | 6 | 10 | 12 | 12 | 12 | 12 |  | 50 Ohms | TOP=L2:L3=L2/L4:L6=L5/L7:BOTTOM=L7 |
| SSD_PERST#0_B1 | OTHERS | BUS | 7 | 5 | 5 | 10 | 5 | 14 | 6 | 10 | 12 | 12 | 12 | 12 |  | 50 Ohms | TOP=L2:L3=L2/L4:L6=L5/L7:BOTTOM=L7 |
| SSD_PERST#0_B1 | OTHERS | BUS | 8 | 4.75 | 5 | 10 | 5 | 14 | 6 | 9.5 | 12 | 12 | 12 | 12 |  | 50 Ohms | TOP=L2:L3=L2/L4:L6=L5/L7:BOTTOM=L7 |
| SSD_PERST#0_B10 | OTHERS | BUS | 1 | 4.75 | 5 | 10 | 5 | 14 | 6 | 9.5 | 12 | 12 | 12 | 12 |  | 50 Ohms | TOP=L2:L3=L2/L4:L6=L5/L7:BOTTOM=L7 |
| SSD_PERST#0_B10 | OTHERS | BUS | 2 | 5 | 5 | 10 | 5 | 14 | 6 | 10 | 12 | 12 | 12 | 12 |  | 50 Ohms | TOP=L2:L3=L2/L4:L6=L5/L7:BOTTOM=L7 |
| SSD_PERST#0_B10 | OTHERS | BUS | 3 | 5 | 5 | 10 | 5 | 14 | 6 | 10 | 12 | 12 | 12 | 12 |  | 50 Ohms | TOP=L2:L3=L2/L4:L6=L5/L7:BOTTOM=L7 |
| SSD_PERST#0_B10 | OTHERS | BUS | 4 | 5 | 5 | 10 | 5 | 14 | 6 | 10 | 12 | 12 | 12 | 12 |  | 50 Ohms | TOP=L2:L3=L2/L4:L6=L5/L7:BOTTOM=L7 |
| SSD_PERST#0_B10 | OTHERS | BUS | 5 | 5 | 5 | 10 | 5 | 14 | 6 | 10 | 12 | 12 | 12 | 12 |  | 50 Ohms | TOP=L2:L3=L2/L4:L6=L5/L7:BOTTOM=L7 |
| SSD_PERST#0_B10 | OTHERS | BUS | 6 | 5 | 5 | 10 | 5 | 14 | 6 | 10 | 12 | 12 | 12 | 12 |  | 50 Ohms | TOP=L2:L3=L2/L4:L6=L5/L7:BOTTOM=L7 |
| SSD_PERST#0_B10 | OTHERS | BUS | 7 | 5 | 5 | 10 | 5 | 14 | 6 | 10 | 12 | 12 | 12 | 12 |  | 50 Ohms | TOP=L2:L3=L2/L4:L6=L5/L7:BOTTOM=L7 |
| SSD_PERST#0_B10 | OTHERS | BUS | 8 | 4.75 | 5 | 10 | 5 | 14 | 6 | 9.5 | 12 | 12 | 12 | 12 |  | 50 Ohms | TOP=L2:L3=L2/L4:L6=L5/L7:BOTTOM=L7 |
| SSD_PERST#0_B11 | OTHERS | BUS | 1 | 4.75 | 5 | 10 | 5 | 14 | 6 | 9.5 | 12 | 12 | 12 | 12 |  | 50 Ohms | TOP=L2:L3=L2/L4:L6=L5/L7:BOTTOM=L7 |
| SSD_PERST#0_B11 | OTHERS | BUS | 2 | 5 | 5 | 10 | 5 | 14 | 6 | 10 | 12 | 12 | 12 | 12 |  | 50 Ohms | TOP=L2:L3=L2/L4:L6=L5/L7:BOTTOM=L7 |
| SSD_PERST#0_B11 | OTHERS | BUS | 3 | 5 | 5 | 10 | 5 | 14 | 6 | 10 | 12 | 12 | 12 | 12 |  | 50 Ohms | TOP=L2:L3=L2/L4:L6=L5/L7:BOTTOM=L7 |
| SSD_PERST#0_B11 | OTHERS | BUS | 4 | 5 | 5 | 10 | 5 | 14 | 6 | 10 | 12 | 12 | 12 | 12 |  | 50 Ohms | TOP=L2:L3=L2/L4:L6=L5/L7:BOTTOM=L7 |
| SSD_PERST#0_B11 | OTHERS | BUS | 5 | 5 | 5 | 10 | 5 | 14 | 6 | 10 | 12 | 12 | 12 | 12 |  | 50 Ohms | TOP=L2:L3=L2/L4:L6=L5/L7:BOTTOM=L7 |
| SSD_PERST#0_B11 | OTHERS | BUS | 6 | 5 | 5 | 10 | 5 | 14 | 6 | 10 | 12 | 12 | 12 | 12 |  | 50 Ohms | TOP=L2:L3=L2/L4:L6=L5/L7:BOTTOM=L7 |
| SSD_PERST#0_B11 | OTHERS | BUS | 7 | 5 | 5 | 10 | 5 | 14 | 6 | 10 | 12 | 12 | 12 | 12 |  | 50 Ohms | TOP=L2:L3=L2/L4:L6=L5/L7:BOTTOM=L7 |
| SSD_PERST#0_B11 | OTHERS | BUS | 8 | 4.75 | 5 | 10 | 5 | 14 | 6 | 9.5 | 12 | 12 | 12 | 12 |  | 50 Ohms | TOP=L2:L3=L2/L4:L6=L5/L7:BOTTOM=L7 |
| SSD_PERST#0_B12 | OTHERS | BUS | 1 | 4.75 | 5 | 10 | 5 | 14 | 6 | 9.5 | 12 | 12 | 12 | 12 |  | 50 Ohms | TOP=L2:L3=L2/L4:L6=L5/L7:BOTTOM=L7 |
| SSD_PERST#0_B12 | OTHERS | BUS | 2 | 5 | 5 | 10 | 5 | 14 | 6 | 10 | 12 | 12 | 12 | 12 |  | 50 Ohms | TOP=L2:L3=L2/L4:L6=L5/L7:BOTTOM=L7 |
| SSD_PERST#0_B12 | OTHERS | BUS | 3 | 5 | 5 | 10 | 5 | 14 | 6 | 10 | 12 | 12 | 12 | 12 |  | 50 Ohms | TOP=L2:L3=L2/L4:L6=L5/L7:BOTTOM=L7 |
| SSD_PERST#0_B12 | OTHERS | BUS | 4 | 5 | 5 | 10 | 5 | 14 | 6 | 10 | 12 | 12 | 12 | 12 |  | 50 Ohms | TOP=L2:L3=L2/L4:L6=L5/L7:BOTTOM=L7 |
| SSD_PERST#0_B12 | OTHERS | BUS | 5 | 5 | 5 | 10 | 5 | 14 | 6 | 10 | 12 | 12 | 12 | 12 |  | 50 Ohms | TOP=L2:L3=L2/L4:L6=L5/L7:BOTTOM=L7 |
| SSD_PERST#0_B12 | OTHERS | BUS | 6 | 5 | 5 | 10 | 5 | 14 | 6 | 10 | 12 | 12 | 12 | 12 |  | 50 Ohms | TOP=L2:L3=L2/L4:L6=L5/L7:BOTTOM=L7 |
| SSD_PERST#0_B12 | OTHERS | BUS | 7 | 5 | 5 | 10 | 5 | 14 | 6 | 10 | 12 | 12 | 12 | 12 |  | 50 Ohms | TOP=L2:L3=L2/L4:L6=L5/L7:BOTTOM=L7 |
| SSD_PERST#0_B12 | OTHERS | BUS | 8 | 4.75 | 5 | 10 | 5 | 14 | 6 | 9.5 | 12 | 12 | 12 | 12 |  | 50 Ohms | TOP=L2:L3=L2/L4:L6=L5/L7:BOTTOM=L7 |
| SSD_PERST#0_B13 | OTHERS | BUS | 1 | 4.75 | 5 | 10 | 5 | 14 | 6 | 9.5 | 12 | 12 | 12 | 12 |  | 50 Ohms | TOP=L2:L3=L2/L4:L6=L5/L7:BOTTOM=L7 |
| SSD_PERST#0_B13 | OTHERS | BUS | 2 | 5 | 5 | 10 | 5 | 14 | 6 | 10 | 12 | 12 | 12 | 12 |  | 50 Ohms | TOP=L2:L3=L2/L4:L6=L5/L7:BOTTOM=L7 |
| SSD_PERST#0_B13 | OTHERS | BUS | 3 | 5 | 5 | 10 | 5 | 14 | 6 | 10 | 12 | 12 | 12 | 12 |  | 50 Ohms | TOP=L2:L3=L2/L4:L6=L5/L7:BOTTOM=L7 |
| SSD_PERST#0_B13 | OTHERS | BUS | 4 | 5 | 5 | 10 | 5 | 14 | 6 | 10 | 12 | 12 | 12 | 12 |  | 50 Ohms | TOP=L2:L3=L2/L4:L6=L5/L7:BOTTOM=L7 |
| SSD_PERST#0_B13 | OTHERS | BUS | 5 | 5 | 5 | 10 | 5 | 14 | 6 | 10 | 12 | 12 | 12 | 12 |  | 50 Ohms | TOP=L2:L3=L2/L4:L6=L5/L7:BOTTOM=L7 |
| SSD_PERST#0_B13 | OTHERS | BUS | 6 | 5 | 5 | 10 | 5 | 14 | 6 | 10 | 12 | 12 | 12 | 12 |  | 50 Ohms | TOP=L2:L3=L2/L4:L6=L5/L7:BOTTOM=L7 |
| SSD_PERST#0_B13 | OTHERS | BUS | 7 | 5 | 5 | 10 | 5 | 14 | 6 | 10 | 12 | 12 | 12 | 12 |  | 50 Ohms | TOP=L2:L3=L2/L4:L6=L5/L7:BOTTOM=L7 |
| SSD_PERST#0_B13 | OTHERS | BUS | 8 | 4.75 | 5 | 10 | 5 | 14 | 6 | 9.5 | 12 | 12 | 12 | 12 |  | 50 Ohms | TOP=L2:L3=L2/L4:L6=L5/L7:BOTTOM=L7 |
| SSD_PERST#0_B14 | OTHERS | BUS | 1 | 4.75 | 5 | 10 | 5 | 14 | 6 | 9.5 | 12 | 12 | 12 | 12 |  | 50 Ohms | TOP=L2:L3=L2/L4:L6=L5/L7:BOTTOM=L7 |
| SSD_PERST#0_B14 | OTHERS | BUS | 2 | 5 | 5 | 10 | 5 | 14 | 6 | 10 | 12 | 12 | 12 | 12 |  | 50 Ohms | TOP=L2:L3=L2/L4:L6=L5/L7:BOTTOM=L7 |
| SSD_PERST#0_B14 | OTHERS | BUS | 3 | 5 | 5 | 10 | 5 | 14 | 6 | 10 | 12 | 12 | 12 | 12 |  | 50 Ohms | TOP=L2:L3=L2/L4:L6=L5/L7:BOTTOM=L7 |
| SSD_PERST#0_B14 | OTHERS | BUS | 4 | 5 | 5 | 10 | 5 | 14 | 6 | 10 | 12 | 12 | 12 | 12 |  | 50 Ohms | TOP=L2:L3=L2/L4:L6=L5/L7:BOTTOM=L7 |
| SSD_PERST#0_B14 | OTHERS | BUS | 5 | 5 | 5 | 10 | 5 | 14 | 6 | 10 | 12 | 12 | 12 | 12 |  | 50 Ohms | TOP=L2:L3=L2/L4:L6=L5/L7:BOTTOM=L7 |
| SSD_PERST#0_B14 | OTHERS | BUS | 6 | 5 | 5 | 10 | 5 | 14 | 6 | 10 | 12 | 12 | 12 | 12 |  | 50 Ohms | TOP=L2:L3=L2/L4:L6=L5/L7:BOTTOM=L7 |
| SSD_PERST#0_B14 | OTHERS | BUS | 7 | 5 | 5 | 10 | 5 | 14 | 6 | 10 | 12 | 12 | 12 | 12 |  | 50 Ohms | TOP=L2:L3=L2/L4:L6=L5/L7:BOTTOM=L7 |
| SSD_PERST#0_B14 | OTHERS | BUS | 8 | 4.75 | 5 | 10 | 5 | 14 | 6 | 9.5 | 12 | 12 | 12 | 12 |  | 50 Ohms | TOP=L2:L3=L2/L4:L6=L5/L7:BOTTOM=L7 |
| SSD_PERST#0_B2 | OTHERS | BUS | 1 | 4.75 | 5 | 10 | 5 | 14 | 6 | 9.5 | 12 | 12 | 12 | 12 |  | 50 Ohms | TOP=L2:L3=L2/L4:L6=L5/L7:BOTTOM=L7 |
| SSD_PERST#0_B2 | OTHERS | BUS | 2 | 5 | 5 | 10 | 5 | 14 | 6 | 10 | 12 | 12 | 12 | 12 |  | 50 Ohms | TOP=L2:L3=L2/L4:L6=L5/L7:BOTTOM=L7 |
| SSD_PERST#0_B2 | OTHERS | BUS | 3 | 5 | 5 | 10 | 5 | 14 | 6 | 10 | 12 | 12 | 12 | 12 |  | 50 Ohms | TOP=L2:L3=L2/L4:L6=L5/L7:BOTTOM=L7 |
| SSD_PERST#0_B2 | OTHERS | BUS | 4 | 5 | 5 | 10 | 5 | 14 | 6 | 10 | 12 | 12 | 12 | 12 |  | 50 Ohms | TOP=L2:L3=L2/L4:L6=L5/L7:BOTTOM=L7 |
| SSD_PERST#0_B2 | OTHERS | BUS | 5 | 5 | 5 | 10 | 5 | 14 | 6 | 10 | 12 | 12 | 12 | 12 |  | 50 Ohms | TOP=L2:L3=L2/L4:L6=L5/L7:BOTTOM=L7 |
| SSD_PERST#0_B2 | OTHERS | BUS | 6 | 5 | 5 | 10 | 5 | 14 | 6 | 10 | 12 | 12 | 12 | 12 |  | 50 Ohms | TOP=L2:L3=L2/L4:L6=L5/L7:BOTTOM=L7 |
| SSD_PERST#0_B2 | OTHERS | BUS | 7 | 5 | 5 | 10 | 5 | 14 | 6 | 10 | 12 | 12 | 12 | 12 |  | 50 Ohms | TOP=L2:L3=L2/L4:L6=L5/L7:BOTTOM=L7 |
| SSD_PERST#0_B2 | OTHERS | BUS | 8 | 4.75 | 5 | 10 | 5 | 14 | 6 | 9.5 | 12 | 12 | 12 | 12 |  | 50 Ohms | TOP=L2:L3=L2/L4:L6=L5/L7:BOTTOM=L7 |
| SSD_PERST#0_B3 | OTHERS | BUS | 1 | 4.75 | 5 | 10 | 5 | 14 | 6 | 9.5 | 12 | 12 | 12 | 12 |  | 50 Ohms | TOP=L2:L3=L2/L4:L6=L5/L7:BOTTOM=L7 |
| SSD_PERST#0_B3 | OTHERS | BUS | 2 | 5 | 5 | 10 | 5 | 14 | 6 | 10 | 12 | 12 | 12 | 12 |  | 50 Ohms | TOP=L2:L3=L2/L4:L6=L5/L7:BOTTOM=L7 |
| SSD_PERST#0_B3 | OTHERS | BUS | 3 | 5 | 5 | 10 | 5 | 14 | 6 | 10 | 12 | 12 | 12 | 12 |  | 50 Ohms | TOP=L2:L3=L2/L4:L6=L5/L7:BOTTOM=L7 |
| SSD_PERST#0_B3 | OTHERS | BUS | 4 | 5 | 5 | 10 | 5 | 14 | 6 | 10 | 12 | 12 | 12 | 12 |  | 50 Ohms | TOP=L2:L3=L2/L4:L6=L5/L7:BOTTOM=L7 |
| SSD_PERST#0_B3 | OTHERS | BUS | 5 | 5 | 5 | 10 | 5 | 14 | 6 | 10 | 12 | 12 | 12 | 12 |  | 50 Ohms | TOP=L2:L3=L2/L4:L6=L5/L7:BOTTOM=L7 |
| SSD_PERST#0_B3 | OTHERS | BUS | 6 | 5 | 5 | 10 | 5 | 14 | 6 | 10 | 12 | 12 | 12 | 12 |  | 50 Ohms | TOP=L2:L3=L2/L4:L6=L5/L7:BOTTOM=L7 |
| SSD_PERST#0_B3 | OTHERS | BUS | 7 | 5 | 5 | 10 | 5 | 14 | 6 | 10 | 12 | 12 | 12 | 12 |  | 50 Ohms | TOP=L2:L3=L2/L4:L6=L5/L7:BOTTOM=L7 |
| SSD_PERST#0_B3 | OTHERS | BUS | 8 | 4.75 | 5 | 10 | 5 | 14 | 6 | 9.5 | 12 | 12 | 12 | 12 |  | 50 Ohms | TOP=L2:L3=L2/L4:L6=L5/L7:BOTTOM=L7 |
| SSD_PERST#0_B4 | OTHERS | BUS | 1 | 4.75 | 5 | 10 | 5 | 14 | 6 | 9.5 | 12 | 12 | 12 | 12 |  | 50 Ohms | TOP=L2:L3=L2/L4:L6=L5/L7:BOTTOM=L7 |
| SSD_PERST#0_B4 | OTHERS | BUS | 2 | 5 | 5 | 10 | 5 | 14 | 6 | 10 | 12 | 12 | 12 | 12 |  | 50 Ohms | TOP=L2:L3=L2/L4:L6=L5/L7:BOTTOM=L7 |
| SSD_PERST#0_B4 | OTHERS | BUS | 3 | 5 | 5 | 10 | 5 | 14 | 6 | 10 | 12 | 12 | 12 | 12 |  | 50 Ohms | TOP=L2:L3=L2/L4:L6=L5/L7:BOTTOM=L7 |
| SSD_PERST#0_B4 | OTHERS | BUS | 4 | 5 | 5 | 10 | 5 | 14 | 6 | 10 | 12 | 12 | 12 | 12 |  | 50 Ohms | TOP=L2:L3=L2/L4:L6=L5/L7:BOTTOM=L7 |
| SSD_PERST#0_B4 | OTHERS | BUS | 5 | 5 | 5 | 10 | 5 | 14 | 6 | 10 | 12 | 12 | 12 | 12 |  | 50 Ohms | TOP=L2:L3=L2/L4:L6=L5/L7:BOTTOM=L7 |
| SSD_PERST#0_B4 | OTHERS | BUS | 6 | 5 | 5 | 10 | 5 | 14 | 6 | 10 | 12 | 12 | 12 | 12 |  | 50 Ohms | TOP=L2:L3=L2/L4:L6=L5/L7:BOTTOM=L7 |
| SSD_PERST#0_B4 | OTHERS | BUS | 7 | 5 | 5 | 10 | 5 | 14 | 6 | 10 | 12 | 12 | 12 | 12 |  | 50 Ohms | TOP=L2:L3=L2/L4:L6=L5/L7:BOTTOM=L7 |
| SSD_PERST#0_B4 | OTHERS | BUS | 8 | 4.75 | 5 | 10 | 5 | 14 | 6 | 9.5 | 12 | 12 | 12 | 12 |  | 50 Ohms | TOP=L2:L3=L2/L4:L6=L5/L7:BOTTOM=L7 |
| SSD_PERST#0_B5 | OTHERS | BUS | 1 | 4.75 | 5 | 10 | 5 | 14 | 6 | 9.5 | 12 | 12 | 12 | 12 |  | 50 Ohms | TOP=L2:L3=L2/L4:L6=L5/L7:BOTTOM=L7 |
| SSD_PERST#0_B5 | OTHERS | BUS | 2 | 5 | 5 | 10 | 5 | 14 | 6 | 10 | 12 | 12 | 12 | 12 |  | 50 Ohms | TOP=L2:L3=L2/L4:L6=L5/L7:BOTTOM=L7 |
| SSD_PERST#0_B5 | OTHERS | BUS | 3 | 5 | 5 | 10 | 5 | 14 | 6 | 10 | 12 | 12 | 12 | 12 |  | 50 Ohms | TOP=L2:L3=L2/L4:L6=L5/L7:BOTTOM=L7 |
| SSD_PERST#0_B5 | OTHERS | BUS | 4 | 5 | 5 | 10 | 5 | 14 | 6 | 10 | 12 | 12 | 12 | 12 |  | 50 Ohms | TOP=L2:L3=L2/L4:L6=L5/L7:BOTTOM=L7 |
| SSD_PERST#0_B5 | OTHERS | BUS | 5 | 5 | 5 | 10 | 5 | 14 | 6 | 10 | 12 | 12 | 12 | 12 |  | 50 Ohms | TOP=L2:L3=L2/L4:L6=L5/L7:BOTTOM=L7 |
| SSD_PERST#0_B5 | OTHERS | BUS | 6 | 5 | 5 | 10 | 5 | 14 | 6 | 10 | 12 | 12 | 12 | 12 |  | 50 Ohms | TOP=L2:L3=L2/L4:L6=L5/L7:BOTTOM=L7 |
| SSD_PERST#0_B5 | OTHERS | BUS | 7 | 5 | 5 | 10 | 5 | 14 | 6 | 10 | 12 | 12 | 12 | 12 |  | 50 Ohms | TOP=L2:L3=L2/L4:L6=L5/L7:BOTTOM=L7 |
| SSD_PERST#0_B5 | OTHERS | BUS | 8 | 4.75 | 5 | 10 | 5 | 14 | 6 | 9.5 | 12 | 12 | 12 | 12 |  | 50 Ohms | TOP=L2:L3=L2/L4:L6=L5/L7:BOTTOM=L7 |
| SSD_PERST#0_B6 | OTHERS | BUS | 1 | 4.75 | 5 | 10 | 5 | 14 | 6 | 9.5 | 12 | 12 | 12 | 12 |  | 50 Ohms | TOP=L2:L3=L2/L4:L6=L5/L7:BOTTOM=L7 |
| SSD_PERST#0_B6 | OTHERS | BUS | 2 | 5 | 5 | 10 | 5 | 14 | 6 | 10 | 12 | 12 | 12 | 12 |  | 50 Ohms | TOP=L2:L3=L2/L4:L6=L5/L7:BOTTOM=L7 |
| SSD_PERST#0_B6 | OTHERS | BUS | 3 | 5 | 5 | 10 | 5 | 14 | 6 | 10 | 12 | 12 | 12 | 12 |  | 50 Ohms | TOP=L2:L3=L2/L4:L6=L5/L7:BOTTOM=L7 |
| SSD_PERST#0_B6 | OTHERS | BUS | 4 | 5 | 5 | 10 | 5 | 14 | 6 | 10 | 12 | 12 | 12 | 12 |  | 50 Ohms | TOP=L2:L3=L2/L4:L6=L5/L7:BOTTOM=L7 |
| SSD_PERST#0_B6 | OTHERS | BUS | 5 | 5 | 5 | 10 | 5 | 14 | 6 | 10 | 12 | 12 | 12 | 12 |  | 50 Ohms | TOP=L2:L3=L2/L4:L6=L5/L7:BOTTOM=L7 |
| SSD_PERST#0_B6 | OTHERS | BUS | 6 | 5 | 5 | 10 | 5 | 14 | 6 | 10 | 12 | 12 | 12 | 12 |  | 50 Ohms | TOP=L2:L3=L2/L4:L6=L5/L7:BOTTOM=L7 |
| SSD_PERST#0_B6 | OTHERS | BUS | 7 | 5 | 5 | 10 | 5 | 14 | 6 | 10 | 12 | 12 | 12 | 12 |  | 50 Ohms | TOP=L2:L3=L2/L4:L6=L5/L7:BOTTOM=L7 |
| SSD_PERST#0_B6 | OTHERS | BUS | 8 | 4.75 | 5 | 10 | 5 | 14 | 6 | 9.5 | 12 | 12 | 12 | 12 |  | 50 Ohms | TOP=L2:L3=L2/L4:L6=L5/L7:BOTTOM=L7 |
| SSD_PERST#0_B7 | OTHERS | BUS | 1 | 4.75 | 5 | 10 | 5 | 14 | 6 | 9.5 | 12 | 12 | 12 | 12 |  | 50 Ohms | TOP=L2:L3=L2/L4:L6=L5/L7:BOTTOM=L7 |
| SSD_PERST#0_B7 | OTHERS | BUS | 2 | 5 | 5 | 10 | 5 | 14 | 6 | 10 | 12 | 12 | 12 | 12 |  | 50 Ohms | TOP=L2:L3=L2/L4:L6=L5/L7:BOTTOM=L7 |
| SSD_PERST#0_B7 | OTHERS | BUS | 3 | 5 | 5 | 10 | 5 | 14 | 6 | 10 | 12 | 12 | 12 | 12 |  | 50 Ohms | TOP=L2:L3=L2/L4:L6=L5/L7:BOTTOM=L7 |
| SSD_PERST#0_B7 | OTHERS | BUS | 4 | 5 | 5 | 10 | 5 | 14 | 6 | 10 | 12 | 12 | 12 | 12 |  | 50 Ohms | TOP=L2:L3=L2/L4:L6=L5/L7:BOTTOM=L7 |
| SSD_PERST#0_B7 | OTHERS | BUS | 5 | 5 | 5 | 10 | 5 | 14 | 6 | 10 | 12 | 12 | 12 | 12 |  | 50 Ohms | TOP=L2:L3=L2/L4:L6=L5/L7:BOTTOM=L7 |
| SSD_PERST#0_B7 | OTHERS | BUS | 6 | 5 | 5 | 10 | 5 | 14 | 6 | 10 | 12 | 12 | 12 | 12 |  | 50 Ohms | TOP=L2:L3=L2/L4:L6=L5/L7:BOTTOM=L7 |
| SSD_PERST#0_B7 | OTHERS | BUS | 7 | 5 | 5 | 10 | 5 | 14 | 6 | 10 | 12 | 12 | 12 | 12 |  | 50 Ohms | TOP=L2:L3=L2/L4:L6=L5/L7:BOTTOM=L7 |
| SSD_PERST#0_B7 | OTHERS | BUS | 8 | 4.75 | 5 | 10 | 5 | 14 | 6 | 9.5 | 12 | 12 | 12 | 12 |  | 50 Ohms | TOP=L2:L3=L2/L4:L6=L5/L7:BOTTOM=L7 |
| SSD_PERST#0_B8 | OTHERS | BUS | 1 | 4.75 | 5 | 10 | 5 | 14 | 6 | 9.5 | 12 | 12 | 12 | 12 |  | 50 Ohms | TOP=L2:L3=L2/L4:L6=L5/L7:BOTTOM=L7 |
| SSD_PERST#0_B8 | OTHERS | BUS | 2 | 5 | 5 | 10 | 5 | 14 | 6 | 10 | 12 | 12 | 12 | 12 |  | 50 Ohms | TOP=L2:L3=L2/L4:L6=L5/L7:BOTTOM=L7 |
| SSD_PERST#0_B8 | OTHERS | BUS | 3 | 5 | 5 | 10 | 5 | 14 | 6 | 10 | 12 | 12 | 12 | 12 |  | 50 Ohms | TOP=L2:L3=L2/L4:L6=L5/L7:BOTTOM=L7 |
| SSD_PERST#0_B8 | OTHERS | BUS | 4 | 5 | 5 | 10 | 5 | 14 | 6 | 10 | 12 | 12 | 12 | 12 |  | 50 Ohms | TOP=L2:L3=L2/L4:L6=L5/L7:BOTTOM=L7 |
| SSD_PERST#0_B8 | OTHERS | BUS | 5 | 5 | 5 | 10 | 5 | 14 | 6 | 10 | 12 | 12 | 12 | 12 |  | 50 Ohms | TOP=L2:L3=L2/L4:L6=L5/L7:BOTTOM=L7 |
| SSD_PERST#0_B8 | OTHERS | BUS | 6 | 5 | 5 | 10 | 5 | 14 | 6 | 10 | 12 | 12 | 12 | 12 |  | 50 Ohms | TOP=L2:L3=L2/L4:L6=L5/L7:BOTTOM=L7 |
| SSD_PERST#0_B8 | OTHERS | BUS | 7 | 5 | 5 | 10 | 5 | 14 | 6 | 10 | 12 | 12 | 12 | 12 |  | 50 Ohms | TOP=L2:L3=L2/L4:L6=L5/L7:BOTTOM=L7 |
| SSD_PERST#0_B8 | OTHERS | BUS | 8 | 4.75 | 5 | 10 | 5 | 14 | 6 | 9.5 | 12 | 12 | 12 | 12 |  | 50 Ohms | TOP=L2:L3=L2/L4:L6=L5/L7:BOTTOM=L7 |
| SSD_PERST#0_B9 | OTHERS | BUS | 1 | 4.75 | 5 | 10 | 5 | 14 | 6 | 9.5 | 12 | 12 | 12 | 12 |  | 50 Ohms | TOP=L2:L3=L2/L4:L6=L5/L7:BOTTOM=L7 |
| SSD_PERST#0_B9 | OTHERS | BUS | 2 | 5 | 5 | 10 | 5 | 14 | 6 | 10 | 12 | 12 | 12 | 12 |  | 50 Ohms | TOP=L2:L3=L2/L4:L6=L5/L7:BOTTOM=L7 |
| SSD_PERST#0_B9 | OTHERS | BUS | 3 | 5 | 5 | 10 | 5 | 14 | 6 | 10 | 12 | 12 | 12 | 12 |  | 50 Ohms | TOP=L2:L3=L2/L4:L6=L5/L7:BOTTOM=L7 |
| SSD_PERST#0_B9 | OTHERS | BUS | 4 | 5 | 5 | 10 | 5 | 14 | 6 | 10 | 12 | 12 | 12 | 12 |  | 50 Ohms | TOP=L2:L3=L2/L4:L6=L5/L7:BOTTOM=L7 |
| SSD_PERST#0_B9 | OTHERS | BUS | 5 | 5 | 5 | 10 | 5 | 14 | 6 | 10 | 12 | 12 | 12 | 12 |  | 50 Ohms | TOP=L2:L3=L2/L4:L6=L5/L7:BOTTOM=L7 |
| SSD_PERST#0_B9 | OTHERS | BUS | 6 | 5 | 5 | 10 | 5 | 14 | 6 | 10 | 12 | 12 | 12 | 12 |  | 50 Ohms | TOP=L2:L3=L2/L4:L6=L5/L7:BOTTOM=L7 |
| SSD_PERST#0_B9 | OTHERS | BUS | 7 | 5 | 5 | 10 | 5 | 14 | 6 | 10 | 12 | 12 | 12 | 12 |  | 50 Ohms | TOP=L2:L3=L2/L4:L6=L5/L7:BOTTOM=L7 |
| SSD_PERST#0_B9 | OTHERS | BUS | 8 | 4.75 | 5 | 10 | 5 | 14 | 6 | 9.5 | 12 | 12 | 12 | 12 |  | 50 Ohms | TOP=L2:L3=L2/L4:L6=L5/L7:BOTTOM=L7 |
| SSD_PERST#0_R | OTHERS | BUS | 1 | 4.75 | 5 | 10 | 5 | 14 | 6 | 9.5 | 12 | 12 | 12 | 12 |  | 50 Ohms | TOP=L2:L3=L2/L4:L6=L5/L7:BOTTOM=L7 |
| SSD_PERST#0_R | OTHERS | BUS | 2 | 5 | 5 | 10 | 5 | 14 | 6 | 10 | 12 | 12 | 12 | 12 |  | 50 Ohms | TOP=L2:L3=L2/L4:L6=L5/L7:BOTTOM=L7 |
| SSD_PERST#0_R | OTHERS | BUS | 3 | 5 | 5 | 10 | 5 | 14 | 6 | 10 | 12 | 12 | 12 | 12 |  | 50 Ohms | TOP=L2:L3=L2/L4:L6=L5/L7:BOTTOM=L7 |
| SSD_PERST#0_R | OTHERS | BUS | 4 | 5 | 5 | 10 | 5 | 14 | 6 | 10 | 12 | 12 | 12 | 12 |  | 50 Ohms | TOP=L2:L3=L2/L4:L6=L5/L7:BOTTOM=L7 |
| SSD_PERST#0_R | OTHERS | BUS | 5 | 5 | 5 | 10 | 5 | 14 | 6 | 10 | 12 | 12 | 12 | 12 |  | 50 Ohms | TOP=L2:L3=L2/L4:L6=L5/L7:BOTTOM=L7 |
| SSD_PERST#0_R | OTHERS | BUS | 6 | 5 | 5 | 10 | 5 | 14 | 6 | 10 | 12 | 12 | 12 | 12 |  | 50 Ohms | TOP=L2:L3=L2/L4:L6=L5/L7:BOTTOM=L7 |
| SSD_PERST#0_R | OTHERS | BUS | 7 | 5 | 5 | 10 | 5 | 14 | 6 | 10 | 12 | 12 | 12 | 12 |  | 50 Ohms | TOP=L2:L3=L2/L4:L6=L5/L7:BOTTOM=L7 |
| SSD_PERST#0_R | OTHERS | BUS | 8 | 4.75 | 5 | 10 | 5 | 14 | 6 | 9.5 | 12 | 12 | 12 | 12 |  | 50 Ohms | TOP=L2:L3=L2/L4:L6=L5/L7:BOTTOM=L7 |
| SSD_PERST#1 | OTHERS | BUS | 1 | 4.75 | 5 | 10 | 5 | 14 | 6 | 9.5 | 12 | 12 | 12 | 12 |  | 50 Ohms | TOP=L2:L3=L2/L4:L6=L5/L7:BOTTOM=L7 |
| SSD_PERST#1 | OTHERS | BUS | 2 | 5 | 5 | 10 | 5 | 14 | 6 | 10 | 12 | 12 | 12 | 12 |  | 50 Ohms | TOP=L2:L3=L2/L4:L6=L5/L7:BOTTOM=L7 |
| SSD_PERST#1 | OTHERS | BUS | 3 | 5 | 5 | 10 | 5 | 14 | 6 | 10 | 12 | 12 | 12 | 12 |  | 50 Ohms | TOP=L2:L3=L2/L4:L6=L5/L7:BOTTOM=L7 |
| SSD_PERST#1 | OTHERS | BUS | 4 | 5 | 5 | 10 | 5 | 14 | 6 | 10 | 12 | 12 | 12 | 12 |  | 50 Ohms | TOP=L2:L3=L2/L4:L6=L5/L7:BOTTOM=L7 |
| SSD_PERST#1 | OTHERS | BUS | 5 | 5 | 5 | 10 | 5 | 14 | 6 | 10 | 12 | 12 | 12 | 12 |  | 50 Ohms | TOP=L2:L3=L2/L4:L6=L5/L7:BOTTOM=L7 |
| SSD_PERST#1 | OTHERS | BUS | 6 | 5 | 5 | 10 | 5 | 14 | 6 | 10 | 12 | 12 | 12 | 12 |  | 50 Ohms | TOP=L2:L3=L2/L4:L6=L5/L7:BOTTOM=L7 |
| SSD_PERST#1 | OTHERS | BUS | 7 | 5 | 5 | 10 | 5 | 14 | 6 | 10 | 12 | 12 | 12 | 12 |  | 50 Ohms | TOP=L2:L3=L2/L4:L6=L5/L7:BOTTOM=L7 |
| SSD_PERST#1 | OTHERS | BUS | 8 | 4.75 | 5 | 10 | 5 | 14 | 6 | 9.5 | 12 | 12 | 12 | 12 |  | 50 Ohms | TOP=L2:L3=L2/L4:L6=L5/L7:BOTTOM=L7 |
| SSD_PERST#1_R | OTHERS | BUS | 1 | 4.75 | 5 | 10 | 5 | 14 | 6 | 9.5 | 12 | 12 | 12 | 12 |  | 50 Ohms | TOP=L2:L3=L2/L4:L6=L5/L7:BOTTOM=L7 |
| SSD_PERST#1_R | OTHERS | BUS | 2 | 5 | 5 | 10 | 5 | 14 | 6 | 10 | 12 | 12 | 12 | 12 |  | 50 Ohms | TOP=L2:L3=L2/L4:L6=L5/L7:BOTTOM=L7 |
| SSD_PERST#1_R | OTHERS | BUS | 3 | 5 | 5 | 10 | 5 | 14 | 6 | 10 | 12 | 12 | 12 | 12 |  | 50 Ohms | TOP=L2:L3=L2/L4:L6=L5/L7:BOTTOM=L7 |
| SSD_PERST#1_R | OTHERS | BUS | 4 | 5 | 5 | 10 | 5 | 14 | 6 | 10 | 12 | 12 | 12 | 12 |  | 50 Ohms | TOP=L2:L3=L2/L4:L6=L5/L7:BOTTOM=L7 |
| SSD_PERST#1_R | OTHERS | BUS | 5 | 5 | 5 | 10 | 5 | 14 | 6 | 10 | 12 | 12 | 12 | 12 |  | 50 Ohms | TOP=L2:L3=L2/L4:L6=L5/L7:BOTTOM=L7 |
| SSD_PERST#1_R | OTHERS | BUS | 6 | 5 | 5 | 10 | 5 | 14 | 6 | 10 | 12 | 12 | 12 | 12 |  | 50 Ohms | TOP=L2:L3=L2/L4:L6=L5/L7:BOTTOM=L7 |
| SSD_PERST#1_R | OTHERS | BUS | 7 | 5 | 5 | 10 | 5 | 14 | 6 | 10 | 12 | 12 | 12 | 12 |  | 50 Ohms | TOP=L2:L3=L2/L4:L6=L5/L7:BOTTOM=L7 |
| SSD_PERST#1_R | OTHERS | BUS | 8 | 4.75 | 5 | 10 | 5 | 14 | 6 | 9.5 | 12 | 12 | 12 | 12 |  | 50 Ohms | TOP=L2:L3=L2/L4:L6=L5/L7:BOTTOM=L7 |
| SSD_PERST#10 | OTHERS | BUS | 1 | 4.75 | 5 | 10 | 5 | 14 | 6 | 9.5 | 12 | 12 | 12 | 12 |  | 50 Ohms | TOP=L2:L3=L2/L4:L6=L5/L7:BOTTOM=L7 |
| SSD_PERST#10 | OTHERS | BUS | 2 | 5 | 5 | 10 | 5 | 14 | 6 | 10 | 12 | 12 | 12 | 12 |  | 50 Ohms | TOP=L2:L3=L2/L4:L6=L5/L7:BOTTOM=L7 |
| SSD_PERST#10 | OTHERS | BUS | 3 | 5 | 5 | 10 | 5 | 14 | 6 | 10 | 12 | 12 | 12 | 12 |  | 50 Ohms | TOP=L2:L3=L2/L4:L6=L5/L7:BOTTOM=L7 |
| SSD_PERST#10 | OTHERS | BUS | 4 | 5 | 5 | 10 | 5 | 14 | 6 | 10 | 12 | 12 | 12 | 12 |  | 50 Ohms | TOP=L2:L3=L2/L4:L6=L5/L7:BOTTOM=L7 |
| SSD_PERST#10 | OTHERS | BUS | 5 | 5 | 5 | 10 | 5 | 14 | 6 | 10 | 12 | 12 | 12 | 12 |  | 50 Ohms | TOP=L2:L3=L2/L4:L6=L5/L7:BOTTOM=L7 |
| SSD_PERST#10 | OTHERS | BUS | 6 | 5 | 5 | 10 | 5 | 14 | 6 | 10 | 12 | 12 | 12 | 12 |  | 50 Ohms | TOP=L2:L3=L2/L4:L6=L5/L7:BOTTOM=L7 |
| SSD_PERST#10 | OTHERS | BUS | 7 | 5 | 5 | 10 | 5 | 14 | 6 | 10 | 12 | 12 | 12 | 12 |  | 50 Ohms | TOP=L2:L3=L2/L4:L6=L5/L7:BOTTOM=L7 |
| SSD_PERST#10 | OTHERS | BUS | 8 | 4.75 | 5 | 10 | 5 | 14 | 6 | 9.5 | 12 | 12 | 12 | 12 |  | 50 Ohms | TOP=L2:L3=L2/L4:L6=L5/L7:BOTTOM=L7 |
| SSD_PERST#10_R | OTHERS | BUS | 1 | 4.75 | 5 | 10 | 5 | 14 | 6 | 9.5 | 12 | 12 | 12 | 12 |  | 50 Ohms | TOP=L2:L3=L2/L4:L6=L5/L7:BOTTOM=L7 |
| SSD_PERST#10_R | OTHERS | BUS | 2 | 5 | 5 | 10 | 5 | 14 | 6 | 10 | 12 | 12 | 12 | 12 |  | 50 Ohms | TOP=L2:L3=L2/L4:L6=L5/L7:BOTTOM=L7 |
| SSD_PERST#10_R | OTHERS | BUS | 3 | 5 | 5 | 10 | 5 | 14 | 6 | 10 | 12 | 12 | 12 | 12 |  | 50 Ohms | TOP=L2:L3=L2/L4:L6=L5/L7:BOTTOM=L7 |
| SSD_PERST#10_R | OTHERS | BUS | 4 | 5 | 5 | 10 | 5 | 14 | 6 | 10 | 12 | 12 | 12 | 12 |  | 50 Ohms | TOP=L2:L3=L2/L4:L6=L5/L7:BOTTOM=L7 |
| SSD_PERST#10_R | OTHERS | BUS | 5 | 5 | 5 | 10 | 5 | 14 | 6 | 10 | 12 | 12 | 12 | 12 |  | 50 Ohms | TOP=L2:L3=L2/L4:L6=L5/L7:BOTTOM=L7 |
| SSD_PERST#10_R | OTHERS | BUS | 6 | 5 | 5 | 10 | 5 | 14 | 6 | 10 | 12 | 12 | 12 | 12 |  | 50 Ohms | TOP=L2:L3=L2/L4:L6=L5/L7:BOTTOM=L7 |
| SSD_PERST#10_R | OTHERS | BUS | 7 | 5 | 5 | 10 | 5 | 14 | 6 | 10 | 12 | 12 | 12 | 12 |  | 50 Ohms | TOP=L2:L3=L2/L4:L6=L5/L7:BOTTOM=L7 |
| SSD_PERST#10_R | OTHERS | BUS | 8 | 4.75 | 5 | 10 | 5 | 14 | 6 | 9.5 | 12 | 12 | 12 | 12 |  | 50 Ohms | TOP=L2:L3=L2/L4:L6=L5/L7:BOTTOM=L7 |
| SSD_PERST#11 | OTHERS | BUS | 1 | 4.75 | 5 | 10 | 5 | 14 | 6 | 9.5 | 12 | 12 | 12 | 12 |  | 50 Ohms | TOP=L2:L3=L2/L4:L6=L5/L7:BOTTOM=L7 |
| SSD_PERST#11 | OTHERS | BUS | 2 | 5 | 5 | 10 | 5 | 14 | 6 | 10 | 12 | 12 | 12 | 12 |  | 50 Ohms | TOP=L2:L3=L2/L4:L6=L5/L7:BOTTOM=L7 |
| SSD_PERST#11 | OTHERS | BUS | 3 | 5 | 5 | 10 | 5 | 14 | 6 | 10 | 12 | 12 | 12 | 12 |  | 50 Ohms | TOP=L2:L3=L2/L4:L6=L5/L7:BOTTOM=L7 |
| SSD_PERST#11 | OTHERS | BUS | 4 | 5 | 5 | 10 | 5 | 14 | 6 | 10 | 12 | 12 | 12 | 12 |  | 50 Ohms | TOP=L2:L3=L2/L4:L6=L5/L7:BOTTOM=L7 |
| SSD_PERST#11 | OTHERS | BUS | 5 | 5 | 5 | 10 | 5 | 14 | 6 | 10 | 12 | 12 | 12 | 12 |  | 50 Ohms | TOP=L2:L3=L2/L4:L6=L5/L7:BOTTOM=L7 |
| SSD_PERST#11 | OTHERS | BUS | 6 | 5 | 5 | 10 | 5 | 14 | 6 | 10 | 12 | 12 | 12 | 12 |  | 50 Ohms | TOP=L2:L3=L2/L4:L6=L5/L7:BOTTOM=L7 |
| SSD_PERST#11 | OTHERS | BUS | 7 | 5 | 5 | 10 | 5 | 14 | 6 | 10 | 12 | 12 | 12 | 12 |  | 50 Ohms | TOP=L2:L3=L2/L4:L6=L5/L7:BOTTOM=L7 |
| SSD_PERST#11 | OTHERS | BUS | 8 | 4.75 | 5 | 10 | 5 | 14 | 6 | 9.5 | 12 | 12 | 12 | 12 |  | 50 Ohms | TOP=L2:L3=L2/L4:L6=L5/L7:BOTTOM=L7 |
| SSD_PERST#11_R | OTHERS | BUS | 1 | 4.75 | 5 | 10 | 5 | 14 | 6 | 9.5 | 12 | 12 | 12 | 12 |  | 50 Ohms | TOP=L2:L3=L2/L4:L6=L5/L7:BOTTOM=L7 |
| SSD_PERST#11_R | OTHERS | BUS | 2 | 5 | 5 | 10 | 5 | 14 | 6 | 10 | 12 | 12 | 12 | 12 |  | 50 Ohms | TOP=L2:L3=L2/L4:L6=L5/L7:BOTTOM=L7 |
| SSD_PERST#11_R | OTHERS | BUS | 3 | 5 | 5 | 10 | 5 | 14 | 6 | 10 | 12 | 12 | 12 | 12 |  | 50 Ohms | TOP=L2:L3=L2/L4:L6=L5/L7:BOTTOM=L7 |
| SSD_PERST#11_R | OTHERS | BUS | 4 | 5 | 5 | 10 | 5 | 14 | 6 | 10 | 12 | 12 | 12 | 12 |  | 50 Ohms | TOP=L2:L3=L2/L4:L6=L5/L7:BOTTOM=L7 |
| SSD_PERST#11_R | OTHERS | BUS | 5 | 5 | 5 | 10 | 5 | 14 | 6 | 10 | 12 | 12 | 12 | 12 |  | 50 Ohms | TOP=L2:L3=L2/L4:L6=L5/L7:BOTTOM=L7 |
| SSD_PERST#11_R | OTHERS | BUS | 6 | 5 | 5 | 10 | 5 | 14 | 6 | 10 | 12 | 12 | 12 | 12 |  | 50 Ohms | TOP=L2:L3=L2/L4:L6=L5/L7:BOTTOM=L7 |
| SSD_PERST#11_R | OTHERS | BUS | 7 | 5 | 5 | 10 | 5 | 14 | 6 | 10 | 12 | 12 | 12 | 12 |  | 50 Ohms | TOP=L2:L3=L2/L4:L6=L5/L7:BOTTOM=L7 |
| SSD_PERST#11_R | OTHERS | BUS | 8 | 4.75 | 5 | 10 | 5 | 14 | 6 | 9.5 | 12 | 12 | 12 | 12 |  | 50 Ohms | TOP=L2:L3=L2/L4:L6=L5/L7:BOTTOM=L7 |
| SSD_PERST#12 | OTHERS | BUS | 1 | 4.75 | 5 | 10 | 5 | 14 | 6 | 9.5 | 12 | 12 | 12 | 12 |  | 50 Ohms | TOP=L2:L3=L2/L4:L6=L5/L7:BOTTOM=L7 |
| SSD_PERST#12 | OTHERS | BUS | 2 | 5 | 5 | 10 | 5 | 14 | 6 | 10 | 12 | 12 | 12 | 12 |  | 50 Ohms | TOP=L2:L3=L2/L4:L6=L5/L7:BOTTOM=L7 |
| SSD_PERST#12 | OTHERS | BUS | 3 | 5 | 5 | 10 | 5 | 14 | 6 | 10 | 12 | 12 | 12 | 12 |  | 50 Ohms | TOP=L2:L3=L2/L4:L6=L5/L7:BOTTOM=L7 |
| SSD_PERST#12 | OTHERS | BUS | 4 | 5 | 5 | 10 | 5 | 14 | 6 | 10 | 12 | 12 | 12 | 12 |  | 50 Ohms | TOP=L2:L3=L2/L4:L6=L5/L7:BOTTOM=L7 |
| SSD_PERST#12 | OTHERS | BUS | 5 | 5 | 5 | 10 | 5 | 14 | 6 | 10 | 12 | 12 | 12 | 12 |  | 50 Ohms | TOP=L2:L3=L2/L4:L6=L5/L7:BOTTOM=L7 |
| SSD_PERST#12 | OTHERS | BUS | 6 | 5 | 5 | 10 | 5 | 14 | 6 | 10 | 12 | 12 | 12 | 12 |  | 50 Ohms | TOP=L2:L3=L2/L4:L6=L5/L7:BOTTOM=L7 |
| SSD_PERST#12 | OTHERS | BUS | 7 | 5 | 5 | 10 | 5 | 14 | 6 | 10 | 12 | 12 | 12 | 12 |  | 50 Ohms | TOP=L2:L3=L2/L4:L6=L5/L7:BOTTOM=L7 |
| SSD_PERST#12 | OTHERS | BUS | 8 | 4.75 | 5 | 10 | 5 | 14 | 6 | 9.5 | 12 | 12 | 12 | 12 |  | 50 Ohms | TOP=L2:L3=L2/L4:L6=L5/L7:BOTTOM=L7 |
| SSD_PERST#12_R | OTHERS | BUS | 1 | 4.75 | 5 | 10 | 5 | 14 | 6 | 9.5 | 12 | 12 | 12 | 12 |  | 50 Ohms | TOP=L2:L3=L2/L4:L6=L5/L7:BOTTOM=L7 |
| SSD_PERST#12_R | OTHERS | BUS | 2 | 5 | 5 | 10 | 5 | 14 | 6 | 10 | 12 | 12 | 12 | 12 |  | 50 Ohms | TOP=L2:L3=L2/L4:L6=L5/L7:BOTTOM=L7 |
| SSD_PERST#12_R | OTHERS | BUS | 3 | 5 | 5 | 10 | 5 | 14 | 6 | 10 | 12 | 12 | 12 | 12 |  | 50 Ohms | TOP=L2:L3=L2/L4:L6=L5/L7:BOTTOM=L7 |
| SSD_PERST#12_R | OTHERS | BUS | 4 | 5 | 5 | 10 | 5 | 14 | 6 | 10 | 12 | 12 | 12 | 12 |  | 50 Ohms | TOP=L2:L3=L2/L4:L6=L5/L7:BOTTOM=L7 |
| SSD_PERST#12_R | OTHERS | BUS | 5 | 5 | 5 | 10 | 5 | 14 | 6 | 10 | 12 | 12 | 12 | 12 |  | 50 Ohms | TOP=L2:L3=L2/L4:L6=L5/L7:BOTTOM=L7 |
| SSD_PERST#12_R | OTHERS | BUS | 6 | 5 | 5 | 10 | 5 | 14 | 6 | 10 | 12 | 12 | 12 | 12 |  | 50 Ohms | TOP=L2:L3=L2/L4:L6=L5/L7:BOTTOM=L7 |
| SSD_PERST#12_R | OTHERS | BUS | 7 | 5 | 5 | 10 | 5 | 14 | 6 | 10 | 12 | 12 | 12 | 12 |  | 50 Ohms | TOP=L2:L3=L2/L4:L6=L5/L7:BOTTOM=L7 |
| SSD_PERST#12_R | OTHERS | BUS | 8 | 4.75 | 5 | 10 | 5 | 14 | 6 | 9.5 | 12 | 12 | 12 | 12 |  | 50 Ohms | TOP=L2:L3=L2/L4:L6=L5/L7:BOTTOM=L7 |
| SSD_PERST#13 | OTHERS | BUS | 1 | 4.75 | 5 | 10 | 5 | 14 | 6 | 9.5 | 12 | 12 | 12 | 12 |  | 50 Ohms | TOP=L2:L3=L2/L4:L6=L5/L7:BOTTOM=L7 |
| SSD_PERST#13 | OTHERS | BUS | 2 | 5 | 5 | 10 | 5 | 14 | 6 | 10 | 12 | 12 | 12 | 12 |  | 50 Ohms | TOP=L2:L3=L2/L4:L6=L5/L7:BOTTOM=L7 |
| SSD_PERST#13 | OTHERS | BUS | 3 | 5 | 5 | 10 | 5 | 14 | 6 | 10 | 12 | 12 | 12 | 12 |  | 50 Ohms | TOP=L2:L3=L2/L4:L6=L5/L7:BOTTOM=L7 |
| SSD_PERST#13 | OTHERS | BUS | 4 | 5 | 5 | 10 | 5 | 14 | 6 | 10 | 12 | 12 | 12 | 12 |  | 50 Ohms | TOP=L2:L3=L2/L4:L6=L5/L7:BOTTOM=L7 |
| SSD_PERST#13 | OTHERS | BUS | 5 | 5 | 5 | 10 | 5 | 14 | 6 | 10 | 12 | 12 | 12 | 12 |  | 50 Ohms | TOP=L2:L3=L2/L4:L6=L5/L7:BOTTOM=L7 |
| SSD_PERST#13 | OTHERS | BUS | 6 | 5 | 5 | 10 | 5 | 14 | 6 | 10 | 12 | 12 | 12 | 12 |  | 50 Ohms | TOP=L2:L3=L2/L4:L6=L5/L7:BOTTOM=L7 |
| SSD_PERST#13 | OTHERS | BUS | 7 | 5 | 5 | 10 | 5 | 14 | 6 | 10 | 12 | 12 | 12 | 12 |  | 50 Ohms | TOP=L2:L3=L2/L4:L6=L5/L7:BOTTOM=L7 |
| SSD_PERST#13 | OTHERS | BUS | 8 | 4.75 | 5 | 10 | 5 | 14 | 6 | 9.5 | 12 | 12 | 12 | 12 |  | 50 Ohms | TOP=L2:L3=L2/L4:L6=L5/L7:BOTTOM=L7 |
| SSD_PERST#13_R | OTHERS | BUS | 1 | 4.75 | 5 | 10 | 5 | 14 | 6 | 9.5 | 12 | 12 | 12 | 12 |  | 50 Ohms | TOP=L2:L3=L2/L4:L6=L5/L7:BOTTOM=L7 |
| SSD_PERST#13_R | OTHERS | BUS | 2 | 5 | 5 | 10 | 5 | 14 | 6 | 10 | 12 | 12 | 12 | 12 |  | 50 Ohms | TOP=L2:L3=L2/L4:L6=L5/L7:BOTTOM=L7 |
| SSD_PERST#13_R | OTHERS | BUS | 3 | 5 | 5 | 10 | 5 | 14 | 6 | 10 | 12 | 12 | 12 | 12 |  | 50 Ohms | TOP=L2:L3=L2/L4:L6=L5/L7:BOTTOM=L7 |
| SSD_PERST#13_R | OTHERS | BUS | 4 | 5 | 5 | 10 | 5 | 14 | 6 | 10 | 12 | 12 | 12 | 12 |  | 50 Ohms | TOP=L2:L3=L2/L4:L6=L5/L7:BOTTOM=L7 |
| SSD_PERST#13_R | OTHERS | BUS | 5 | 5 | 5 | 10 | 5 | 14 | 6 | 10 | 12 | 12 | 12 | 12 |  | 50 Ohms | TOP=L2:L3=L2/L4:L6=L5/L7:BOTTOM=L7 |
| SSD_PERST#13_R | OTHERS | BUS | 6 | 5 | 5 | 10 | 5 | 14 | 6 | 10 | 12 | 12 | 12 | 12 |  | 50 Ohms | TOP=L2:L3=L2/L4:L6=L5/L7:BOTTOM=L7 |
| SSD_PERST#13_R | OTHERS | BUS | 7 | 5 | 5 | 10 | 5 | 14 | 6 | 10 | 12 | 12 | 12 | 12 |  | 50 Ohms | TOP=L2:L3=L2/L4:L6=L5/L7:BOTTOM=L7 |
| SSD_PERST#13_R | OTHERS | BUS | 8 | 4.75 | 5 | 10 | 5 | 14 | 6 | 9.5 | 12 | 12 | 12 | 12 |  | 50 Ohms | TOP=L2:L3=L2/L4:L6=L5/L7:BOTTOM=L7 |
| SSD_PERST#14 | OTHERS | BUS | 1 | 4.75 | 5 | 10 | 5 | 14 | 6 | 9.5 | 12 | 12 | 12 | 12 |  | 50 Ohms | TOP=L2:L3=L2/L4:L6=L5/L7:BOTTOM=L7 |
| SSD_PERST#14 | OTHERS | BUS | 2 | 5 | 5 | 10 | 5 | 14 | 6 | 10 | 12 | 12 | 12 | 12 |  | 50 Ohms | TOP=L2:L3=L2/L4:L6=L5/L7:BOTTOM=L7 |
| SSD_PERST#14 | OTHERS | BUS | 3 | 5 | 5 | 10 | 5 | 14 | 6 | 10 | 12 | 12 | 12 | 12 |  | 50 Ohms | TOP=L2:L3=L2/L4:L6=L5/L7:BOTTOM=L7 |
| SSD_PERST#14 | OTHERS | BUS | 4 | 5 | 5 | 10 | 5 | 14 | 6 | 10 | 12 | 12 | 12 | 12 |  | 50 Ohms | TOP=L2:L3=L2/L4:L6=L5/L7:BOTTOM=L7 |
| SSD_PERST#14 | OTHERS | BUS | 5 | 5 | 5 | 10 | 5 | 14 | 6 | 10 | 12 | 12 | 12 | 12 |  | 50 Ohms | TOP=L2:L3=L2/L4:L6=L5/L7:BOTTOM=L7 |
| SSD_PERST#14 | OTHERS | BUS | 6 | 5 | 5 | 10 | 5 | 14 | 6 | 10 | 12 | 12 | 12 | 12 |  | 50 Ohms | TOP=L2:L3=L2/L4:L6=L5/L7:BOTTOM=L7 |
| SSD_PERST#14 | OTHERS | BUS | 7 | 5 | 5 | 10 | 5 | 14 | 6 | 10 | 12 | 12 | 12 | 12 |  | 50 Ohms | TOP=L2:L3=L2/L4:L6=L5/L7:BOTTOM=L7 |
| SSD_PERST#14 | OTHERS | BUS | 8 | 4.75 | 5 | 10 | 5 | 14 | 6 | 9.5 | 12 | 12 | 12 | 12 |  | 50 Ohms | TOP=L2:L3=L2/L4:L6=L5/L7:BOTTOM=L7 |
| SSD_PERST#14_R | OTHERS | BUS | 1 | 4.75 | 5 | 10 | 5 | 14 | 6 | 9.5 | 12 | 12 | 12 | 12 |  | 50 Ohms | TOP=L2:L3=L2/L4:L6=L5/L7:BOTTOM=L7 |
| SSD_PERST#14_R | OTHERS | BUS | 2 | 5 | 5 | 10 | 5 | 14 | 6 | 10 | 12 | 12 | 12 | 12 |  | 50 Ohms | TOP=L2:L3=L2/L4:L6=L5/L7:BOTTOM=L7 |
| SSD_PERST#14_R | OTHERS | BUS | 3 | 5 | 5 | 10 | 5 | 14 | 6 | 10 | 12 | 12 | 12 | 12 |  | 50 Ohms | TOP=L2:L3=L2/L4:L6=L5/L7:BOTTOM=L7 |
| SSD_PERST#14_R | OTHERS | BUS | 4 | 5 | 5 | 10 | 5 | 14 | 6 | 10 | 12 | 12 | 12 | 12 |  | 50 Ohms | TOP=L2:L3=L2/L4:L6=L5/L7:BOTTOM=L7 |
| SSD_PERST#14_R | OTHERS | BUS | 5 | 5 | 5 | 10 | 5 | 14 | 6 | 10 | 12 | 12 | 12 | 12 |  | 50 Ohms | TOP=L2:L3=L2/L4:L6=L5/L7:BOTTOM=L7 |
| SSD_PERST#14_R | OTHERS | BUS | 6 | 5 | 5 | 10 | 5 | 14 | 6 | 10 | 12 | 12 | 12 | 12 |  | 50 Ohms | TOP=L2:L3=L2/L4:L6=L5/L7:BOTTOM=L7 |
| SSD_PERST#14_R | OTHERS | BUS | 7 | 5 | 5 | 10 | 5 | 14 | 6 | 10 | 12 | 12 | 12 | 12 |  | 50 Ohms | TOP=L2:L3=L2/L4:L6=L5/L7:BOTTOM=L7 |
| SSD_PERST#14_R | OTHERS | BUS | 8 | 4.75 | 5 | 10 | 5 | 14 | 6 | 9.5 | 12 | 12 | 12 | 12 |  | 50 Ohms | TOP=L2:L3=L2/L4:L6=L5/L7:BOTTOM=L7 |
| SSD_PERST#2 | OTHERS | BUS | 1 | 4.75 | 5 | 10 | 5 | 14 | 6 | 9.5 | 12 | 12 | 12 | 12 |  | 50 Ohms | TOP=L2:L3=L2/L4:L6=L5/L7:BOTTOM=L7 |
| SSD_PERST#2 | OTHERS | BUS | 2 | 5 | 5 | 10 | 5 | 14 | 6 | 10 | 12 | 12 | 12 | 12 |  | 50 Ohms | TOP=L2:L3=L2/L4:L6=L5/L7:BOTTOM=L7 |
| SSD_PERST#2 | OTHERS | BUS | 3 | 5 | 5 | 10 | 5 | 14 | 6 | 10 | 12 | 12 | 12 | 12 |  | 50 Ohms | TOP=L2:L3=L2/L4:L6=L5/L7:BOTTOM=L7 |
| SSD_PERST#2 | OTHERS | BUS | 4 | 5 | 5 | 10 | 5 | 14 | 6 | 10 | 12 | 12 | 12 | 12 |  | 50 Ohms | TOP=L2:L3=L2/L4:L6=L5/L7:BOTTOM=L7 |
| SSD_PERST#2 | OTHERS | BUS | 5 | 5 | 5 | 10 | 5 | 14 | 6 | 10 | 12 | 12 | 12 | 12 |  | 50 Ohms | TOP=L2:L3=L2/L4:L6=L5/L7:BOTTOM=L7 |
| SSD_PERST#2 | OTHERS | BUS | 6 | 5 | 5 | 10 | 5 | 14 | 6 | 10 | 12 | 12 | 12 | 12 |  | 50 Ohms | TOP=L2:L3=L2/L4:L6=L5/L7:BOTTOM=L7 |
| SSD_PERST#2 | OTHERS | BUS | 7 | 5 | 5 | 10 | 5 | 14 | 6 | 10 | 12 | 12 | 12 | 12 |  | 50 Ohms | TOP=L2:L3=L2/L4:L6=L5/L7:BOTTOM=L7 |
| SSD_PERST#2 | OTHERS | BUS | 8 | 4.75 | 5 | 10 | 5 | 14 | 6 | 9.5 | 12 | 12 | 12 | 12 |  | 50 Ohms | TOP=L2:L3=L2/L4:L6=L5/L7:BOTTOM=L7 |
| SSD_PERST#2_R | OTHERS | BUS | 1 | 4.75 | 5 | 10 | 5 | 14 | 6 | 9.5 | 12 | 12 | 12 | 12 |  | 50 Ohms | TOP=L2:L3=L2/L4:L6=L5/L7:BOTTOM=L7 |
| SSD_PERST#2_R | OTHERS | BUS | 2 | 5 | 5 | 10 | 5 | 14 | 6 | 10 | 12 | 12 | 12 | 12 |  | 50 Ohms | TOP=L2:L3=L2/L4:L6=L5/L7:BOTTOM=L7 |
| SSD_PERST#2_R | OTHERS | BUS | 3 | 5 | 5 | 10 | 5 | 14 | 6 | 10 | 12 | 12 | 12 | 12 |  | 50 Ohms | TOP=L2:L3=L2/L4:L6=L5/L7:BOTTOM=L7 |
| SSD_PERST#2_R | OTHERS | BUS | 4 | 5 | 5 | 10 | 5 | 14 | 6 | 10 | 12 | 12 | 12 | 12 |  | 50 Ohms | TOP=L2:L3=L2/L4:L6=L5/L7:BOTTOM=L7 |
| SSD_PERST#2_R | OTHERS | BUS | 5 | 5 | 5 | 10 | 5 | 14 | 6 | 10 | 12 | 12 | 12 | 12 |  | 50 Ohms | TOP=L2:L3=L2/L4:L6=L5/L7:BOTTOM=L7 |
| SSD_PERST#2_R | OTHERS | BUS | 6 | 5 | 5 | 10 | 5 | 14 | 6 | 10 | 12 | 12 | 12 | 12 |  | 50 Ohms | TOP=L2:L3=L2/L4:L6=L5/L7:BOTTOM=L7 |
| SSD_PERST#2_R | OTHERS | BUS | 7 | 5 | 5 | 10 | 5 | 14 | 6 | 10 | 12 | 12 | 12 | 12 |  | 50 Ohms | TOP=L2:L3=L2/L4:L6=L5/L7:BOTTOM=L7 |
| SSD_PERST#2_R | OTHERS | BUS | 8 | 4.75 | 5 | 10 | 5 | 14 | 6 | 9.5 | 12 | 12 | 12 | 12 |  | 50 Ohms | TOP=L2:L3=L2/L4:L6=L5/L7:BOTTOM=L7 |
| SSD_PERST#3 | OTHERS | BUS | 1 | 4.75 | 5 | 10 | 5 | 14 | 6 | 9.5 | 12 | 12 | 12 | 12 |  | 50 Ohms | TOP=L2:L3=L2/L4:L6=L5/L7:BOTTOM=L7 |
| SSD_PERST#3 | OTHERS | BUS | 2 | 5 | 5 | 10 | 5 | 14 | 6 | 10 | 12 | 12 | 12 | 12 |  | 50 Ohms | TOP=L2:L3=L2/L4:L6=L5/L7:BOTTOM=L7 |
| SSD_PERST#3 | OTHERS | BUS | 3 | 5 | 5 | 10 | 5 | 14 | 6 | 10 | 12 | 12 | 12 | 12 |  | 50 Ohms | TOP=L2:L3=L2/L4:L6=L5/L7:BOTTOM=L7 |
| SSD_PERST#3 | OTHERS | BUS | 4 | 5 | 5 | 10 | 5 | 14 | 6 | 10 | 12 | 12 | 12 | 12 |  | 50 Ohms | TOP=L2:L3=L2/L4:L6=L5/L7:BOTTOM=L7 |
| SSD_PERST#3 | OTHERS | BUS | 5 | 5 | 5 | 10 | 5 | 14 | 6 | 10 | 12 | 12 | 12 | 12 |  | 50 Ohms | TOP=L2:L3=L2/L4:L6=L5/L7:BOTTOM=L7 |
| SSD_PERST#3 | OTHERS | BUS | 6 | 5 | 5 | 10 | 5 | 14 | 6 | 10 | 12 | 12 | 12 | 12 |  | 50 Ohms | TOP=L2:L3=L2/L4:L6=L5/L7:BOTTOM=L7 |
| SSD_PERST#3 | OTHERS | BUS | 7 | 5 | 5 | 10 | 5 | 14 | 6 | 10 | 12 | 12 | 12 | 12 |  | 50 Ohms | TOP=L2:L3=L2/L4:L6=L5/L7:BOTTOM=L7 |
| SSD_PERST#3 | OTHERS | BUS | 8 | 4.75 | 5 | 10 | 5 | 14 | 6 | 9.5 | 12 | 12 | 12 | 12 |  | 50 Ohms | TOP=L2:L3=L2/L4:L6=L5/L7:BOTTOM=L7 |
| SSD_PERST#3_R | OTHERS | BUS | 1 | 4.75 | 5 | 10 | 5 | 14 | 6 | 9.5 | 12 | 12 | 12 | 12 |  | 50 Ohms | TOP=L2:L3=L2/L4:L6=L5/L7:BOTTOM=L7 |
| SSD_PERST#3_R | OTHERS | BUS | 2 | 5 | 5 | 10 | 5 | 14 | 6 | 10 | 12 | 12 | 12 | 12 |  | 50 Ohms | TOP=L2:L3=L2/L4:L6=L5/L7:BOTTOM=L7 |
| SSD_PERST#3_R | OTHERS | BUS | 3 | 5 | 5 | 10 | 5 | 14 | 6 | 10 | 12 | 12 | 12 | 12 |  | 50 Ohms | TOP=L2:L3=L2/L4:L6=L5/L7:BOTTOM=L7 |
| SSD_PERST#3_R | OTHERS | BUS | 4 | 5 | 5 | 10 | 5 | 14 | 6 | 10 | 12 | 12 | 12 | 12 |  | 50 Ohms | TOP=L2:L3=L2/L4:L6=L5/L7:BOTTOM=L7 |
| SSD_PERST#3_R | OTHERS | BUS | 5 | 5 | 5 | 10 | 5 | 14 | 6 | 10 | 12 | 12 | 12 | 12 |  | 50 Ohms | TOP=L2:L3=L2/L4:L6=L5/L7:BOTTOM=L7 |
| SSD_PERST#3_R | OTHERS | BUS | 6 | 5 | 5 | 10 | 5 | 14 | 6 | 10 | 12 | 12 | 12 | 12 |  | 50 Ohms | TOP=L2:L3=L2/L4:L6=L5/L7:BOTTOM=L7 |
| SSD_PERST#3_R | OTHERS | BUS | 7 | 5 | 5 | 10 | 5 | 14 | 6 | 10 | 12 | 12 | 12 | 12 |  | 50 Ohms | TOP=L2:L3=L2/L4:L6=L5/L7:BOTTOM=L7 |
| SSD_PERST#3_R | OTHERS | BUS | 8 | 4.75 | 5 | 10 | 5 | 14 | 6 | 9.5 | 12 | 12 | 12 | 12 |  | 50 Ohms | TOP=L2:L3=L2/L4:L6=L5/L7:BOTTOM=L7 |
| SSD_PERST#4 | OTHERS | BUS | 1 | 4.75 | 5 | 10 | 5 | 14 | 6 | 9.5 | 12 | 12 | 12 | 12 |  | 50 Ohms | TOP=L2:L3=L2/L4:L6=L5/L7:BOTTOM=L7 |
| SSD_PERST#4 | OTHERS | BUS | 2 | 5 | 5 | 10 | 5 | 14 | 6 | 10 | 12 | 12 | 12 | 12 |  | 50 Ohms | TOP=L2:L3=L2/L4:L6=L5/L7:BOTTOM=L7 |
| SSD_PERST#4 | OTHERS | BUS | 3 | 5 | 5 | 10 | 5 | 14 | 6 | 10 | 12 | 12 | 12 | 12 |  | 50 Ohms | TOP=L2:L3=L2/L4:L6=L5/L7:BOTTOM=L7 |
| SSD_PERST#4 | OTHERS | BUS | 4 | 5 | 5 | 10 | 5 | 14 | 6 | 10 | 12 | 12 | 12 | 12 |  | 50 Ohms | TOP=L2:L3=L2/L4:L6=L5/L7:BOTTOM=L7 |
| SSD_PERST#4 | OTHERS | BUS | 5 | 5 | 5 | 10 | 5 | 14 | 6 | 10 | 12 | 12 | 12 | 12 |  | 50 Ohms | TOP=L2:L3=L2/L4:L6=L5/L7:BOTTOM=L7 |
| SSD_PERST#4 | OTHERS | BUS | 6 | 5 | 5 | 10 | 5 | 14 | 6 | 10 | 12 | 12 | 12 | 12 |  | 50 Ohms | TOP=L2:L3=L2/L4:L6=L5/L7:BOTTOM=L7 |
| SSD_PERST#4 | OTHERS | BUS | 7 | 5 | 5 | 10 | 5 | 14 | 6 | 10 | 12 | 12 | 12 | 12 |  | 50 Ohms | TOP=L2:L3=L2/L4:L6=L5/L7:BOTTOM=L7 |
| SSD_PERST#4 | OTHERS | BUS | 8 | 4.75 | 5 | 10 | 5 | 14 | 6 | 9.5 | 12 | 12 | 12 | 12 |  | 50 Ohms | TOP=L2:L3=L2/L4:L6=L5/L7:BOTTOM=L7 |
| SSD_PERST#4_R | OTHERS | BUS | 1 | 4.75 | 5 | 10 | 5 | 14 | 6 | 9.5 | 12 | 12 | 12 | 12 |  | 50 Ohms | TOP=L2:L3=L2/L4:L6=L5/L7:BOTTOM=L7 |
| SSD_PERST#4_R | OTHERS | BUS | 2 | 5 | 5 | 10 | 5 | 14 | 6 | 10 | 12 | 12 | 12 | 12 |  | 50 Ohms | TOP=L2:L3=L2/L4:L6=L5/L7:BOTTOM=L7 |
| SSD_PERST#4_R | OTHERS | BUS | 3 | 5 | 5 | 10 | 5 | 14 | 6 | 10 | 12 | 12 | 12 | 12 |  | 50 Ohms | TOP=L2:L3=L2/L4:L6=L5/L7:BOTTOM=L7 |
| SSD_PERST#4_R | OTHERS | BUS | 4 | 5 | 5 | 10 | 5 | 14 | 6 | 10 | 12 | 12 | 12 | 12 |  | 50 Ohms | TOP=L2:L3=L2/L4:L6=L5/L7:BOTTOM=L7 |
| SSD_PERST#4_R | OTHERS | BUS | 5 | 5 | 5 | 10 | 5 | 14 | 6 | 10 | 12 | 12 | 12 | 12 |  | 50 Ohms | TOP=L2:L3=L2/L4:L6=L5/L7:BOTTOM=L7 |
| SSD_PERST#4_R | OTHERS | BUS | 6 | 5 | 5 | 10 | 5 | 14 | 6 | 10 | 12 | 12 | 12 | 12 |  | 50 Ohms | TOP=L2:L3=L2/L4:L6=L5/L7:BOTTOM=L7 |
| SSD_PERST#4_R | OTHERS | BUS | 7 | 5 | 5 | 10 | 5 | 14 | 6 | 10 | 12 | 12 | 12 | 12 |  | 50 Ohms | TOP=L2:L3=L2/L4:L6=L5/L7:BOTTOM=L7 |
| SSD_PERST#4_R | OTHERS | BUS | 8 | 4.75 | 5 | 10 | 5 | 14 | 6 | 9.5 | 12 | 12 | 12 | 12 |  | 50 Ohms | TOP=L2:L3=L2/L4:L6=L5/L7:BOTTOM=L7 |
| SSD_PERST#5 | OTHERS | BUS | 1 | 4.75 | 5 | 10 | 5 | 14 | 6 | 9.5 | 12 | 12 | 12 | 12 |  | 50 Ohms | TOP=L2:L3=L2/L4:L6=L5/L7:BOTTOM=L7 |
| SSD_PERST#5 | OTHERS | BUS | 2 | 5 | 5 | 10 | 5 | 14 | 6 | 10 | 12 | 12 | 12 | 12 |  | 50 Ohms | TOP=L2:L3=L2/L4:L6=L5/L7:BOTTOM=L7 |
| SSD_PERST#5 | OTHERS | BUS | 3 | 5 | 5 | 10 | 5 | 14 | 6 | 10 | 12 | 12 | 12 | 12 |  | 50 Ohms | TOP=L2:L3=L2/L4:L6=L5/L7:BOTTOM=L7 |
| SSD_PERST#5 | OTHERS | BUS | 4 | 5 | 5 | 10 | 5 | 14 | 6 | 10 | 12 | 12 | 12 | 12 |  | 50 Ohms | TOP=L2:L3=L2/L4:L6=L5/L7:BOTTOM=L7 |
| SSD_PERST#5 | OTHERS | BUS | 5 | 5 | 5 | 10 | 5 | 14 | 6 | 10 | 12 | 12 | 12 | 12 |  | 50 Ohms | TOP=L2:L3=L2/L4:L6=L5/L7:BOTTOM=L7 |
| SSD_PERST#5 | OTHERS | BUS | 6 | 5 | 5 | 10 | 5 | 14 | 6 | 10 | 12 | 12 | 12 | 12 |  | 50 Ohms | TOP=L2:L3=L2/L4:L6=L5/L7:BOTTOM=L7 |
| SSD_PERST#5 | OTHERS | BUS | 7 | 5 | 5 | 10 | 5 | 14 | 6 | 10 | 12 | 12 | 12 | 12 |  | 50 Ohms | TOP=L2:L3=L2/L4:L6=L5/L7:BOTTOM=L7 |
| SSD_PERST#5 | OTHERS | BUS | 8 | 4.75 | 5 | 10 | 5 | 14 | 6 | 9.5 | 12 | 12 | 12 | 12 |  | 50 Ohms | TOP=L2:L3=L2/L4:L6=L5/L7:BOTTOM=L7 |
| SSD_PERST#5_R | OTHERS | BUS | 1 | 4.75 | 5 | 10 | 5 | 14 | 6 | 9.5 | 12 | 12 | 12 | 12 |  | 50 Ohms | TOP=L2:L3=L2/L4:L6=L5/L7:BOTTOM=L7 |
| SSD_PERST#5_R | OTHERS | BUS | 2 | 5 | 5 | 10 | 5 | 14 | 6 | 10 | 12 | 12 | 12 | 12 |  | 50 Ohms | TOP=L2:L3=L2/L4:L6=L5/L7:BOTTOM=L7 |
| SSD_PERST#5_R | OTHERS | BUS | 3 | 5 | 5 | 10 | 5 | 14 | 6 | 10 | 12 | 12 | 12 | 12 |  | 50 Ohms | TOP=L2:L3=L2/L4:L6=L5/L7:BOTTOM=L7 |
| SSD_PERST#5_R | OTHERS | BUS | 4 | 5 | 5 | 10 | 5 | 14 | 6 | 10 | 12 | 12 | 12 | 12 |  | 50 Ohms | TOP=L2:L3=L2/L4:L6=L5/L7:BOTTOM=L7 |
| SSD_PERST#5_R | OTHERS | BUS | 5 | 5 | 5 | 10 | 5 | 14 | 6 | 10 | 12 | 12 | 12 | 12 |  | 50 Ohms | TOP=L2:L3=L2/L4:L6=L5/L7:BOTTOM=L7 |
| SSD_PERST#5_R | OTHERS | BUS | 6 | 5 | 5 | 10 | 5 | 14 | 6 | 10 | 12 | 12 | 12 | 12 |  | 50 Ohms | TOP=L2:L3=L2/L4:L6=L5/L7:BOTTOM=L7 |
| SSD_PERST#5_R | OTHERS | BUS | 7 | 5 | 5 | 10 | 5 | 14 | 6 | 10 | 12 | 12 | 12 | 12 |  | 50 Ohms | TOP=L2:L3=L2/L4:L6=L5/L7:BOTTOM=L7 |
| SSD_PERST#5_R | OTHERS | BUS | 8 | 4.75 | 5 | 10 | 5 | 14 | 6 | 9.5 | 12 | 12 | 12 | 12 |  | 50 Ohms | TOP=L2:L3=L2/L4:L6=L5/L7:BOTTOM=L7 |
| SSD_PERST#6 | OTHERS | BUS | 1 | 4.75 | 5 | 10 | 5 | 14 | 6 | 9.5 | 12 | 12 | 12 | 12 |  | 50 Ohms | TOP=L2:L3=L2/L4:L6=L5/L7:BOTTOM=L7 |
| SSD_PERST#6 | OTHERS | BUS | 2 | 5 | 5 | 10 | 5 | 14 | 6 | 10 | 12 | 12 | 12 | 12 |  | 50 Ohms | TOP=L2:L3=L2/L4:L6=L5/L7:BOTTOM=L7 |
| SSD_PERST#6 | OTHERS | BUS | 3 | 5 | 5 | 10 | 5 | 14 | 6 | 10 | 12 | 12 | 12 | 12 |  | 50 Ohms | TOP=L2:L3=L2/L4:L6=L5/L7:BOTTOM=L7 |
| SSD_PERST#6 | OTHERS | BUS | 4 | 5 | 5 | 10 | 5 | 14 | 6 | 10 | 12 | 12 | 12 | 12 |  | 50 Ohms | TOP=L2:L3=L2/L4:L6=L5/L7:BOTTOM=L7 |
| SSD_PERST#6 | OTHERS | BUS | 5 | 5 | 5 | 10 | 5 | 14 | 6 | 10 | 12 | 12 | 12 | 12 |  | 50 Ohms | TOP=L2:L3=L2/L4:L6=L5/L7:BOTTOM=L7 |
| SSD_PERST#6 | OTHERS | BUS | 6 | 5 | 5 | 10 | 5 | 14 | 6 | 10 | 12 | 12 | 12 | 12 |  | 50 Ohms | TOP=L2:L3=L2/L4:L6=L5/L7:BOTTOM=L7 |
| SSD_PERST#6 | OTHERS | BUS | 7 | 5 | 5 | 10 | 5 | 14 | 6 | 10 | 12 | 12 | 12 | 12 |  | 50 Ohms | TOP=L2:L3=L2/L4:L6=L5/L7:BOTTOM=L7 |
| SSD_PERST#6 | OTHERS | BUS | 8 | 4.75 | 5 | 10 | 5 | 14 | 6 | 9.5 | 12 | 12 | 12 | 12 |  | 50 Ohms | TOP=L2:L3=L2/L4:L6=L5/L7:BOTTOM=L7 |
| SSD_PERST#6_R | OTHERS | BUS | 1 | 4.75 | 5 | 10 | 5 | 14 | 6 | 9.5 | 12 | 12 | 12 | 12 |  | 50 Ohms | TOP=L2:L3=L2/L4:L6=L5/L7:BOTTOM=L7 |
| SSD_PERST#6_R | OTHERS | BUS | 2 | 5 | 5 | 10 | 5 | 14 | 6 | 10 | 12 | 12 | 12 | 12 |  | 50 Ohms | TOP=L2:L3=L2/L4:L6=L5/L7:BOTTOM=L7 |
| SSD_PERST#6_R | OTHERS | BUS | 3 | 5 | 5 | 10 | 5 | 14 | 6 | 10 | 12 | 12 | 12 | 12 |  | 50 Ohms | TOP=L2:L3=L2/L4:L6=L5/L7:BOTTOM=L7 |
| SSD_PERST#6_R | OTHERS | BUS | 4 | 5 | 5 | 10 | 5 | 14 | 6 | 10 | 12 | 12 | 12 | 12 |  | 50 Ohms | TOP=L2:L3=L2/L4:L6=L5/L7:BOTTOM=L7 |
| SSD_PERST#6_R | OTHERS | BUS | 5 | 5 | 5 | 10 | 5 | 14 | 6 | 10 | 12 | 12 | 12 | 12 |  | 50 Ohms | TOP=L2:L3=L2/L4:L6=L5/L7:BOTTOM=L7 |
| SSD_PERST#6_R | OTHERS | BUS | 6 | 5 | 5 | 10 | 5 | 14 | 6 | 10 | 12 | 12 | 12 | 12 |  | 50 Ohms | TOP=L2:L3=L2/L4:L6=L5/L7:BOTTOM=L7 |
| SSD_PERST#6_R | OTHERS | BUS | 7 | 5 | 5 | 10 | 5 | 14 | 6 | 10 | 12 | 12 | 12 | 12 |  | 50 Ohms | TOP=L2:L3=L2/L4:L6=L5/L7:BOTTOM=L7 |
| SSD_PERST#6_R | OTHERS | BUS | 8 | 4.75 | 5 | 10 | 5 | 14 | 6 | 9.5 | 12 | 12 | 12 | 12 |  | 50 Ohms | TOP=L2:L3=L2/L4:L6=L5/L7:BOTTOM=L7 |
| SSD_PERST#7 | OTHERS | BUS | 1 | 4.75 | 5 | 10 | 5 | 14 | 6 | 9.5 | 12 | 12 | 12 | 12 |  | 50 Ohms | TOP=L2:L3=L2/L4:L6=L5/L7:BOTTOM=L7 |
| SSD_PERST#7 | OTHERS | BUS | 2 | 5 | 5 | 10 | 5 | 14 | 6 | 10 | 12 | 12 | 12 | 12 |  | 50 Ohms | TOP=L2:L3=L2/L4:L6=L5/L7:BOTTOM=L7 |
| SSD_PERST#7 | OTHERS | BUS | 3 | 5 | 5 | 10 | 5 | 14 | 6 | 10 | 12 | 12 | 12 | 12 |  | 50 Ohms | TOP=L2:L3=L2/L4:L6=L5/L7:BOTTOM=L7 |
| SSD_PERST#7 | OTHERS | BUS | 4 | 5 | 5 | 10 | 5 | 14 | 6 | 10 | 12 | 12 | 12 | 12 |  | 50 Ohms | TOP=L2:L3=L2/L4:L6=L5/L7:BOTTOM=L7 |
| SSD_PERST#7 | OTHERS | BUS | 5 | 5 | 5 | 10 | 5 | 14 | 6 | 10 | 12 | 12 | 12 | 12 |  | 50 Ohms | TOP=L2:L3=L2/L4:L6=L5/L7:BOTTOM=L7 |
| SSD_PERST#7 | OTHERS | BUS | 6 | 5 | 5 | 10 | 5 | 14 | 6 | 10 | 12 | 12 | 12 | 12 |  | 50 Ohms | TOP=L2:L3=L2/L4:L6=L5/L7:BOTTOM=L7 |
| SSD_PERST#7 | OTHERS | BUS | 7 | 5 | 5 | 10 | 5 | 14 | 6 | 10 | 12 | 12 | 12 | 12 |  | 50 Ohms | TOP=L2:L3=L2/L4:L6=L5/L7:BOTTOM=L7 |
| SSD_PERST#7 | OTHERS | BUS | 8 | 4.75 | 5 | 10 | 5 | 14 | 6 | 9.5 | 12 | 12 | 12 | 12 |  | 50 Ohms | TOP=L2:L3=L2/L4:L6=L5/L7:BOTTOM=L7 |
| SSD_PERST#7_R | OTHERS | BUS | 1 | 4.75 | 5 | 10 | 5 | 14 | 6 | 9.5 | 12 | 12 | 12 | 12 |  | 50 Ohms | TOP=L2:L3=L2/L4:L6=L5/L7:BOTTOM=L7 |
| SSD_PERST#7_R | OTHERS | BUS | 2 | 5 | 5 | 10 | 5 | 14 | 6 | 10 | 12 | 12 | 12 | 12 |  | 50 Ohms | TOP=L2:L3=L2/L4:L6=L5/L7:BOTTOM=L7 |
| SSD_PERST#7_R | OTHERS | BUS | 3 | 5 | 5 | 10 | 5 | 14 | 6 | 10 | 12 | 12 | 12 | 12 |  | 50 Ohms | TOP=L2:L3=L2/L4:L6=L5/L7:BOTTOM=L7 |
| SSD_PERST#7_R | OTHERS | BUS | 4 | 5 | 5 | 10 | 5 | 14 | 6 | 10 | 12 | 12 | 12 | 12 |  | 50 Ohms | TOP=L2:L3=L2/L4:L6=L5/L7:BOTTOM=L7 |
| SSD_PERST#7_R | OTHERS | BUS | 5 | 5 | 5 | 10 | 5 | 14 | 6 | 10 | 12 | 12 | 12 | 12 |  | 50 Ohms | TOP=L2:L3=L2/L4:L6=L5/L7:BOTTOM=L7 |
| SSD_PERST#7_R | OTHERS | BUS | 6 | 5 | 5 | 10 | 5 | 14 | 6 | 10 | 12 | 12 | 12 | 12 |  | 50 Ohms | TOP=L2:L3=L2/L4:L6=L5/L7:BOTTOM=L7 |
| SSD_PERST#7_R | OTHERS | BUS | 7 | 5 | 5 | 10 | 5 | 14 | 6 | 10 | 12 | 12 | 12 | 12 |  | 50 Ohms | TOP=L2:L3=L2/L4:L6=L5/L7:BOTTOM=L7 |
| SSD_PERST#7_R | OTHERS | BUS | 8 | 4.75 | 5 | 10 | 5 | 14 | 6 | 9.5 | 12 | 12 | 12 | 12 |  | 50 Ohms | TOP=L2:L3=L2/L4:L6=L5/L7:BOTTOM=L7 |
| SSD_PERST#8 | OTHERS | BUS | 1 | 4.75 | 5 | 10 | 5 | 14 | 6 | 9.5 | 12 | 12 | 12 | 12 |  | 50 Ohms | TOP=L2:L3=L2/L4:L6=L5/L7:BOTTOM=L7 |
| SSD_PERST#8 | OTHERS | BUS | 2 | 5 | 5 | 10 | 5 | 14 | 6 | 10 | 12 | 12 | 12 | 12 |  | 50 Ohms | TOP=L2:L3=L2/L4:L6=L5/L7:BOTTOM=L7 |
| SSD_PERST#8 | OTHERS | BUS | 3 | 5 | 5 | 10 | 5 | 14 | 6 | 10 | 12 | 12 | 12 | 12 |  | 50 Ohms | TOP=L2:L3=L2/L4:L6=L5/L7:BOTTOM=L7 |
| SSD_PERST#8 | OTHERS | BUS | 4 | 5 | 5 | 10 | 5 | 14 | 6 | 10 | 12 | 12 | 12 | 12 |  | 50 Ohms | TOP=L2:L3=L2/L4:L6=L5/L7:BOTTOM=L7 |
| SSD_PERST#8 | OTHERS | BUS | 5 | 5 | 5 | 10 | 5 | 14 | 6 | 10 | 12 | 12 | 12 | 12 |  | 50 Ohms | TOP=L2:L3=L2/L4:L6=L5/L7:BOTTOM=L7 |
| SSD_PERST#8 | OTHERS | BUS | 6 | 5 | 5 | 10 | 5 | 14 | 6 | 10 | 12 | 12 | 12 | 12 |  | 50 Ohms | TOP=L2:L3=L2/L4:L6=L5/L7:BOTTOM=L7 |
| SSD_PERST#8 | OTHERS | BUS | 7 | 5 | 5 | 10 | 5 | 14 | 6 | 10 | 12 | 12 | 12 | 12 |  | 50 Ohms | TOP=L2:L3=L2/L4:L6=L5/L7:BOTTOM=L7 |
| SSD_PERST#8 | OTHERS | BUS | 8 | 4.75 | 5 | 10 | 5 | 14 | 6 | 9.5 | 12 | 12 | 12 | 12 |  | 50 Ohms | TOP=L2:L3=L2/L4:L6=L5/L7:BOTTOM=L7 |
| SSD_PERST#8_R | OTHERS | BUS | 1 | 4.75 | 5 | 10 | 5 | 14 | 6 | 9.5 | 12 | 12 | 12 | 12 |  | 50 Ohms | TOP=L2:L3=L2/L4:L6=L5/L7:BOTTOM=L7 |
| SSD_PERST#8_R | OTHERS | BUS | 2 | 5 | 5 | 10 | 5 | 14 | 6 | 10 | 12 | 12 | 12 | 12 |  | 50 Ohms | TOP=L2:L3=L2/L4:L6=L5/L7:BOTTOM=L7 |
| SSD_PERST#8_R | OTHERS | BUS | 3 | 5 | 5 | 10 | 5 | 14 | 6 | 10 | 12 | 12 | 12 | 12 |  | 50 Ohms | TOP=L2:L3=L2/L4:L6=L5/L7:BOTTOM=L7 |
| SSD_PERST#8_R | OTHERS | BUS | 4 | 5 | 5 | 10 | 5 | 14 | 6 | 10 | 12 | 12 | 12 | 12 |  | 50 Ohms | TOP=L2:L3=L2/L4:L6=L5/L7:BOTTOM=L7 |
| SSD_PERST#8_R | OTHERS | BUS | 5 | 5 | 5 | 10 | 5 | 14 | 6 | 10 | 12 | 12 | 12 | 12 |  | 50 Ohms | TOP=L2:L3=L2/L4:L6=L5/L7:BOTTOM=L7 |
| SSD_PERST#8_R | OTHERS | BUS | 6 | 5 | 5 | 10 | 5 | 14 | 6 | 10 | 12 | 12 | 12 | 12 |  | 50 Ohms | TOP=L2:L3=L2/L4:L6=L5/L7:BOTTOM=L7 |
| SSD_PERST#8_R | OTHERS | BUS | 7 | 5 | 5 | 10 | 5 | 14 | 6 | 10 | 12 | 12 | 12 | 12 |  | 50 Ohms | TOP=L2:L3=L2/L4:L6=L5/L7:BOTTOM=L7 |
| SSD_PERST#8_R | OTHERS | BUS | 8 | 4.75 | 5 | 10 | 5 | 14 | 6 | 9.5 | 12 | 12 | 12 | 12 |  | 50 Ohms | TOP=L2:L3=L2/L4:L6=L5/L7:BOTTOM=L7 |
| SSD_PERST#9 | OTHERS | BUS | 1 | 4.75 | 5 | 10 | 5 | 14 | 6 | 9.5 | 12 | 12 | 12 | 12 |  | 50 Ohms | TOP=L2:L3=L2/L4:L6=L5/L7:BOTTOM=L7 |
| SSD_PERST#9 | OTHERS | BUS | 2 | 5 | 5 | 10 | 5 | 14 | 6 | 10 | 12 | 12 | 12 | 12 |  | 50 Ohms | TOP=L2:L3=L2/L4:L6=L5/L7:BOTTOM=L7 |
| SSD_PERST#9 | OTHERS | BUS | 3 | 5 | 5 | 10 | 5 | 14 | 6 | 10 | 12 | 12 | 12 | 12 |  | 50 Ohms | TOP=L2:L3=L2/L4:L6=L5/L7:BOTTOM=L7 |
| SSD_PERST#9 | OTHERS | BUS | 4 | 5 | 5 | 10 | 5 | 14 | 6 | 10 | 12 | 12 | 12 | 12 |  | 50 Ohms | TOP=L2:L3=L2/L4:L6=L5/L7:BOTTOM=L7 |
| SSD_PERST#9 | OTHERS | BUS | 5 | 5 | 5 | 10 | 5 | 14 | 6 | 10 | 12 | 12 | 12 | 12 |  | 50 Ohms | TOP=L2:L3=L2/L4:L6=L5/L7:BOTTOM=L7 |
| SSD_PERST#9 | OTHERS | BUS | 6 | 5 | 5 | 10 | 5 | 14 | 6 | 10 | 12 | 12 | 12 | 12 |  | 50 Ohms | TOP=L2:L3=L2/L4:L6=L5/L7:BOTTOM=L7 |
| SSD_PERST#9 | OTHERS | BUS | 7 | 5 | 5 | 10 | 5 | 14 | 6 | 10 | 12 | 12 | 12 | 12 |  | 50 Ohms | TOP=L2:L3=L2/L4:L6=L5/L7:BOTTOM=L7 |
| SSD_PERST#9 | OTHERS | BUS | 8 | 4.75 | 5 | 10 | 5 | 14 | 6 | 9.5 | 12 | 12 | 12 | 12 |  | 50 Ohms | TOP=L2:L3=L2/L4:L6=L5/L7:BOTTOM=L7 |
| SSD_PERST#9_R | OTHERS | BUS | 1 | 4.75 | 5 | 10 | 5 | 14 | 6 | 9.5 | 12 | 12 | 12 | 12 |  | 50 Ohms | TOP=L2:L3=L2/L4:L6=L5/L7:BOTTOM=L7 |
| SSD_PERST#9_R | OTHERS | BUS | 2 | 5 | 5 | 10 | 5 | 14 | 6 | 10 | 12 | 12 | 12 | 12 |  | 50 Ohms | TOP=L2:L3=L2/L4:L6=L5/L7:BOTTOM=L7 |
| SSD_PERST#9_R | OTHERS | BUS | 3 | 5 | 5 | 10 | 5 | 14 | 6 | 10 | 12 | 12 | 12 | 12 |  | 50 Ohms | TOP=L2:L3=L2/L4:L6=L5/L7:BOTTOM=L7 |
| SSD_PERST#9_R | OTHERS | BUS | 4 | 5 | 5 | 10 | 5 | 14 | 6 | 10 | 12 | 12 | 12 | 12 |  | 50 Ohms | TOP=L2:L3=L2/L4:L6=L5/L7:BOTTOM=L7 |
| SSD_PERST#9_R | OTHERS | BUS | 5 | 5 | 5 | 10 | 5 | 14 | 6 | 10 | 12 | 12 | 12 | 12 |  | 50 Ohms | TOP=L2:L3=L2/L4:L6=L5/L7:BOTTOM=L7 |
| SSD_PERST#9_R | OTHERS | BUS | 6 | 5 | 5 | 10 | 5 | 14 | 6 | 10 | 12 | 12 | 12 | 12 |  | 50 Ohms | TOP=L2:L3=L2/L4:L6=L5/L7:BOTTOM=L7 |
| SSD_PERST#9_R | OTHERS | BUS | 7 | 5 | 5 | 10 | 5 | 14 | 6 | 10 | 12 | 12 | 12 | 12 |  | 50 Ohms | TOP=L2:L3=L2/L4:L6=L5/L7:BOTTOM=L7 |
| SSD_PERST#9_R | OTHERS | BUS | 8 | 4.75 | 5 | 10 | 5 | 14 | 6 | 9.5 | 12 | 12 | 12 | 12 |  | 50 Ohms | TOP=L2:L3=L2/L4:L6=L5/L7:BOTTOM=L7 |
| SSD_PERST_Y0 | OTHERS | BUS | 1 | 4.75 | 5 | 10 | 5 | 14 | 6 | 9.5 | 12 | 12 | 12 | 12 |  | 50 Ohms | TOP=L2:L3=L2/L4:L6=L5/L7:BOTTOM=L7 |
| SSD_PERST_Y0 | OTHERS | BUS | 2 | 5 | 5 | 10 | 5 | 14 | 6 | 10 | 12 | 12 | 12 | 12 |  | 50 Ohms | TOP=L2:L3=L2/L4:L6=L5/L7:BOTTOM=L7 |
| SSD_PERST_Y0 | OTHERS | BUS | 3 | 5 | 5 | 10 | 5 | 14 | 6 | 10 | 12 | 12 | 12 | 12 |  | 50 Ohms | TOP=L2:L3=L2/L4:L6=L5/L7:BOTTOM=L7 |
| SSD_PERST_Y0 | OTHERS | BUS | 4 | 5 | 5 | 10 | 5 | 14 | 6 | 10 | 12 | 12 | 12 | 12 |  | 50 Ohms | TOP=L2:L3=L2/L4:L6=L5/L7:BOTTOM=L7 |
| SSD_PERST_Y0 | OTHERS | BUS | 5 | 5 | 5 | 10 | 5 | 14 | 6 | 10 | 12 | 12 | 12 | 12 |  | 50 Ohms | TOP=L2:L3=L2/L4:L6=L5/L7:BOTTOM=L7 |
| SSD_PERST_Y0 | OTHERS | BUS | 6 | 5 | 5 | 10 | 5 | 14 | 6 | 10 | 12 | 12 | 12 | 12 |  | 50 Ohms | TOP=L2:L3=L2/L4:L6=L5/L7:BOTTOM=L7 |
| SSD_PERST_Y0 | OTHERS | BUS | 7 | 5 | 5 | 10 | 5 | 14 | 6 | 10 | 12 | 12 | 12 | 12 |  | 50 Ohms | TOP=L2:L3=L2/L4:L6=L5/L7:BOTTOM=L7 |
| SSD_PERST_Y0 | OTHERS | BUS | 8 | 4.75 | 5 | 10 | 5 | 14 | 6 | 9.5 | 12 | 12 | 12 | 12 |  | 50 Ohms | TOP=L2:L3=L2/L4:L6=L5/L7:BOTTOM=L7 |
| SSD_PERST_Y1 | OTHERS | BUS | 1 | 4.75 | 5 | 10 | 5 | 14 | 6 | 9.5 | 12 | 12 | 12 | 12 |  | 50 Ohms | TOP=L2:L3=L2/L4:L6=L5/L7:BOTTOM=L7 |
| SSD_PERST_Y1 | OTHERS | BUS | 2 | 5 | 5 | 10 | 5 | 14 | 6 | 10 | 12 | 12 | 12 | 12 |  | 50 Ohms | TOP=L2:L3=L2/L4:L6=L5/L7:BOTTOM=L7 |
| SSD_PERST_Y1 | OTHERS | BUS | 3 | 5 | 5 | 10 | 5 | 14 | 6 | 10 | 12 | 12 | 12 | 12 |  | 50 Ohms | TOP=L2:L3=L2/L4:L6=L5/L7:BOTTOM=L7 |
| SSD_PERST_Y1 | OTHERS | BUS | 4 | 5 | 5 | 10 | 5 | 14 | 6 | 10 | 12 | 12 | 12 | 12 |  | 50 Ohms | TOP=L2:L3=L2/L4:L6=L5/L7:BOTTOM=L7 |
| SSD_PERST_Y1 | OTHERS | BUS | 5 | 5 | 5 | 10 | 5 | 14 | 6 | 10 | 12 | 12 | 12 | 12 |  | 50 Ohms | TOP=L2:L3=L2/L4:L6=L5/L7:BOTTOM=L7 |
| SSD_PERST_Y1 | OTHERS | BUS | 6 | 5 | 5 | 10 | 5 | 14 | 6 | 10 | 12 | 12 | 12 | 12 |  | 50 Ohms | TOP=L2:L3=L2/L4:L6=L5/L7:BOTTOM=L7 |
| SSD_PERST_Y1 | OTHERS | BUS | 7 | 5 | 5 | 10 | 5 | 14 | 6 | 10 | 12 | 12 | 12 | 12 |  | 50 Ohms | TOP=L2:L3=L2/L4:L6=L5/L7:BOTTOM=L7 |
| SSD_PERST_Y1 | OTHERS | BUS | 8 | 4.75 | 5 | 10 | 5 | 14 | 6 | 9.5 | 12 | 12 | 12 | 12 |  | 50 Ohms | TOP=L2:L3=L2/L4:L6=L5/L7:BOTTOM=L7 |
| SSD_PERST_Y10 | OTHERS | BUS | 1 | 4.75 | 5 | 10 | 5 | 14 | 6 | 9.5 | 12 | 12 | 12 | 12 |  | 50 Ohms | TOP=L2:L3=L2/L4:L6=L5/L7:BOTTOM=L7 |
| SSD_PERST_Y10 | OTHERS | BUS | 2 | 5 | 5 | 10 | 5 | 14 | 6 | 10 | 12 | 12 | 12 | 12 |  | 50 Ohms | TOP=L2:L3=L2/L4:L6=L5/L7:BOTTOM=L7 |
| SSD_PERST_Y10 | OTHERS | BUS | 3 | 5 | 5 | 10 | 5 | 14 | 6 | 10 | 12 | 12 | 12 | 12 |  | 50 Ohms | TOP=L2:L3=L2/L4:L6=L5/L7:BOTTOM=L7 |
| SSD_PERST_Y10 | OTHERS | BUS | 4 | 5 | 5 | 10 | 5 | 14 | 6 | 10 | 12 | 12 | 12 | 12 |  | 50 Ohms | TOP=L2:L3=L2/L4:L6=L5/L7:BOTTOM=L7 |
| SSD_PERST_Y10 | OTHERS | BUS | 5 | 5 | 5 | 10 | 5 | 14 | 6 | 10 | 12 | 12 | 12 | 12 |  | 50 Ohms | TOP=L2:L3=L2/L4:L6=L5/L7:BOTTOM=L7 |
| SSD_PERST_Y10 | OTHERS | BUS | 6 | 5 | 5 | 10 | 5 | 14 | 6 | 10 | 12 | 12 | 12 | 12 |  | 50 Ohms | TOP=L2:L3=L2/L4:L6=L5/L7:BOTTOM=L7 |
| SSD_PERST_Y10 | OTHERS | BUS | 7 | 5 | 5 | 10 | 5 | 14 | 6 | 10 | 12 | 12 | 12 | 12 |  | 50 Ohms | TOP=L2:L3=L2/L4:L6=L5/L7:BOTTOM=L7 |
| SSD_PERST_Y10 | OTHERS | BUS | 8 | 4.75 | 5 | 10 | 5 | 14 | 6 | 9.5 | 12 | 12 | 12 | 12 |  | 50 Ohms | TOP=L2:L3=L2/L4:L6=L5/L7:BOTTOM=L7 |
| SSD_PERST_Y11 | OTHERS | BUS | 1 | 4.75 | 5 | 10 | 5 | 14 | 6 | 9.5 | 12 | 12 | 12 | 12 |  | 50 Ohms | TOP=L2:L3=L2/L4:L6=L5/L7:BOTTOM=L7 |
| SSD_PERST_Y11 | OTHERS | BUS | 2 | 5 | 5 | 10 | 5 | 14 | 6 | 10 | 12 | 12 | 12 | 12 |  | 50 Ohms | TOP=L2:L3=L2/L4:L6=L5/L7:BOTTOM=L7 |
| SSD_PERST_Y11 | OTHERS | BUS | 3 | 5 | 5 | 10 | 5 | 14 | 6 | 10 | 12 | 12 | 12 | 12 |  | 50 Ohms | TOP=L2:L3=L2/L4:L6=L5/L7:BOTTOM=L7 |
| SSD_PERST_Y11 | OTHERS | BUS | 4 | 5 | 5 | 10 | 5 | 14 | 6 | 10 | 12 | 12 | 12 | 12 |  | 50 Ohms | TOP=L2:L3=L2/L4:L6=L5/L7:BOTTOM=L7 |
| SSD_PERST_Y11 | OTHERS | BUS | 5 | 5 | 5 | 10 | 5 | 14 | 6 | 10 | 12 | 12 | 12 | 12 |  | 50 Ohms | TOP=L2:L3=L2/L4:L6=L5/L7:BOTTOM=L7 |
| SSD_PERST_Y11 | OTHERS | BUS | 6 | 5 | 5 | 10 | 5 | 14 | 6 | 10 | 12 | 12 | 12 | 12 |  | 50 Ohms | TOP=L2:L3=L2/L4:L6=L5/L7:BOTTOM=L7 |
| SSD_PERST_Y11 | OTHERS | BUS | 7 | 5 | 5 | 10 | 5 | 14 | 6 | 10 | 12 | 12 | 12 | 12 |  | 50 Ohms | TOP=L2:L3=L2/L4:L6=L5/L7:BOTTOM=L7 |
| SSD_PERST_Y11 | OTHERS | BUS | 8 | 4.75 | 5 | 10 | 5 | 14 | 6 | 9.5 | 12 | 12 | 12 | 12 |  | 50 Ohms | TOP=L2:L3=L2/L4:L6=L5/L7:BOTTOM=L7 |
| SSD_PERST_Y12 | OTHERS | BUS | 1 | 4.75 | 5 | 10 | 5 | 14 | 6 | 9.5 | 12 | 12 | 12 | 12 |  | 50 Ohms | TOP=L2:L3=L2/L4:L6=L5/L7:BOTTOM=L7 |
| SSD_PERST_Y12 | OTHERS | BUS | 2 | 5 | 5 | 10 | 5 | 14 | 6 | 10 | 12 | 12 | 12 | 12 |  | 50 Ohms | TOP=L2:L3=L2/L4:L6=L5/L7:BOTTOM=L7 |
| SSD_PERST_Y12 | OTHERS | BUS | 3 | 5 | 5 | 10 | 5 | 14 | 6 | 10 | 12 | 12 | 12 | 12 |  | 50 Ohms | TOP=L2:L3=L2/L4:L6=L5/L7:BOTTOM=L7 |
| SSD_PERST_Y12 | OTHERS | BUS | 4 | 5 | 5 | 10 | 5 | 14 | 6 | 10 | 12 | 12 | 12 | 12 |  | 50 Ohms | TOP=L2:L3=L2/L4:L6=L5/L7:BOTTOM=L7 |
| SSD_PERST_Y12 | OTHERS | BUS | 5 | 5 | 5 | 10 | 5 | 14 | 6 | 10 | 12 | 12 | 12 | 12 |  | 50 Ohms | TOP=L2:L3=L2/L4:L6=L5/L7:BOTTOM=L7 |
| SSD_PERST_Y12 | OTHERS | BUS | 6 | 5 | 5 | 10 | 5 | 14 | 6 | 10 | 12 | 12 | 12 | 12 |  | 50 Ohms | TOP=L2:L3=L2/L4:L6=L5/L7:BOTTOM=L7 |
| SSD_PERST_Y12 | OTHERS | BUS | 7 | 5 | 5 | 10 | 5 | 14 | 6 | 10 | 12 | 12 | 12 | 12 |  | 50 Ohms | TOP=L2:L3=L2/L4:L6=L5/L7:BOTTOM=L7 |
| SSD_PERST_Y12 | OTHERS | BUS | 8 | 4.75 | 5 | 10 | 5 | 14 | 6 | 9.5 | 12 | 12 | 12 | 12 |  | 50 Ohms | TOP=L2:L3=L2/L4:L6=L5/L7:BOTTOM=L7 |
| SSD_PERST_Y13 | OTHERS | BUS | 1 | 4.75 | 5 | 10 | 5 | 14 | 6 | 9.5 | 12 | 12 | 12 | 12 |  | 50 Ohms | TOP=L2:L3=L2/L4:L6=L5/L7:BOTTOM=L7 |
| SSD_PERST_Y13 | OTHERS | BUS | 2 | 5 | 5 | 10 | 5 | 14 | 6 | 10 | 12 | 12 | 12 | 12 |  | 50 Ohms | TOP=L2:L3=L2/L4:L6=L5/L7:BOTTOM=L7 |
| SSD_PERST_Y13 | OTHERS | BUS | 3 | 5 | 5 | 10 | 5 | 14 | 6 | 10 | 12 | 12 | 12 | 12 |  | 50 Ohms | TOP=L2:L3=L2/L4:L6=L5/L7:BOTTOM=L7 |
| SSD_PERST_Y13 | OTHERS | BUS | 4 | 5 | 5 | 10 | 5 | 14 | 6 | 10 | 12 | 12 | 12 | 12 |  | 50 Ohms | TOP=L2:L3=L2/L4:L6=L5/L7:BOTTOM=L7 |
| SSD_PERST_Y13 | OTHERS | BUS | 5 | 5 | 5 | 10 | 5 | 14 | 6 | 10 | 12 | 12 | 12 | 12 |  | 50 Ohms | TOP=L2:L3=L2/L4:L6=L5/L7:BOTTOM=L7 |
| SSD_PERST_Y13 | OTHERS | BUS | 6 | 5 | 5 | 10 | 5 | 14 | 6 | 10 | 12 | 12 | 12 | 12 |  | 50 Ohms | TOP=L2:L3=L2/L4:L6=L5/L7:BOTTOM=L7 |
| SSD_PERST_Y13 | OTHERS | BUS | 7 | 5 | 5 | 10 | 5 | 14 | 6 | 10 | 12 | 12 | 12 | 12 |  | 50 Ohms | TOP=L2:L3=L2/L4:L6=L5/L7:BOTTOM=L7 |
| SSD_PERST_Y13 | OTHERS | BUS | 8 | 4.75 | 5 | 10 | 5 | 14 | 6 | 9.5 | 12 | 12 | 12 | 12 |  | 50 Ohms | TOP=L2:L3=L2/L4:L6=L5/L7:BOTTOM=L7 |
| SSD_PERST_Y14 | OTHERS | BUS | 1 | 4.75 | 5 | 10 | 5 | 14 | 6 | 9.5 | 12 | 12 | 12 | 12 |  | 50 Ohms | TOP=L2:L3=L2/L4:L6=L5/L7:BOTTOM=L7 |
| SSD_PERST_Y14 | OTHERS | BUS | 2 | 5 | 5 | 10 | 5 | 14 | 6 | 10 | 12 | 12 | 12 | 12 |  | 50 Ohms | TOP=L2:L3=L2/L4:L6=L5/L7:BOTTOM=L7 |
| SSD_PERST_Y14 | OTHERS | BUS | 3 | 5 | 5 | 10 | 5 | 14 | 6 | 10 | 12 | 12 | 12 | 12 |  | 50 Ohms | TOP=L2:L3=L2/L4:L6=L5/L7:BOTTOM=L7 |
| SSD_PERST_Y14 | OTHERS | BUS | 4 | 5 | 5 | 10 | 5 | 14 | 6 | 10 | 12 | 12 | 12 | 12 |  | 50 Ohms | TOP=L2:L3=L2/L4:L6=L5/L7:BOTTOM=L7 |
| SSD_PERST_Y14 | OTHERS | BUS | 5 | 5 | 5 | 10 | 5 | 14 | 6 | 10 | 12 | 12 | 12 | 12 |  | 50 Ohms | TOP=L2:L3=L2/L4:L6=L5/L7:BOTTOM=L7 |
| SSD_PERST_Y14 | OTHERS | BUS | 6 | 5 | 5 | 10 | 5 | 14 | 6 | 10 | 12 | 12 | 12 | 12 |  | 50 Ohms | TOP=L2:L3=L2/L4:L6=L5/L7:BOTTOM=L7 |
| SSD_PERST_Y14 | OTHERS | BUS | 7 | 5 | 5 | 10 | 5 | 14 | 6 | 10 | 12 | 12 | 12 | 12 |  | 50 Ohms | TOP=L2:L3=L2/L4:L6=L5/L7:BOTTOM=L7 |
| SSD_PERST_Y14 | OTHERS | BUS | 8 | 4.75 | 5 | 10 | 5 | 14 | 6 | 9.5 | 12 | 12 | 12 | 12 |  | 50 Ohms | TOP=L2:L3=L2/L4:L6=L5/L7:BOTTOM=L7 |
| SSD_PERST_Y2 | OTHERS | BUS | 1 | 4.75 | 5 | 10 | 5 | 14 | 6 | 9.5 | 12 | 12 | 12 | 12 |  | 50 Ohms | TOP=L2:L3=L2/L4:L6=L5/L7:BOTTOM=L7 |
| SSD_PERST_Y2 | OTHERS | BUS | 2 | 5 | 5 | 10 | 5 | 14 | 6 | 10 | 12 | 12 | 12 | 12 |  | 50 Ohms | TOP=L2:L3=L2/L4:L6=L5/L7:BOTTOM=L7 |
| SSD_PERST_Y2 | OTHERS | BUS | 3 | 5 | 5 | 10 | 5 | 14 | 6 | 10 | 12 | 12 | 12 | 12 |  | 50 Ohms | TOP=L2:L3=L2/L4:L6=L5/L7:BOTTOM=L7 |
| SSD_PERST_Y2 | OTHERS | BUS | 4 | 5 | 5 | 10 | 5 | 14 | 6 | 10 | 12 | 12 | 12 | 12 |  | 50 Ohms | TOP=L2:L3=L2/L4:L6=L5/L7:BOTTOM=L7 |
| SSD_PERST_Y2 | OTHERS | BUS | 5 | 5 | 5 | 10 | 5 | 14 | 6 | 10 | 12 | 12 | 12 | 12 |  | 50 Ohms | TOP=L2:L3=L2/L4:L6=L5/L7:BOTTOM=L7 |
| SSD_PERST_Y2 | OTHERS | BUS | 6 | 5 | 5 | 10 | 5 | 14 | 6 | 10 | 12 | 12 | 12 | 12 |  | 50 Ohms | TOP=L2:L3=L2/L4:L6=L5/L7:BOTTOM=L7 |
| SSD_PERST_Y2 | OTHERS | BUS | 7 | 5 | 5 | 10 | 5 | 14 | 6 | 10 | 12 | 12 | 12 | 12 |  | 50 Ohms | TOP=L2:L3=L2/L4:L6=L5/L7:BOTTOM=L7 |
| SSD_PERST_Y2 | OTHERS | BUS | 8 | 4.75 | 5 | 10 | 5 | 14 | 6 | 9.5 | 12 | 12 | 12 | 12 |  | 50 Ohms | TOP=L2:L3=L2/L4:L6=L5/L7:BOTTOM=L7 |
| SSD_PERST_Y3 | OTHERS | BUS | 1 | 4.75 | 5 | 10 | 5 | 14 | 6 | 9.5 | 12 | 12 | 12 | 12 |  | 50 Ohms | TOP=L2:L3=L2/L4:L6=L5/L7:BOTTOM=L7 |
| SSD_PERST_Y3 | OTHERS | BUS | 2 | 5 | 5 | 10 | 5 | 14 | 6 | 10 | 12 | 12 | 12 | 12 |  | 50 Ohms | TOP=L2:L3=L2/L4:L6=L5/L7:BOTTOM=L7 |
| SSD_PERST_Y3 | OTHERS | BUS | 3 | 5 | 5 | 10 | 5 | 14 | 6 | 10 | 12 | 12 | 12 | 12 |  | 50 Ohms | TOP=L2:L3=L2/L4:L6=L5/L7:BOTTOM=L7 |
| SSD_PERST_Y3 | OTHERS | BUS | 4 | 5 | 5 | 10 | 5 | 14 | 6 | 10 | 12 | 12 | 12 | 12 |  | 50 Ohms | TOP=L2:L3=L2/L4:L6=L5/L7:BOTTOM=L7 |
| SSD_PERST_Y3 | OTHERS | BUS | 5 | 5 | 5 | 10 | 5 | 14 | 6 | 10 | 12 | 12 | 12 | 12 |  | 50 Ohms | TOP=L2:L3=L2/L4:L6=L5/L7:BOTTOM=L7 |
| SSD_PERST_Y3 | OTHERS | BUS | 6 | 5 | 5 | 10 | 5 | 14 | 6 | 10 | 12 | 12 | 12 | 12 |  | 50 Ohms | TOP=L2:L3=L2/L4:L6=L5/L7:BOTTOM=L7 |
| SSD_PERST_Y3 | OTHERS | BUS | 7 | 5 | 5 | 10 | 5 | 14 | 6 | 10 | 12 | 12 | 12 | 12 |  | 50 Ohms | TOP=L2:L3=L2/L4:L6=L5/L7:BOTTOM=L7 |
| SSD_PERST_Y3 | OTHERS | BUS | 8 | 4.75 | 5 | 10 | 5 | 14 | 6 | 9.5 | 12 | 12 | 12 | 12 |  | 50 Ohms | TOP=L2:L3=L2/L4:L6=L5/L7:BOTTOM=L7 |
| SSD_PERST_Y4 | OTHERS | BUS | 1 | 4.75 | 5 | 10 | 5 | 14 | 6 | 9.5 | 12 | 12 | 12 | 12 |  | 50 Ohms | TOP=L2:L3=L2/L4:L6=L5/L7:BOTTOM=L7 |
| SSD_PERST_Y4 | OTHERS | BUS | 2 | 5 | 5 | 10 | 5 | 14 | 6 | 10 | 12 | 12 | 12 | 12 |  | 50 Ohms | TOP=L2:L3=L2/L4:L6=L5/L7:BOTTOM=L7 |
| SSD_PERST_Y4 | OTHERS | BUS | 3 | 5 | 5 | 10 | 5 | 14 | 6 | 10 | 12 | 12 | 12 | 12 |  | 50 Ohms | TOP=L2:L3=L2/L4:L6=L5/L7:BOTTOM=L7 |
| SSD_PERST_Y4 | OTHERS | BUS | 4 | 5 | 5 | 10 | 5 | 14 | 6 | 10 | 12 | 12 | 12 | 12 |  | 50 Ohms | TOP=L2:L3=L2/L4:L6=L5/L7:BOTTOM=L7 |
| SSD_PERST_Y4 | OTHERS | BUS | 5 | 5 | 5 | 10 | 5 | 14 | 6 | 10 | 12 | 12 | 12 | 12 |  | 50 Ohms | TOP=L2:L3=L2/L4:L6=L5/L7:BOTTOM=L7 |
| SSD_PERST_Y4 | OTHERS | BUS | 6 | 5 | 5 | 10 | 5 | 14 | 6 | 10 | 12 | 12 | 12 | 12 |  | 50 Ohms | TOP=L2:L3=L2/L4:L6=L5/L7:BOTTOM=L7 |
| SSD_PERST_Y4 | OTHERS | BUS | 7 | 5 | 5 | 10 | 5 | 14 | 6 | 10 | 12 | 12 | 12 | 12 |  | 50 Ohms | TOP=L2:L3=L2/L4:L6=L5/L7:BOTTOM=L7 |
| SSD_PERST_Y4 | OTHERS | BUS | 8 | 4.75 | 5 | 10 | 5 | 14 | 6 | 9.5 | 12 | 12 | 12 | 12 |  | 50 Ohms | TOP=L2:L3=L2/L4:L6=L5/L7:BOTTOM=L7 |
| SSD_PERST_Y5 | OTHERS | BUS | 1 | 4.75 | 5 | 10 | 5 | 14 | 6 | 9.5 | 12 | 12 | 12 | 12 |  | 50 Ohms | TOP=L2:L3=L2/L4:L6=L5/L7:BOTTOM=L7 |
| SSD_PERST_Y5 | OTHERS | BUS | 2 | 5 | 5 | 10 | 5 | 14 | 6 | 10 | 12 | 12 | 12 | 12 |  | 50 Ohms | TOP=L2:L3=L2/L4:L6=L5/L7:BOTTOM=L7 |
| SSD_PERST_Y5 | OTHERS | BUS | 3 | 5 | 5 | 10 | 5 | 14 | 6 | 10 | 12 | 12 | 12 | 12 |  | 50 Ohms | TOP=L2:L3=L2/L4:L6=L5/L7:BOTTOM=L7 |
| SSD_PERST_Y5 | OTHERS | BUS | 4 | 5 | 5 | 10 | 5 | 14 | 6 | 10 | 12 | 12 | 12 | 12 |  | 50 Ohms | TOP=L2:L3=L2/L4:L6=L5/L7:BOTTOM=L7 |
| SSD_PERST_Y5 | OTHERS | BUS | 5 | 5 | 5 | 10 | 5 | 14 | 6 | 10 | 12 | 12 | 12 | 12 |  | 50 Ohms | TOP=L2:L3=L2/L4:L6=L5/L7:BOTTOM=L7 |
| SSD_PERST_Y5 | OTHERS | BUS | 6 | 5 | 5 | 10 | 5 | 14 | 6 | 10 | 12 | 12 | 12 | 12 |  | 50 Ohms | TOP=L2:L3=L2/L4:L6=L5/L7:BOTTOM=L7 |
| SSD_PERST_Y5 | OTHERS | BUS | 7 | 5 | 5 | 10 | 5 | 14 | 6 | 10 | 12 | 12 | 12 | 12 |  | 50 Ohms | TOP=L2:L3=L2/L4:L6=L5/L7:BOTTOM=L7 |
| SSD_PERST_Y5 | OTHERS | BUS | 8 | 4.75 | 5 | 10 | 5 | 14 | 6 | 9.5 | 12 | 12 | 12 | 12 |  | 50 Ohms | TOP=L2:L3=L2/L4:L6=L5/L7:BOTTOM=L7 |
| SSD_PERST_Y6 | OTHERS | BUS | 1 | 4.75 | 5 | 10 | 5 | 14 | 6 | 9.5 | 12 | 12 | 12 | 12 |  | 50 Ohms | TOP=L2:L3=L2/L4:L6=L5/L7:BOTTOM=L7 |
| SSD_PERST_Y6 | OTHERS | BUS | 2 | 5 | 5 | 10 | 5 | 14 | 6 | 10 | 12 | 12 | 12 | 12 |  | 50 Ohms | TOP=L2:L3=L2/L4:L6=L5/L7:BOTTOM=L7 |
| SSD_PERST_Y6 | OTHERS | BUS | 3 | 5 | 5 | 10 | 5 | 14 | 6 | 10 | 12 | 12 | 12 | 12 |  | 50 Ohms | TOP=L2:L3=L2/L4:L6=L5/L7:BOTTOM=L7 |
| SSD_PERST_Y6 | OTHERS | BUS | 4 | 5 | 5 | 10 | 5 | 14 | 6 | 10 | 12 | 12 | 12 | 12 |  | 50 Ohms | TOP=L2:L3=L2/L4:L6=L5/L7:BOTTOM=L7 |
| SSD_PERST_Y6 | OTHERS | BUS | 5 | 5 | 5 | 10 | 5 | 14 | 6 | 10 | 12 | 12 | 12 | 12 |  | 50 Ohms | TOP=L2:L3=L2/L4:L6=L5/L7:BOTTOM=L7 |
| SSD_PERST_Y6 | OTHERS | BUS | 6 | 5 | 5 | 10 | 5 | 14 | 6 | 10 | 12 | 12 | 12 | 12 |  | 50 Ohms | TOP=L2:L3=L2/L4:L6=L5/L7:BOTTOM=L7 |
| SSD_PERST_Y6 | OTHERS | BUS | 7 | 5 | 5 | 10 | 5 | 14 | 6 | 10 | 12 | 12 | 12 | 12 |  | 50 Ohms | TOP=L2:L3=L2/L4:L6=L5/L7:BOTTOM=L7 |
| SSD_PERST_Y6 | OTHERS | BUS | 8 | 4.75 | 5 | 10 | 5 | 14 | 6 | 9.5 | 12 | 12 | 12 | 12 |  | 50 Ohms | TOP=L2:L3=L2/L4:L6=L5/L7:BOTTOM=L7 |
| SSD_PERST_Y7 | OTHERS | BUS | 1 | 4.75 | 5 | 10 | 5 | 14 | 6 | 9.5 | 12 | 12 | 12 | 12 |  | 50 Ohms | TOP=L2:L3=L2/L4:L6=L5/L7:BOTTOM=L7 |
| SSD_PERST_Y7 | OTHERS | BUS | 2 | 5 | 5 | 10 | 5 | 14 | 6 | 10 | 12 | 12 | 12 | 12 |  | 50 Ohms | TOP=L2:L3=L2/L4:L6=L5/L7:BOTTOM=L7 |
| SSD_PERST_Y7 | OTHERS | BUS | 3 | 5 | 5 | 10 | 5 | 14 | 6 | 10 | 12 | 12 | 12 | 12 |  | 50 Ohms | TOP=L2:L3=L2/L4:L6=L5/L7:BOTTOM=L7 |
| SSD_PERST_Y7 | OTHERS | BUS | 4 | 5 | 5 | 10 | 5 | 14 | 6 | 10 | 12 | 12 | 12 | 12 |  | 50 Ohms | TOP=L2:L3=L2/L4:L6=L5/L7:BOTTOM=L7 |
| SSD_PERST_Y7 | OTHERS | BUS | 5 | 5 | 5 | 10 | 5 | 14 | 6 | 10 | 12 | 12 | 12 | 12 |  | 50 Ohms | TOP=L2:L3=L2/L4:L6=L5/L7:BOTTOM=L7 |
| SSD_PERST_Y7 | OTHERS | BUS | 6 | 5 | 5 | 10 | 5 | 14 | 6 | 10 | 12 | 12 | 12 | 12 |  | 50 Ohms | TOP=L2:L3=L2/L4:L6=L5/L7:BOTTOM=L7 |
| SSD_PERST_Y7 | OTHERS | BUS | 7 | 5 | 5 | 10 | 5 | 14 | 6 | 10 | 12 | 12 | 12 | 12 |  | 50 Ohms | TOP=L2:L3=L2/L4:L6=L5/L7:BOTTOM=L7 |
| SSD_PERST_Y7 | OTHERS | BUS | 8 | 4.75 | 5 | 10 | 5 | 14 | 6 | 9.5 | 12 | 12 | 12 | 12 |  | 50 Ohms | TOP=L2:L3=L2/L4:L6=L5/L7:BOTTOM=L7 |
| SSD_PERST_Y8 | OTHERS | BUS | 1 | 4.75 | 5 | 10 | 5 | 14 | 6 | 9.5 | 12 | 12 | 12 | 12 |  | 50 Ohms | TOP=L2:L3=L2/L4:L6=L5/L7:BOTTOM=L7 |
| SSD_PERST_Y8 | OTHERS | BUS | 2 | 5 | 5 | 10 | 5 | 14 | 6 | 10 | 12 | 12 | 12 | 12 |  | 50 Ohms | TOP=L2:L3=L2/L4:L6=L5/L7:BOTTOM=L7 |
| SSD_PERST_Y8 | OTHERS | BUS | 3 | 5 | 5 | 10 | 5 | 14 | 6 | 10 | 12 | 12 | 12 | 12 |  | 50 Ohms | TOP=L2:L3=L2/L4:L6=L5/L7:BOTTOM=L7 |
| SSD_PERST_Y8 | OTHERS | BUS | 4 | 5 | 5 | 10 | 5 | 14 | 6 | 10 | 12 | 12 | 12 | 12 |  | 50 Ohms | TOP=L2:L3=L2/L4:L6=L5/L7:BOTTOM=L7 |
| SSD_PERST_Y8 | OTHERS | BUS | 5 | 5 | 5 | 10 | 5 | 14 | 6 | 10 | 12 | 12 | 12 | 12 |  | 50 Ohms | TOP=L2:L3=L2/L4:L6=L5/L7:BOTTOM=L7 |
| SSD_PERST_Y8 | OTHERS | BUS | 6 | 5 | 5 | 10 | 5 | 14 | 6 | 10 | 12 | 12 | 12 | 12 |  | 50 Ohms | TOP=L2:L3=L2/L4:L6=L5/L7:BOTTOM=L7 |
| SSD_PERST_Y8 | OTHERS | BUS | 7 | 5 | 5 | 10 | 5 | 14 | 6 | 10 | 12 | 12 | 12 | 12 |  | 50 Ohms | TOP=L2:L3=L2/L4:L6=L5/L7:BOTTOM=L7 |
| SSD_PERST_Y8 | OTHERS | BUS | 8 | 4.75 | 5 | 10 | 5 | 14 | 6 | 9.5 | 12 | 12 | 12 | 12 |  | 50 Ohms | TOP=L2:L3=L2/L4:L6=L5/L7:BOTTOM=L7 |
| SSD_PERST_Y9 | OTHERS | BUS | 1 | 4.75 | 5 | 10 | 5 | 14 | 6 | 9.5 | 12 | 12 | 12 | 12 |  | 50 Ohms | TOP=L2:L3=L2/L4:L6=L5/L7:BOTTOM=L7 |
| SSD_PERST_Y9 | OTHERS | BUS | 2 | 5 | 5 | 10 | 5 | 14 | 6 | 10 | 12 | 12 | 12 | 12 |  | 50 Ohms | TOP=L2:L3=L2/L4:L6=L5/L7:BOTTOM=L7 |
| SSD_PERST_Y9 | OTHERS | BUS | 3 | 5 | 5 | 10 | 5 | 14 | 6 | 10 | 12 | 12 | 12 | 12 |  | 50 Ohms | TOP=L2:L3=L2/L4:L6=L5/L7:BOTTOM=L7 |
| SSD_PERST_Y9 | OTHERS | BUS | 4 | 5 | 5 | 10 | 5 | 14 | 6 | 10 | 12 | 12 | 12 | 12 |  | 50 Ohms | TOP=L2:L3=L2/L4:L6=L5/L7:BOTTOM=L7 |
| SSD_PERST_Y9 | OTHERS | BUS | 5 | 5 | 5 | 10 | 5 | 14 | 6 | 10 | 12 | 12 | 12 | 12 |  | 50 Ohms | TOP=L2:L3=L2/L4:L6=L5/L7:BOTTOM=L7 |
| SSD_PERST_Y9 | OTHERS | BUS | 6 | 5 | 5 | 10 | 5 | 14 | 6 | 10 | 12 | 12 | 12 | 12 |  | 50 Ohms | TOP=L2:L3=L2/L4:L6=L5/L7:BOTTOM=L7 |
| SSD_PERST_Y9 | OTHERS | BUS | 7 | 5 | 5 | 10 | 5 | 14 | 6 | 10 | 12 | 12 | 12 | 12 |  | 50 Ohms | TOP=L2:L3=L2/L4:L6=L5/L7:BOTTOM=L7 |
| SSD_PERST_Y9 | OTHERS | BUS | 8 | 4.75 | 5 | 10 | 5 | 14 | 6 | 9.5 | 12 | 12 | 12 | 12 |  | 50 Ohms | TOP=L2:L3=L2/L4:L6=L5/L7:BOTTOM=L7 |
| SSD_PRSNT#0 | OTHERS | BUS | 1 | 4.75 | 5 | 10 | 5 | 14 | 6 | 9.5 | 12 | 12 | 12 | 12 |  | 50 Ohms | TOP=L2:L3=L2/L4:L6=L5/L7:BOTTOM=L7 |
| SSD_PRSNT#0 | OTHERS | BUS | 2 | 5 | 5 | 10 | 5 | 14 | 6 | 10 | 12 | 12 | 12 | 12 |  | 50 Ohms | TOP=L2:L3=L2/L4:L6=L5/L7:BOTTOM=L7 |
| SSD_PRSNT#0 | OTHERS | BUS | 3 | 5 | 5 | 10 | 5 | 14 | 6 | 10 | 12 | 12 | 12 | 12 |  | 50 Ohms | TOP=L2:L3=L2/L4:L6=L5/L7:BOTTOM=L7 |
| SSD_PRSNT#0 | OTHERS | BUS | 4 | 5 | 5 | 10 | 5 | 14 | 6 | 10 | 12 | 12 | 12 | 12 |  | 50 Ohms | TOP=L2:L3=L2/L4:L6=L5/L7:BOTTOM=L7 |
| SSD_PRSNT#0 | OTHERS | BUS | 5 | 5 | 5 | 10 | 5 | 14 | 6 | 10 | 12 | 12 | 12 | 12 |  | 50 Ohms | TOP=L2:L3=L2/L4:L6=L5/L7:BOTTOM=L7 |
| SSD_PRSNT#0 | OTHERS | BUS | 6 | 5 | 5 | 10 | 5 | 14 | 6 | 10 | 12 | 12 | 12 | 12 |  | 50 Ohms | TOP=L2:L3=L2/L4:L6=L5/L7:BOTTOM=L7 |
| SSD_PRSNT#0 | OTHERS | BUS | 7 | 5 | 5 | 10 | 5 | 14 | 6 | 10 | 12 | 12 | 12 | 12 |  | 50 Ohms | TOP=L2:L3=L2/L4:L6=L5/L7:BOTTOM=L7 |
| SSD_PRSNT#0 | OTHERS | BUS | 8 | 4.75 | 5 | 10 | 5 | 14 | 6 | 9.5 | 12 | 12 | 12 | 12 |  | 50 Ohms | TOP=L2:L3=L2/L4:L6=L5/L7:BOTTOM=L7 |
| SSD_PRSNT#0_R | OTHERS | BUS | 1 | 4.75 | 5 | 10 | 5 | 14 | 6 | 9.5 | 12 | 12 | 12 | 12 |  | 50 Ohms | TOP=L2:L3=L2/L4:L6=L5/L7:BOTTOM=L7 |
| SSD_PRSNT#0_R | OTHERS | BUS | 2 | 5 | 5 | 10 | 5 | 14 | 6 | 10 | 12 | 12 | 12 | 12 |  | 50 Ohms | TOP=L2:L3=L2/L4:L6=L5/L7:BOTTOM=L7 |
| SSD_PRSNT#0_R | OTHERS | BUS | 3 | 5 | 5 | 10 | 5 | 14 | 6 | 10 | 12 | 12 | 12 | 12 |  | 50 Ohms | TOP=L2:L3=L2/L4:L6=L5/L7:BOTTOM=L7 |
| SSD_PRSNT#0_R | OTHERS | BUS | 4 | 5 | 5 | 10 | 5 | 14 | 6 | 10 | 12 | 12 | 12 | 12 |  | 50 Ohms | TOP=L2:L3=L2/L4:L6=L5/L7:BOTTOM=L7 |
| SSD_PRSNT#0_R | OTHERS | BUS | 5 | 5 | 5 | 10 | 5 | 14 | 6 | 10 | 12 | 12 | 12 | 12 |  | 50 Ohms | TOP=L2:L3=L2/L4:L6=L5/L7:BOTTOM=L7 |
| SSD_PRSNT#0_R | OTHERS | BUS | 6 | 5 | 5 | 10 | 5 | 14 | 6 | 10 | 12 | 12 | 12 | 12 |  | 50 Ohms | TOP=L2:L3=L2/L4:L6=L5/L7:BOTTOM=L7 |
| SSD_PRSNT#0_R | OTHERS | BUS | 7 | 5 | 5 | 10 | 5 | 14 | 6 | 10 | 12 | 12 | 12 | 12 |  | 50 Ohms | TOP=L2:L3=L2/L4:L6=L5/L7:BOTTOM=L7 |
| SSD_PRSNT#0_R | OTHERS | BUS | 8 | 4.75 | 5 | 10 | 5 | 14 | 6 | 9.5 | 12 | 12 | 12 | 12 |  | 50 Ohms | TOP=L2:L3=L2/L4:L6=L5/L7:BOTTOM=L7 |
| SSD_PRSNT#1 | OTHERS | BUS | 1 | 4.75 | 5 | 10 | 5 | 14 | 6 | 9.5 | 12 | 12 | 12 | 12 |  | 50 Ohms | TOP=L2:L3=L2/L4:L6=L5/L7:BOTTOM=L7 |
| SSD_PRSNT#1 | OTHERS | BUS | 2 | 5 | 5 | 10 | 5 | 14 | 6 | 10 | 12 | 12 | 12 | 12 |  | 50 Ohms | TOP=L2:L3=L2/L4:L6=L5/L7:BOTTOM=L7 |
| SSD_PRSNT#1 | OTHERS | BUS | 3 | 5 | 5 | 10 | 5 | 14 | 6 | 10 | 12 | 12 | 12 | 12 |  | 50 Ohms | TOP=L2:L3=L2/L4:L6=L5/L7:BOTTOM=L7 |
| SSD_PRSNT#1 | OTHERS | BUS | 4 | 5 | 5 | 10 | 5 | 14 | 6 | 10 | 12 | 12 | 12 | 12 |  | 50 Ohms | TOP=L2:L3=L2/L4:L6=L5/L7:BOTTOM=L7 |
| SSD_PRSNT#1 | OTHERS | BUS | 5 | 5 | 5 | 10 | 5 | 14 | 6 | 10 | 12 | 12 | 12 | 12 |  | 50 Ohms | TOP=L2:L3=L2/L4:L6=L5/L7:BOTTOM=L7 |
| SSD_PRSNT#1 | OTHERS | BUS | 6 | 5 | 5 | 10 | 5 | 14 | 6 | 10 | 12 | 12 | 12 | 12 |  | 50 Ohms | TOP=L2:L3=L2/L4:L6=L5/L7:BOTTOM=L7 |
| SSD_PRSNT#1 | OTHERS | BUS | 7 | 5 | 5 | 10 | 5 | 14 | 6 | 10 | 12 | 12 | 12 | 12 |  | 50 Ohms | TOP=L2:L3=L2/L4:L6=L5/L7:BOTTOM=L7 |
| SSD_PRSNT#1 | OTHERS | BUS | 8 | 4.75 | 5 | 10 | 5 | 14 | 6 | 9.5 | 12 | 12 | 12 | 12 |  | 50 Ohms | TOP=L2:L3=L2/L4:L6=L5/L7:BOTTOM=L7 |
| SSD_PRSNT#1_R | OTHERS | BUS | 1 | 4.75 | 5 | 10 | 5 | 14 | 6 | 9.5 | 12 | 12 | 12 | 12 |  | 50 Ohms | TOP=L2:L3=L2/L4:L6=L5/L7:BOTTOM=L7 |
| SSD_PRSNT#1_R | OTHERS | BUS | 2 | 5 | 5 | 10 | 5 | 14 | 6 | 10 | 12 | 12 | 12 | 12 |  | 50 Ohms | TOP=L2:L3=L2/L4:L6=L5/L7:BOTTOM=L7 |
| SSD_PRSNT#1_R | OTHERS | BUS | 3 | 5 | 5 | 10 | 5 | 14 | 6 | 10 | 12 | 12 | 12 | 12 |  | 50 Ohms | TOP=L2:L3=L2/L4:L6=L5/L7:BOTTOM=L7 |
| SSD_PRSNT#1_R | OTHERS | BUS | 4 | 5 | 5 | 10 | 5 | 14 | 6 | 10 | 12 | 12 | 12 | 12 |  | 50 Ohms | TOP=L2:L3=L2/L4:L6=L5/L7:BOTTOM=L7 |
| SSD_PRSNT#1_R | OTHERS | BUS | 5 | 5 | 5 | 10 | 5 | 14 | 6 | 10 | 12 | 12 | 12 | 12 |  | 50 Ohms | TOP=L2:L3=L2/L4:L6=L5/L7:BOTTOM=L7 |
| SSD_PRSNT#1_R | OTHERS | BUS | 6 | 5 | 5 | 10 | 5 | 14 | 6 | 10 | 12 | 12 | 12 | 12 |  | 50 Ohms | TOP=L2:L3=L2/L4:L6=L5/L7:BOTTOM=L7 |
| SSD_PRSNT#1_R | OTHERS | BUS | 7 | 5 | 5 | 10 | 5 | 14 | 6 | 10 | 12 | 12 | 12 | 12 |  | 50 Ohms | TOP=L2:L3=L2/L4:L6=L5/L7:BOTTOM=L7 |
| SSD_PRSNT#1_R | OTHERS | BUS | 8 | 4.75 | 5 | 10 | 5 | 14 | 6 | 9.5 | 12 | 12 | 12 | 12 |  | 50 Ohms | TOP=L2:L3=L2/L4:L6=L5/L7:BOTTOM=L7 |
| SSD_PRSNT#10 | OTHERS | BUS | 1 | 4.75 | 5 | 10 | 5 | 14 | 6 | 9.5 | 12 | 12 | 12 | 12 |  | 50 Ohms | TOP=L2:L3=L2/L4:L6=L5/L7:BOTTOM=L7 |
| SSD_PRSNT#10 | OTHERS | BUS | 2 | 5 | 5 | 10 | 5 | 14 | 6 | 10 | 12 | 12 | 12 | 12 |  | 50 Ohms | TOP=L2:L3=L2/L4:L6=L5/L7:BOTTOM=L7 |
| SSD_PRSNT#10 | OTHERS | BUS | 3 | 5 | 5 | 10 | 5 | 14 | 6 | 10 | 12 | 12 | 12 | 12 |  | 50 Ohms | TOP=L2:L3=L2/L4:L6=L5/L7:BOTTOM=L7 |
| SSD_PRSNT#10 | OTHERS | BUS | 4 | 5 | 5 | 10 | 5 | 14 | 6 | 10 | 12 | 12 | 12 | 12 |  | 50 Ohms | TOP=L2:L3=L2/L4:L6=L5/L7:BOTTOM=L7 |
| SSD_PRSNT#10 | OTHERS | BUS | 5 | 5 | 5 | 10 | 5 | 14 | 6 | 10 | 12 | 12 | 12 | 12 |  | 50 Ohms | TOP=L2:L3=L2/L4:L6=L5/L7:BOTTOM=L7 |
| SSD_PRSNT#10 | OTHERS | BUS | 6 | 5 | 5 | 10 | 5 | 14 | 6 | 10 | 12 | 12 | 12 | 12 |  | 50 Ohms | TOP=L2:L3=L2/L4:L6=L5/L7:BOTTOM=L7 |
| SSD_PRSNT#10 | OTHERS | BUS | 7 | 5 | 5 | 10 | 5 | 14 | 6 | 10 | 12 | 12 | 12 | 12 |  | 50 Ohms | TOP=L2:L3=L2/L4:L6=L5/L7:BOTTOM=L7 |
| SSD_PRSNT#10 | OTHERS | BUS | 8 | 4.75 | 5 | 10 | 5 | 14 | 6 | 9.5 | 12 | 12 | 12 | 12 |  | 50 Ohms | TOP=L2:L3=L2/L4:L6=L5/L7:BOTTOM=L7 |
| SSD_PRSNT#10_R | OTHERS | BUS | 1 | 4.75 | 5 | 10 | 5 | 14 | 6 | 9.5 | 12 | 12 | 12 | 12 |  | 50 Ohms | TOP=L2:L3=L2/L4:L6=L5/L7:BOTTOM=L7 |
| SSD_PRSNT#10_R | OTHERS | BUS | 2 | 5 | 5 | 10 | 5 | 14 | 6 | 10 | 12 | 12 | 12 | 12 |  | 50 Ohms | TOP=L2:L3=L2/L4:L6=L5/L7:BOTTOM=L7 |
| SSD_PRSNT#10_R | OTHERS | BUS | 3 | 5 | 5 | 10 | 5 | 14 | 6 | 10 | 12 | 12 | 12 | 12 |  | 50 Ohms | TOP=L2:L3=L2/L4:L6=L5/L7:BOTTOM=L7 |
| SSD_PRSNT#10_R | OTHERS | BUS | 4 | 5 | 5 | 10 | 5 | 14 | 6 | 10 | 12 | 12 | 12 | 12 |  | 50 Ohms | TOP=L2:L3=L2/L4:L6=L5/L7:BOTTOM=L7 |
| SSD_PRSNT#10_R | OTHERS | BUS | 5 | 5 | 5 | 10 | 5 | 14 | 6 | 10 | 12 | 12 | 12 | 12 |  | 50 Ohms | TOP=L2:L3=L2/L4:L6=L5/L7:BOTTOM=L7 |
| SSD_PRSNT#10_R | OTHERS | BUS | 6 | 5 | 5 | 10 | 5 | 14 | 6 | 10 | 12 | 12 | 12 | 12 |  | 50 Ohms | TOP=L2:L3=L2/L4:L6=L5/L7:BOTTOM=L7 |
| SSD_PRSNT#10_R | OTHERS | BUS | 7 | 5 | 5 | 10 | 5 | 14 | 6 | 10 | 12 | 12 | 12 | 12 |  | 50 Ohms | TOP=L2:L3=L2/L4:L6=L5/L7:BOTTOM=L7 |
| SSD_PRSNT#10_R | OTHERS | BUS | 8 | 4.75 | 5 | 10 | 5 | 14 | 6 | 9.5 | 12 | 12 | 12 | 12 |  | 50 Ohms | TOP=L2:L3=L2/L4:L6=L5/L7:BOTTOM=L7 |
| SSD_PRSNT#11 | OTHERS | BUS | 1 | 4.75 | 5 | 10 | 5 | 14 | 6 | 9.5 | 12 | 12 | 12 | 12 |  | 50 Ohms | TOP=L2:L3=L2/L4:L6=L5/L7:BOTTOM=L7 |
| SSD_PRSNT#11 | OTHERS | BUS | 2 | 5 | 5 | 10 | 5 | 14 | 6 | 10 | 12 | 12 | 12 | 12 |  | 50 Ohms | TOP=L2:L3=L2/L4:L6=L5/L7:BOTTOM=L7 |
| SSD_PRSNT#11 | OTHERS | BUS | 3 | 5 | 5 | 10 | 5 | 14 | 6 | 10 | 12 | 12 | 12 | 12 |  | 50 Ohms | TOP=L2:L3=L2/L4:L6=L5/L7:BOTTOM=L7 |
| SSD_PRSNT#11 | OTHERS | BUS | 4 | 5 | 5 | 10 | 5 | 14 | 6 | 10 | 12 | 12 | 12 | 12 |  | 50 Ohms | TOP=L2:L3=L2/L4:L6=L5/L7:BOTTOM=L7 |
| SSD_PRSNT#11 | OTHERS | BUS | 5 | 5 | 5 | 10 | 5 | 14 | 6 | 10 | 12 | 12 | 12 | 12 |  | 50 Ohms | TOP=L2:L3=L2/L4:L6=L5/L7:BOTTOM=L7 |
| SSD_PRSNT#11 | OTHERS | BUS | 6 | 5 | 5 | 10 | 5 | 14 | 6 | 10 | 12 | 12 | 12 | 12 |  | 50 Ohms | TOP=L2:L3=L2/L4:L6=L5/L7:BOTTOM=L7 |
| SSD_PRSNT#11 | OTHERS | BUS | 7 | 5 | 5 | 10 | 5 | 14 | 6 | 10 | 12 | 12 | 12 | 12 |  | 50 Ohms | TOP=L2:L3=L2/L4:L6=L5/L7:BOTTOM=L7 |
| SSD_PRSNT#11 | OTHERS | BUS | 8 | 4.75 | 5 | 10 | 5 | 14 | 6 | 9.5 | 12 | 12 | 12 | 12 |  | 50 Ohms | TOP=L2:L3=L2/L4:L6=L5/L7:BOTTOM=L7 |
| SSD_PRSNT#11_R | OTHERS | BUS | 1 | 4.75 | 5 | 10 | 5 | 14 | 6 | 9.5 | 12 | 12 | 12 | 12 |  | 50 Ohms | TOP=L2:L3=L2/L4:L6=L5/L7:BOTTOM=L7 |
| SSD_PRSNT#11_R | OTHERS | BUS | 2 | 5 | 5 | 10 | 5 | 14 | 6 | 10 | 12 | 12 | 12 | 12 |  | 50 Ohms | TOP=L2:L3=L2/L4:L6=L5/L7:BOTTOM=L7 |
| SSD_PRSNT#11_R | OTHERS | BUS | 3 | 5 | 5 | 10 | 5 | 14 | 6 | 10 | 12 | 12 | 12 | 12 |  | 50 Ohms | TOP=L2:L3=L2/L4:L6=L5/L7:BOTTOM=L7 |
| SSD_PRSNT#11_R | OTHERS | BUS | 4 | 5 | 5 | 10 | 5 | 14 | 6 | 10 | 12 | 12 | 12 | 12 |  | 50 Ohms | TOP=L2:L3=L2/L4:L6=L5/L7:BOTTOM=L7 |
| SSD_PRSNT#11_R | OTHERS | BUS | 5 | 5 | 5 | 10 | 5 | 14 | 6 | 10 | 12 | 12 | 12 | 12 |  | 50 Ohms | TOP=L2:L3=L2/L4:L6=L5/L7:BOTTOM=L7 |
| SSD_PRSNT#11_R | OTHERS | BUS | 6 | 5 | 5 | 10 | 5 | 14 | 6 | 10 | 12 | 12 | 12 | 12 |  | 50 Ohms | TOP=L2:L3=L2/L4:L6=L5/L7:BOTTOM=L7 |
| SSD_PRSNT#11_R | OTHERS | BUS | 7 | 5 | 5 | 10 | 5 | 14 | 6 | 10 | 12 | 12 | 12 | 12 |  | 50 Ohms | TOP=L2:L3=L2/L4:L6=L5/L7:BOTTOM=L7 |
| SSD_PRSNT#11_R | OTHERS | BUS | 8 | 4.75 | 5 | 10 | 5 | 14 | 6 | 9.5 | 12 | 12 | 12 | 12 |  | 50 Ohms | TOP=L2:L3=L2/L4:L6=L5/L7:BOTTOM=L7 |
| SSD_PRSNT#12 | OTHERS | BUS | 1 | 4.75 | 5 | 10 | 5 | 14 | 6 | 9.5 | 12 | 12 | 12 | 12 |  | 50 Ohms | TOP=L2:L3=L2/L4:L6=L5/L7:BOTTOM=L7 |
| SSD_PRSNT#12 | OTHERS | BUS | 2 | 5 | 5 | 10 | 5 | 14 | 6 | 10 | 12 | 12 | 12 | 12 |  | 50 Ohms | TOP=L2:L3=L2/L4:L6=L5/L7:BOTTOM=L7 |
| SSD_PRSNT#12 | OTHERS | BUS | 3 | 5 | 5 | 10 | 5 | 14 | 6 | 10 | 12 | 12 | 12 | 12 |  | 50 Ohms | TOP=L2:L3=L2/L4:L6=L5/L7:BOTTOM=L7 |
| SSD_PRSNT#12 | OTHERS | BUS | 4 | 5 | 5 | 10 | 5 | 14 | 6 | 10 | 12 | 12 | 12 | 12 |  | 50 Ohms | TOP=L2:L3=L2/L4:L6=L5/L7:BOTTOM=L7 |
| SSD_PRSNT#12 | OTHERS | BUS | 5 | 5 | 5 | 10 | 5 | 14 | 6 | 10 | 12 | 12 | 12 | 12 |  | 50 Ohms | TOP=L2:L3=L2/L4:L6=L5/L7:BOTTOM=L7 |
| SSD_PRSNT#12 | OTHERS | BUS | 6 | 5 | 5 | 10 | 5 | 14 | 6 | 10 | 12 | 12 | 12 | 12 |  | 50 Ohms | TOP=L2:L3=L2/L4:L6=L5/L7:BOTTOM=L7 |
| SSD_PRSNT#12 | OTHERS | BUS | 7 | 5 | 5 | 10 | 5 | 14 | 6 | 10 | 12 | 12 | 12 | 12 |  | 50 Ohms | TOP=L2:L3=L2/L4:L6=L5/L7:BOTTOM=L7 |
| SSD_PRSNT#12 | OTHERS | BUS | 8 | 4.75 | 5 | 10 | 5 | 14 | 6 | 9.5 | 12 | 12 | 12 | 12 |  | 50 Ohms | TOP=L2:L3=L2/L4:L6=L5/L7:BOTTOM=L7 |
| SSD_PRSNT#12_R | OTHERS | BUS | 1 | 4.75 | 5 | 10 | 5 | 14 | 6 | 9.5 | 12 | 12 | 12 | 12 |  | 50 Ohms | TOP=L2:L3=L2/L4:L6=L5/L7:BOTTOM=L7 |
| SSD_PRSNT#12_R | OTHERS | BUS | 2 | 5 | 5 | 10 | 5 | 14 | 6 | 10 | 12 | 12 | 12 | 12 |  | 50 Ohms | TOP=L2:L3=L2/L4:L6=L5/L7:BOTTOM=L7 |
| SSD_PRSNT#12_R | OTHERS | BUS | 3 | 5 | 5 | 10 | 5 | 14 | 6 | 10 | 12 | 12 | 12 | 12 |  | 50 Ohms | TOP=L2:L3=L2/L4:L6=L5/L7:BOTTOM=L7 |
| SSD_PRSNT#12_R | OTHERS | BUS | 4 | 5 | 5 | 10 | 5 | 14 | 6 | 10 | 12 | 12 | 12 | 12 |  | 50 Ohms | TOP=L2:L3=L2/L4:L6=L5/L7:BOTTOM=L7 |
| SSD_PRSNT#12_R | OTHERS | BUS | 5 | 5 | 5 | 10 | 5 | 14 | 6 | 10 | 12 | 12 | 12 | 12 |  | 50 Ohms | TOP=L2:L3=L2/L4:L6=L5/L7:BOTTOM=L7 |
| SSD_PRSNT#12_R | OTHERS | BUS | 6 | 5 | 5 | 10 | 5 | 14 | 6 | 10 | 12 | 12 | 12 | 12 |  | 50 Ohms | TOP=L2:L3=L2/L4:L6=L5/L7:BOTTOM=L7 |
| SSD_PRSNT#12_R | OTHERS | BUS | 7 | 5 | 5 | 10 | 5 | 14 | 6 | 10 | 12 | 12 | 12 | 12 |  | 50 Ohms | TOP=L2:L3=L2/L4:L6=L5/L7:BOTTOM=L7 |
| SSD_PRSNT#12_R | OTHERS | BUS | 8 | 4.75 | 5 | 10 | 5 | 14 | 6 | 9.5 | 12 | 12 | 12 | 12 |  | 50 Ohms | TOP=L2:L3=L2/L4:L6=L5/L7:BOTTOM=L7 |
| SSD_PRSNT#13 | OTHERS | BUS | 1 | 4.75 | 5 | 10 | 5 | 14 | 6 | 9.5 | 12 | 12 | 12 | 12 |  | 50 Ohms | TOP=L2:L3=L2/L4:L6=L5/L7:BOTTOM=L7 |
| SSD_PRSNT#13 | OTHERS | BUS | 2 | 5 | 5 | 10 | 5 | 14 | 6 | 10 | 12 | 12 | 12 | 12 |  | 50 Ohms | TOP=L2:L3=L2/L4:L6=L5/L7:BOTTOM=L7 |
| SSD_PRSNT#13 | OTHERS | BUS | 3 | 5 | 5 | 10 | 5 | 14 | 6 | 10 | 12 | 12 | 12 | 12 |  | 50 Ohms | TOP=L2:L3=L2/L4:L6=L5/L7:BOTTOM=L7 |
| SSD_PRSNT#13 | OTHERS | BUS | 4 | 5 | 5 | 10 | 5 | 14 | 6 | 10 | 12 | 12 | 12 | 12 |  | 50 Ohms | TOP=L2:L3=L2/L4:L6=L5/L7:BOTTOM=L7 |
| SSD_PRSNT#13 | OTHERS | BUS | 5 | 5 | 5 | 10 | 5 | 14 | 6 | 10 | 12 | 12 | 12 | 12 |  | 50 Ohms | TOP=L2:L3=L2/L4:L6=L5/L7:BOTTOM=L7 |
| SSD_PRSNT#13 | OTHERS | BUS | 6 | 5 | 5 | 10 | 5 | 14 | 6 | 10 | 12 | 12 | 12 | 12 |  | 50 Ohms | TOP=L2:L3=L2/L4:L6=L5/L7:BOTTOM=L7 |
| SSD_PRSNT#13 | OTHERS | BUS | 7 | 5 | 5 | 10 | 5 | 14 | 6 | 10 | 12 | 12 | 12 | 12 |  | 50 Ohms | TOP=L2:L3=L2/L4:L6=L5/L7:BOTTOM=L7 |
| SSD_PRSNT#13 | OTHERS | BUS | 8 | 4.75 | 5 | 10 | 5 | 14 | 6 | 9.5 | 12 | 12 | 12 | 12 |  | 50 Ohms | TOP=L2:L3=L2/L4:L6=L5/L7:BOTTOM=L7 |
| SSD_PRSNT#13_R | OTHERS | BUS | 1 | 4.75 | 5 | 10 | 5 | 14 | 6 | 9.5 | 12 | 12 | 12 | 12 |  | 50 Ohms | TOP=L2:L3=L2/L4:L6=L5/L7:BOTTOM=L7 |
| SSD_PRSNT#13_R | OTHERS | BUS | 2 | 5 | 5 | 10 | 5 | 14 | 6 | 10 | 12 | 12 | 12 | 12 |  | 50 Ohms | TOP=L2:L3=L2/L4:L6=L5/L7:BOTTOM=L7 |
| SSD_PRSNT#13_R | OTHERS | BUS | 3 | 5 | 5 | 10 | 5 | 14 | 6 | 10 | 12 | 12 | 12 | 12 |  | 50 Ohms | TOP=L2:L3=L2/L4:L6=L5/L7:BOTTOM=L7 |
| SSD_PRSNT#13_R | OTHERS | BUS | 4 | 5 | 5 | 10 | 5 | 14 | 6 | 10 | 12 | 12 | 12 | 12 |  | 50 Ohms | TOP=L2:L3=L2/L4:L6=L5/L7:BOTTOM=L7 |
| SSD_PRSNT#13_R | OTHERS | BUS | 5 | 5 | 5 | 10 | 5 | 14 | 6 | 10 | 12 | 12 | 12 | 12 |  | 50 Ohms | TOP=L2:L3=L2/L4:L6=L5/L7:BOTTOM=L7 |
| SSD_PRSNT#13_R | OTHERS | BUS | 6 | 5 | 5 | 10 | 5 | 14 | 6 | 10 | 12 | 12 | 12 | 12 |  | 50 Ohms | TOP=L2:L3=L2/L4:L6=L5/L7:BOTTOM=L7 |
| SSD_PRSNT#13_R | OTHERS | BUS | 7 | 5 | 5 | 10 | 5 | 14 | 6 | 10 | 12 | 12 | 12 | 12 |  | 50 Ohms | TOP=L2:L3=L2/L4:L6=L5/L7:BOTTOM=L7 |
| SSD_PRSNT#13_R | OTHERS | BUS | 8 | 4.75 | 5 | 10 | 5 | 14 | 6 | 9.5 | 12 | 12 | 12 | 12 |  | 50 Ohms | TOP=L2:L3=L2/L4:L6=L5/L7:BOTTOM=L7 |
| SSD_PRSNT#14 | OTHERS | BUS | 1 | 4.75 | 5 | 10 | 5 | 14 | 6 | 9.5 | 12 | 12 | 12 | 12 |  | 50 Ohms | TOP=L2:L3=L2/L4:L6=L5/L7:BOTTOM=L7 |
| SSD_PRSNT#14 | OTHERS | BUS | 2 | 5 | 5 | 10 | 5 | 14 | 6 | 10 | 12 | 12 | 12 | 12 |  | 50 Ohms | TOP=L2:L3=L2/L4:L6=L5/L7:BOTTOM=L7 |
| SSD_PRSNT#14 | OTHERS | BUS | 3 | 5 | 5 | 10 | 5 | 14 | 6 | 10 | 12 | 12 | 12 | 12 |  | 50 Ohms | TOP=L2:L3=L2/L4:L6=L5/L7:BOTTOM=L7 |
| SSD_PRSNT#14 | OTHERS | BUS | 4 | 5 | 5 | 10 | 5 | 14 | 6 | 10 | 12 | 12 | 12 | 12 |  | 50 Ohms | TOP=L2:L3=L2/L4:L6=L5/L7:BOTTOM=L7 |
| SSD_PRSNT#14 | OTHERS | BUS | 5 | 5 | 5 | 10 | 5 | 14 | 6 | 10 | 12 | 12 | 12 | 12 |  | 50 Ohms | TOP=L2:L3=L2/L4:L6=L5/L7:BOTTOM=L7 |
| SSD_PRSNT#14 | OTHERS | BUS | 6 | 5 | 5 | 10 | 5 | 14 | 6 | 10 | 12 | 12 | 12 | 12 |  | 50 Ohms | TOP=L2:L3=L2/L4:L6=L5/L7:BOTTOM=L7 |
| SSD_PRSNT#14 | OTHERS | BUS | 7 | 5 | 5 | 10 | 5 | 14 | 6 | 10 | 12 | 12 | 12 | 12 |  | 50 Ohms | TOP=L2:L3=L2/L4:L6=L5/L7:BOTTOM=L7 |
| SSD_PRSNT#14 | OTHERS | BUS | 8 | 4.75 | 5 | 10 | 5 | 14 | 6 | 9.5 | 12 | 12 | 12 | 12 |  | 50 Ohms | TOP=L2:L3=L2/L4:L6=L5/L7:BOTTOM=L7 |
| SSD_PRSNT#14_R | OTHERS | BUS | 1 | 4.75 | 5 | 10 | 5 | 14 | 6 | 9.5 | 12 | 12 | 12 | 12 |  | 50 Ohms | TOP=L2:L3=L2/L4:L6=L5/L7:BOTTOM=L7 |
| SSD_PRSNT#14_R | OTHERS | BUS | 2 | 5 | 5 | 10 | 5 | 14 | 6 | 10 | 12 | 12 | 12 | 12 |  | 50 Ohms | TOP=L2:L3=L2/L4:L6=L5/L7:BOTTOM=L7 |
| SSD_PRSNT#14_R | OTHERS | BUS | 3 | 5 | 5 | 10 | 5 | 14 | 6 | 10 | 12 | 12 | 12 | 12 |  | 50 Ohms | TOP=L2:L3=L2/L4:L6=L5/L7:BOTTOM=L7 |
| SSD_PRSNT#14_R | OTHERS | BUS | 4 | 5 | 5 | 10 | 5 | 14 | 6 | 10 | 12 | 12 | 12 | 12 |  | 50 Ohms | TOP=L2:L3=L2/L4:L6=L5/L7:BOTTOM=L7 |
| SSD_PRSNT#14_R | OTHERS | BUS | 5 | 5 | 5 | 10 | 5 | 14 | 6 | 10 | 12 | 12 | 12 | 12 |  | 50 Ohms | TOP=L2:L3=L2/L4:L6=L5/L7:BOTTOM=L7 |
| SSD_PRSNT#14_R | OTHERS | BUS | 6 | 5 | 5 | 10 | 5 | 14 | 6 | 10 | 12 | 12 | 12 | 12 |  | 50 Ohms | TOP=L2:L3=L2/L4:L6=L5/L7:BOTTOM=L7 |
| SSD_PRSNT#14_R | OTHERS | BUS | 7 | 5 | 5 | 10 | 5 | 14 | 6 | 10 | 12 | 12 | 12 | 12 |  | 50 Ohms | TOP=L2:L3=L2/L4:L6=L5/L7:BOTTOM=L7 |
| SSD_PRSNT#14_R | OTHERS | BUS | 8 | 4.75 | 5 | 10 | 5 | 14 | 6 | 9.5 | 12 | 12 | 12 | 12 |  | 50 Ohms | TOP=L2:L3=L2/L4:L6=L5/L7:BOTTOM=L7 |
| SSD_PRSNT#2 | OTHERS | BUS | 1 | 4.75 | 5 | 10 | 5 | 14 | 6 | 9.5 | 12 | 12 | 12 | 12 |  | 50 Ohms | TOP=L2:L3=L2/L4:L6=L5/L7:BOTTOM=L7 |
| SSD_PRSNT#2 | OTHERS | BUS | 2 | 5 | 5 | 10 | 5 | 14 | 6 | 10 | 12 | 12 | 12 | 12 |  | 50 Ohms | TOP=L2:L3=L2/L4:L6=L5/L7:BOTTOM=L7 |
| SSD_PRSNT#2 | OTHERS | BUS | 3 | 5 | 5 | 10 | 5 | 14 | 6 | 10 | 12 | 12 | 12 | 12 |  | 50 Ohms | TOP=L2:L3=L2/L4:L6=L5/L7:BOTTOM=L7 |
| SSD_PRSNT#2 | OTHERS | BUS | 4 | 5 | 5 | 10 | 5 | 14 | 6 | 10 | 12 | 12 | 12 | 12 |  | 50 Ohms | TOP=L2:L3=L2/L4:L6=L5/L7:BOTTOM=L7 |
| SSD_PRSNT#2 | OTHERS | BUS | 5 | 5 | 5 | 10 | 5 | 14 | 6 | 10 | 12 | 12 | 12 | 12 |  | 50 Ohms | TOP=L2:L3=L2/L4:L6=L5/L7:BOTTOM=L7 |
| SSD_PRSNT#2 | OTHERS | BUS | 6 | 5 | 5 | 10 | 5 | 14 | 6 | 10 | 12 | 12 | 12 | 12 |  | 50 Ohms | TOP=L2:L3=L2/L4:L6=L5/L7:BOTTOM=L7 |
| SSD_PRSNT#2 | OTHERS | BUS | 7 | 5 | 5 | 10 | 5 | 14 | 6 | 10 | 12 | 12 | 12 | 12 |  | 50 Ohms | TOP=L2:L3=L2/L4:L6=L5/L7:BOTTOM=L7 |
| SSD_PRSNT#2 | OTHERS | BUS | 8 | 4.75 | 5 | 10 | 5 | 14 | 6 | 9.5 | 12 | 12 | 12 | 12 |  | 50 Ohms | TOP=L2:L3=L2/L4:L6=L5/L7:BOTTOM=L7 |
| SSD_PRSNT#2_R | OTHERS | BUS | 1 | 4.75 | 5 | 10 | 5 | 14 | 6 | 9.5 | 12 | 12 | 12 | 12 |  | 50 Ohms | TOP=L2:L3=L2/L4:L6=L5/L7:BOTTOM=L7 |
| SSD_PRSNT#2_R | OTHERS | BUS | 2 | 5 | 5 | 10 | 5 | 14 | 6 | 10 | 12 | 12 | 12 | 12 |  | 50 Ohms | TOP=L2:L3=L2/L4:L6=L5/L7:BOTTOM=L7 |
| SSD_PRSNT#2_R | OTHERS | BUS | 3 | 5 | 5 | 10 | 5 | 14 | 6 | 10 | 12 | 12 | 12 | 12 |  | 50 Ohms | TOP=L2:L3=L2/L4:L6=L5/L7:BOTTOM=L7 |
| SSD_PRSNT#2_R | OTHERS | BUS | 4 | 5 | 5 | 10 | 5 | 14 | 6 | 10 | 12 | 12 | 12 | 12 |  | 50 Ohms | TOP=L2:L3=L2/L4:L6=L5/L7:BOTTOM=L7 |
| SSD_PRSNT#2_R | OTHERS | BUS | 5 | 5 | 5 | 10 | 5 | 14 | 6 | 10 | 12 | 12 | 12 | 12 |  | 50 Ohms | TOP=L2:L3=L2/L4:L6=L5/L7:BOTTOM=L7 |
| SSD_PRSNT#2_R | OTHERS | BUS | 6 | 5 | 5 | 10 | 5 | 14 | 6 | 10 | 12 | 12 | 12 | 12 |  | 50 Ohms | TOP=L2:L3=L2/L4:L6=L5/L7:BOTTOM=L7 |
| SSD_PRSNT#2_R | OTHERS | BUS | 7 | 5 | 5 | 10 | 5 | 14 | 6 | 10 | 12 | 12 | 12 | 12 |  | 50 Ohms | TOP=L2:L3=L2/L4:L6=L5/L7:BOTTOM=L7 |
| SSD_PRSNT#2_R | OTHERS | BUS | 8 | 4.75 | 5 | 10 | 5 | 14 | 6 | 9.5 | 12 | 12 | 12 | 12 |  | 50 Ohms | TOP=L2:L3=L2/L4:L6=L5/L7:BOTTOM=L7 |
| SSD_PRSNT#3 | OTHERS | BUS | 1 | 4.75 | 5 | 10 | 5 | 14 | 6 | 9.5 | 12 | 12 | 12 | 12 |  | 50 Ohms | TOP=L2:L3=L2/L4:L6=L5/L7:BOTTOM=L7 |
| SSD_PRSNT#3 | OTHERS | BUS | 2 | 5 | 5 | 10 | 5 | 14 | 6 | 10 | 12 | 12 | 12 | 12 |  | 50 Ohms | TOP=L2:L3=L2/L4:L6=L5/L7:BOTTOM=L7 |
| SSD_PRSNT#3 | OTHERS | BUS | 3 | 5 | 5 | 10 | 5 | 14 | 6 | 10 | 12 | 12 | 12 | 12 |  | 50 Ohms | TOP=L2:L3=L2/L4:L6=L5/L7:BOTTOM=L7 |
| SSD_PRSNT#3 | OTHERS | BUS | 4 | 5 | 5 | 10 | 5 | 14 | 6 | 10 | 12 | 12 | 12 | 12 |  | 50 Ohms | TOP=L2:L3=L2/L4:L6=L5/L7:BOTTOM=L7 |
| SSD_PRSNT#3 | OTHERS | BUS | 5 | 5 | 5 | 10 | 5 | 14 | 6 | 10 | 12 | 12 | 12 | 12 |  | 50 Ohms | TOP=L2:L3=L2/L4:L6=L5/L7:BOTTOM=L7 |
| SSD_PRSNT#3 | OTHERS | BUS | 6 | 5 | 5 | 10 | 5 | 14 | 6 | 10 | 12 | 12 | 12 | 12 |  | 50 Ohms | TOP=L2:L3=L2/L4:L6=L5/L7:BOTTOM=L7 |
| SSD_PRSNT#3 | OTHERS | BUS | 7 | 5 | 5 | 10 | 5 | 14 | 6 | 10 | 12 | 12 | 12 | 12 |  | 50 Ohms | TOP=L2:L3=L2/L4:L6=L5/L7:BOTTOM=L7 |
| SSD_PRSNT#3 | OTHERS | BUS | 8 | 4.75 | 5 | 10 | 5 | 14 | 6 | 9.5 | 12 | 12 | 12 | 12 |  | 50 Ohms | TOP=L2:L3=L2/L4:L6=L5/L7:BOTTOM=L7 |
| SSD_PRSNT#3_R | OTHERS | BUS | 1 | 4.75 | 5 | 10 | 5 | 14 | 6 | 9.5 | 12 | 12 | 12 | 12 |  | 50 Ohms | TOP=L2:L3=L2/L4:L6=L5/L7:BOTTOM=L7 |
| SSD_PRSNT#3_R | OTHERS | BUS | 2 | 5 | 5 | 10 | 5 | 14 | 6 | 10 | 12 | 12 | 12 | 12 |  | 50 Ohms | TOP=L2:L3=L2/L4:L6=L5/L7:BOTTOM=L7 |
| SSD_PRSNT#3_R | OTHERS | BUS | 3 | 5 | 5 | 10 | 5 | 14 | 6 | 10 | 12 | 12 | 12 | 12 |  | 50 Ohms | TOP=L2:L3=L2/L4:L6=L5/L7:BOTTOM=L7 |
| SSD_PRSNT#3_R | OTHERS | BUS | 4 | 5 | 5 | 10 | 5 | 14 | 6 | 10 | 12 | 12 | 12 | 12 |  | 50 Ohms | TOP=L2:L3=L2/L4:L6=L5/L7:BOTTOM=L7 |
| SSD_PRSNT#3_R | OTHERS | BUS | 5 | 5 | 5 | 10 | 5 | 14 | 6 | 10 | 12 | 12 | 12 | 12 |  | 50 Ohms | TOP=L2:L3=L2/L4:L6=L5/L7:BOTTOM=L7 |
| SSD_PRSNT#3_R | OTHERS | BUS | 6 | 5 | 5 | 10 | 5 | 14 | 6 | 10 | 12 | 12 | 12 | 12 |  | 50 Ohms | TOP=L2:L3=L2/L4:L6=L5/L7:BOTTOM=L7 |
| SSD_PRSNT#3_R | OTHERS | BUS | 7 | 5 | 5 | 10 | 5 | 14 | 6 | 10 | 12 | 12 | 12 | 12 |  | 50 Ohms | TOP=L2:L3=L2/L4:L6=L5/L7:BOTTOM=L7 |
| SSD_PRSNT#3_R | OTHERS | BUS | 8 | 4.75 | 5 | 10 | 5 | 14 | 6 | 9.5 | 12 | 12 | 12 | 12 |  | 50 Ohms | TOP=L2:L3=L2/L4:L6=L5/L7:BOTTOM=L7 |
| SSD_PRSNT#4 | OTHERS | BUS | 1 | 4.75 | 5 | 10 | 5 | 14 | 6 | 9.5 | 12 | 12 | 12 | 12 |  | 50 Ohms | TOP=L2:L3=L2/L4:L6=L5/L7:BOTTOM=L7 |
| SSD_PRSNT#4 | OTHERS | BUS | 2 | 5 | 5 | 10 | 5 | 14 | 6 | 10 | 12 | 12 | 12 | 12 |  | 50 Ohms | TOP=L2:L3=L2/L4:L6=L5/L7:BOTTOM=L7 |
| SSD_PRSNT#4 | OTHERS | BUS | 3 | 5 | 5 | 10 | 5 | 14 | 6 | 10 | 12 | 12 | 12 | 12 |  | 50 Ohms | TOP=L2:L3=L2/L4:L6=L5/L7:BOTTOM=L7 |
| SSD_PRSNT#4 | OTHERS | BUS | 4 | 5 | 5 | 10 | 5 | 14 | 6 | 10 | 12 | 12 | 12 | 12 |  | 50 Ohms | TOP=L2:L3=L2/L4:L6=L5/L7:BOTTOM=L7 |
| SSD_PRSNT#4 | OTHERS | BUS | 5 | 5 | 5 | 10 | 5 | 14 | 6 | 10 | 12 | 12 | 12 | 12 |  | 50 Ohms | TOP=L2:L3=L2/L4:L6=L5/L7:BOTTOM=L7 |
| SSD_PRSNT#4 | OTHERS | BUS | 6 | 5 | 5 | 10 | 5 | 14 | 6 | 10 | 12 | 12 | 12 | 12 |  | 50 Ohms | TOP=L2:L3=L2/L4:L6=L5/L7:BOTTOM=L7 |
| SSD_PRSNT#4 | OTHERS | BUS | 7 | 5 | 5 | 10 | 5 | 14 | 6 | 10 | 12 | 12 | 12 | 12 |  | 50 Ohms | TOP=L2:L3=L2/L4:L6=L5/L7:BOTTOM=L7 |
| SSD_PRSNT#4 | OTHERS | BUS | 8 | 4.75 | 5 | 10 | 5 | 14 | 6 | 9.5 | 12 | 12 | 12 | 12 |  | 50 Ohms | TOP=L2:L3=L2/L4:L6=L5/L7:BOTTOM=L7 |
| SSD_PRSNT#4_R | OTHERS | BUS | 1 | 4.75 | 5 | 10 | 5 | 14 | 6 | 9.5 | 12 | 12 | 12 | 12 |  | 50 Ohms | TOP=L2:L3=L2/L4:L6=L5/L7:BOTTOM=L7 |
| SSD_PRSNT#4_R | OTHERS | BUS | 2 | 5 | 5 | 10 | 5 | 14 | 6 | 10 | 12 | 12 | 12 | 12 |  | 50 Ohms | TOP=L2:L3=L2/L4:L6=L5/L7:BOTTOM=L7 |
| SSD_PRSNT#4_R | OTHERS | BUS | 3 | 5 | 5 | 10 | 5 | 14 | 6 | 10 | 12 | 12 | 12 | 12 |  | 50 Ohms | TOP=L2:L3=L2/L4:L6=L5/L7:BOTTOM=L7 |
| SSD_PRSNT#4_R | OTHERS | BUS | 4 | 5 | 5 | 10 | 5 | 14 | 6 | 10 | 12 | 12 | 12 | 12 |  | 50 Ohms | TOP=L2:L3=L2/L4:L6=L5/L7:BOTTOM=L7 |
| SSD_PRSNT#4_R | OTHERS | BUS | 5 | 5 | 5 | 10 | 5 | 14 | 6 | 10 | 12 | 12 | 12 | 12 |  | 50 Ohms | TOP=L2:L3=L2/L4:L6=L5/L7:BOTTOM=L7 |
| SSD_PRSNT#4_R | OTHERS | BUS | 6 | 5 | 5 | 10 | 5 | 14 | 6 | 10 | 12 | 12 | 12 | 12 |  | 50 Ohms | TOP=L2:L3=L2/L4:L6=L5/L7:BOTTOM=L7 |
| SSD_PRSNT#4_R | OTHERS | BUS | 7 | 5 | 5 | 10 | 5 | 14 | 6 | 10 | 12 | 12 | 12 | 12 |  | 50 Ohms | TOP=L2:L3=L2/L4:L6=L5/L7:BOTTOM=L7 |
| SSD_PRSNT#4_R | OTHERS | BUS | 8 | 4.75 | 5 | 10 | 5 | 14 | 6 | 9.5 | 12 | 12 | 12 | 12 |  | 50 Ohms | TOP=L2:L3=L2/L4:L6=L5/L7:BOTTOM=L7 |
| SSD_PRSNT#5 | OTHERS | BUS | 1 | 4.75 | 5 | 10 | 5 | 14 | 6 | 9.5 | 12 | 12 | 12 | 12 |  | 50 Ohms | TOP=L2:L3=L2/L4:L6=L5/L7:BOTTOM=L7 |
| SSD_PRSNT#5 | OTHERS | BUS | 2 | 5 | 5 | 10 | 5 | 14 | 6 | 10 | 12 | 12 | 12 | 12 |  | 50 Ohms | TOP=L2:L3=L2/L4:L6=L5/L7:BOTTOM=L7 |
| SSD_PRSNT#5 | OTHERS | BUS | 3 | 5 | 5 | 10 | 5 | 14 | 6 | 10 | 12 | 12 | 12 | 12 |  | 50 Ohms | TOP=L2:L3=L2/L4:L6=L5/L7:BOTTOM=L7 |
| SSD_PRSNT#5 | OTHERS | BUS | 4 | 5 | 5 | 10 | 5 | 14 | 6 | 10 | 12 | 12 | 12 | 12 |  | 50 Ohms | TOP=L2:L3=L2/L4:L6=L5/L7:BOTTOM=L7 |
| SSD_PRSNT#5 | OTHERS | BUS | 5 | 5 | 5 | 10 | 5 | 14 | 6 | 10 | 12 | 12 | 12 | 12 |  | 50 Ohms | TOP=L2:L3=L2/L4:L6=L5/L7:BOTTOM=L7 |
| SSD_PRSNT#5 | OTHERS | BUS | 6 | 5 | 5 | 10 | 5 | 14 | 6 | 10 | 12 | 12 | 12 | 12 |  | 50 Ohms | TOP=L2:L3=L2/L4:L6=L5/L7:BOTTOM=L7 |
| SSD_PRSNT#5 | OTHERS | BUS | 7 | 5 | 5 | 10 | 5 | 14 | 6 | 10 | 12 | 12 | 12 | 12 |  | 50 Ohms | TOP=L2:L3=L2/L4:L6=L5/L7:BOTTOM=L7 |
| SSD_PRSNT#5 | OTHERS | BUS | 8 | 4.75 | 5 | 10 | 5 | 14 | 6 | 9.5 | 12 | 12 | 12 | 12 |  | 50 Ohms | TOP=L2:L3=L2/L4:L6=L5/L7:BOTTOM=L7 |
| SSD_PRSNT#5_R | OTHERS | BUS | 1 | 4.75 | 5 | 10 | 5 | 14 | 6 | 9.5 | 12 | 12 | 12 | 12 |  | 50 Ohms | TOP=L2:L3=L2/L4:L6=L5/L7:BOTTOM=L7 |
| SSD_PRSNT#5_R | OTHERS | BUS | 2 | 5 | 5 | 10 | 5 | 14 | 6 | 10 | 12 | 12 | 12 | 12 |  | 50 Ohms | TOP=L2:L3=L2/L4:L6=L5/L7:BOTTOM=L7 |
| SSD_PRSNT#5_R | OTHERS | BUS | 3 | 5 | 5 | 10 | 5 | 14 | 6 | 10 | 12 | 12 | 12 | 12 |  | 50 Ohms | TOP=L2:L3=L2/L4:L6=L5/L7:BOTTOM=L7 |
| SSD_PRSNT#5_R | OTHERS | BUS | 4 | 5 | 5 | 10 | 5 | 14 | 6 | 10 | 12 | 12 | 12 | 12 |  | 50 Ohms | TOP=L2:L3=L2/L4:L6=L5/L7:BOTTOM=L7 |
| SSD_PRSNT#5_R | OTHERS | BUS | 5 | 5 | 5 | 10 | 5 | 14 | 6 | 10 | 12 | 12 | 12 | 12 |  | 50 Ohms | TOP=L2:L3=L2/L4:L6=L5/L7:BOTTOM=L7 |
| SSD_PRSNT#5_R | OTHERS | BUS | 6 | 5 | 5 | 10 | 5 | 14 | 6 | 10 | 12 | 12 | 12 | 12 |  | 50 Ohms | TOP=L2:L3=L2/L4:L6=L5/L7:BOTTOM=L7 |
| SSD_PRSNT#5_R | OTHERS | BUS | 7 | 5 | 5 | 10 | 5 | 14 | 6 | 10 | 12 | 12 | 12 | 12 |  | 50 Ohms | TOP=L2:L3=L2/L4:L6=L5/L7:BOTTOM=L7 |
| SSD_PRSNT#5_R | OTHERS | BUS | 8 | 4.75 | 5 | 10 | 5 | 14 | 6 | 9.5 | 12 | 12 | 12 | 12 |  | 50 Ohms | TOP=L2:L3=L2/L4:L6=L5/L7:BOTTOM=L7 |
| SSD_PRSNT#6 | OTHERS | BUS | 1 | 4.75 | 5 | 10 | 5 | 14 | 6 | 9.5 | 12 | 12 | 12 | 12 |  | 50 Ohms | TOP=L2:L3=L2/L4:L6=L5/L7:BOTTOM=L7 |
| SSD_PRSNT#6 | OTHERS | BUS | 2 | 5 | 5 | 10 | 5 | 14 | 6 | 10 | 12 | 12 | 12 | 12 |  | 50 Ohms | TOP=L2:L3=L2/L4:L6=L5/L7:BOTTOM=L7 |
| SSD_PRSNT#6 | OTHERS | BUS | 3 | 5 | 5 | 10 | 5 | 14 | 6 | 10 | 12 | 12 | 12 | 12 |  | 50 Ohms | TOP=L2:L3=L2/L4:L6=L5/L7:BOTTOM=L7 |
| SSD_PRSNT#6 | OTHERS | BUS | 4 | 5 | 5 | 10 | 5 | 14 | 6 | 10 | 12 | 12 | 12 | 12 |  | 50 Ohms | TOP=L2:L3=L2/L4:L6=L5/L7:BOTTOM=L7 |
| SSD_PRSNT#6 | OTHERS | BUS | 5 | 5 | 5 | 10 | 5 | 14 | 6 | 10 | 12 | 12 | 12 | 12 |  | 50 Ohms | TOP=L2:L3=L2/L4:L6=L5/L7:BOTTOM=L7 |
| SSD_PRSNT#6 | OTHERS | BUS | 6 | 5 | 5 | 10 | 5 | 14 | 6 | 10 | 12 | 12 | 12 | 12 |  | 50 Ohms | TOP=L2:L3=L2/L4:L6=L5/L7:BOTTOM=L7 |
| SSD_PRSNT#6 | OTHERS | BUS | 7 | 5 | 5 | 10 | 5 | 14 | 6 | 10 | 12 | 12 | 12 | 12 |  | 50 Ohms | TOP=L2:L3=L2/L4:L6=L5/L7:BOTTOM=L7 |
| SSD_PRSNT#6 | OTHERS | BUS | 8 | 4.75 | 5 | 10 | 5 | 14 | 6 | 9.5 | 12 | 12 | 12 | 12 |  | 50 Ohms | TOP=L2:L3=L2/L4:L6=L5/L7:BOTTOM=L7 |
| SSD_PRSNT#6_R | OTHERS | BUS | 1 | 4.75 | 5 | 10 | 5 | 14 | 6 | 9.5 | 12 | 12 | 12 | 12 |  | 50 Ohms | TOP=L2:L3=L2/L4:L6=L5/L7:BOTTOM=L7 |
| SSD_PRSNT#6_R | OTHERS | BUS | 2 | 5 | 5 | 10 | 5 | 14 | 6 | 10 | 12 | 12 | 12 | 12 |  | 50 Ohms | TOP=L2:L3=L2/L4:L6=L5/L7:BOTTOM=L7 |
| SSD_PRSNT#6_R | OTHERS | BUS | 3 | 5 | 5 | 10 | 5 | 14 | 6 | 10 | 12 | 12 | 12 | 12 |  | 50 Ohms | TOP=L2:L3=L2/L4:L6=L5/L7:BOTTOM=L7 |
| SSD_PRSNT#6_R | OTHERS | BUS | 4 | 5 | 5 | 10 | 5 | 14 | 6 | 10 | 12 | 12 | 12 | 12 |  | 50 Ohms | TOP=L2:L3=L2/L4:L6=L5/L7:BOTTOM=L7 |
| SSD_PRSNT#6_R | OTHERS | BUS | 5 | 5 | 5 | 10 | 5 | 14 | 6 | 10 | 12 | 12 | 12 | 12 |  | 50 Ohms | TOP=L2:L3=L2/L4:L6=L5/L7:BOTTOM=L7 |
| SSD_PRSNT#6_R | OTHERS | BUS | 6 | 5 | 5 | 10 | 5 | 14 | 6 | 10 | 12 | 12 | 12 | 12 |  | 50 Ohms | TOP=L2:L3=L2/L4:L6=L5/L7:BOTTOM=L7 |
| SSD_PRSNT#6_R | OTHERS | BUS | 7 | 5 | 5 | 10 | 5 | 14 | 6 | 10 | 12 | 12 | 12 | 12 |  | 50 Ohms | TOP=L2:L3=L2/L4:L6=L5/L7:BOTTOM=L7 |
| SSD_PRSNT#6_R | OTHERS | BUS | 8 | 4.75 | 5 | 10 | 5 | 14 | 6 | 9.5 | 12 | 12 | 12 | 12 |  | 50 Ohms | TOP=L2:L3=L2/L4:L6=L5/L7:BOTTOM=L7 |
| SSD_PRSNT#7 | OTHERS | BUS | 1 | 4.75 | 5 | 10 | 5 | 14 | 6 | 9.5 | 12 | 12 | 12 | 12 |  | 50 Ohms | TOP=L2:L3=L2/L4:L6=L5/L7:BOTTOM=L7 |
| SSD_PRSNT#7 | OTHERS | BUS | 2 | 5 | 5 | 10 | 5 | 14 | 6 | 10 | 12 | 12 | 12 | 12 |  | 50 Ohms | TOP=L2:L3=L2/L4:L6=L5/L7:BOTTOM=L7 |
| SSD_PRSNT#7 | OTHERS | BUS | 3 | 5 | 5 | 10 | 5 | 14 | 6 | 10 | 12 | 12 | 12 | 12 |  | 50 Ohms | TOP=L2:L3=L2/L4:L6=L5/L7:BOTTOM=L7 |
| SSD_PRSNT#7 | OTHERS | BUS | 4 | 5 | 5 | 10 | 5 | 14 | 6 | 10 | 12 | 12 | 12 | 12 |  | 50 Ohms | TOP=L2:L3=L2/L4:L6=L5/L7:BOTTOM=L7 |
| SSD_PRSNT#7 | OTHERS | BUS | 5 | 5 | 5 | 10 | 5 | 14 | 6 | 10 | 12 | 12 | 12 | 12 |  | 50 Ohms | TOP=L2:L3=L2/L4:L6=L5/L7:BOTTOM=L7 |
| SSD_PRSNT#7 | OTHERS | BUS | 6 | 5 | 5 | 10 | 5 | 14 | 6 | 10 | 12 | 12 | 12 | 12 |  | 50 Ohms | TOP=L2:L3=L2/L4:L6=L5/L7:BOTTOM=L7 |
| SSD_PRSNT#7 | OTHERS | BUS | 7 | 5 | 5 | 10 | 5 | 14 | 6 | 10 | 12 | 12 | 12 | 12 |  | 50 Ohms | TOP=L2:L3=L2/L4:L6=L5/L7:BOTTOM=L7 |
| SSD_PRSNT#7 | OTHERS | BUS | 8 | 4.75 | 5 | 10 | 5 | 14 | 6 | 9.5 | 12 | 12 | 12 | 12 |  | 50 Ohms | TOP=L2:L3=L2/L4:L6=L5/L7:BOTTOM=L7 |
| SSD_PRSNT#7_R | OTHERS | BUS | 1 | 4.75 | 5 | 10 | 5 | 14 | 6 | 9.5 | 12 | 12 | 12 | 12 |  | 50 Ohms | TOP=L2:L3=L2/L4:L6=L5/L7:BOTTOM=L7 |
| SSD_PRSNT#7_R | OTHERS | BUS | 2 | 5 | 5 | 10 | 5 | 14 | 6 | 10 | 12 | 12 | 12 | 12 |  | 50 Ohms | TOP=L2:L3=L2/L4:L6=L5/L7:BOTTOM=L7 |
| SSD_PRSNT#7_R | OTHERS | BUS | 3 | 5 | 5 | 10 | 5 | 14 | 6 | 10 | 12 | 12 | 12 | 12 |  | 50 Ohms | TOP=L2:L3=L2/L4:L6=L5/L7:BOTTOM=L7 |
| SSD_PRSNT#7_R | OTHERS | BUS | 4 | 5 | 5 | 10 | 5 | 14 | 6 | 10 | 12 | 12 | 12 | 12 |  | 50 Ohms | TOP=L2:L3=L2/L4:L6=L5/L7:BOTTOM=L7 |
| SSD_PRSNT#7_R | OTHERS | BUS | 5 | 5 | 5 | 10 | 5 | 14 | 6 | 10 | 12 | 12 | 12 | 12 |  | 50 Ohms | TOP=L2:L3=L2/L4:L6=L5/L7:BOTTOM=L7 |
| SSD_PRSNT#7_R | OTHERS | BUS | 6 | 5 | 5 | 10 | 5 | 14 | 6 | 10 | 12 | 12 | 12 | 12 |  | 50 Ohms | TOP=L2:L3=L2/L4:L6=L5/L7:BOTTOM=L7 |
| SSD_PRSNT#7_R | OTHERS | BUS | 7 | 5 | 5 | 10 | 5 | 14 | 6 | 10 | 12 | 12 | 12 | 12 |  | 50 Ohms | TOP=L2:L3=L2/L4:L6=L5/L7:BOTTOM=L7 |
| SSD_PRSNT#7_R | OTHERS | BUS | 8 | 4.75 | 5 | 10 | 5 | 14 | 6 | 9.5 | 12 | 12 | 12 | 12 |  | 50 Ohms | TOP=L2:L3=L2/L4:L6=L5/L7:BOTTOM=L7 |
| SSD_PRSNT#8 | OTHERS | BUS | 1 | 4.75 | 5 | 10 | 5 | 14 | 6 | 9.5 | 12 | 12 | 12 | 12 |  | 50 Ohms | TOP=L2:L3=L2/L4:L6=L5/L7:BOTTOM=L7 |
| SSD_PRSNT#8 | OTHERS | BUS | 2 | 5 | 5 | 10 | 5 | 14 | 6 | 10 | 12 | 12 | 12 | 12 |  | 50 Ohms | TOP=L2:L3=L2/L4:L6=L5/L7:BOTTOM=L7 |
| SSD_PRSNT#8 | OTHERS | BUS | 3 | 5 | 5 | 10 | 5 | 14 | 6 | 10 | 12 | 12 | 12 | 12 |  | 50 Ohms | TOP=L2:L3=L2/L4:L6=L5/L7:BOTTOM=L7 |
| SSD_PRSNT#8 | OTHERS | BUS | 4 | 5 | 5 | 10 | 5 | 14 | 6 | 10 | 12 | 12 | 12 | 12 |  | 50 Ohms | TOP=L2:L3=L2/L4:L6=L5/L7:BOTTOM=L7 |
| SSD_PRSNT#8 | OTHERS | BUS | 5 | 5 | 5 | 10 | 5 | 14 | 6 | 10 | 12 | 12 | 12 | 12 |  | 50 Ohms | TOP=L2:L3=L2/L4:L6=L5/L7:BOTTOM=L7 |
| SSD_PRSNT#8 | OTHERS | BUS | 6 | 5 | 5 | 10 | 5 | 14 | 6 | 10 | 12 | 12 | 12 | 12 |  | 50 Ohms | TOP=L2:L3=L2/L4:L6=L5/L7:BOTTOM=L7 |
| SSD_PRSNT#8 | OTHERS | BUS | 7 | 5 | 5 | 10 | 5 | 14 | 6 | 10 | 12 | 12 | 12 | 12 |  | 50 Ohms | TOP=L2:L3=L2/L4:L6=L5/L7:BOTTOM=L7 |
| SSD_PRSNT#8 | OTHERS | BUS | 8 | 4.75 | 5 | 10 | 5 | 14 | 6 | 9.5 | 12 | 12 | 12 | 12 |  | 50 Ohms | TOP=L2:L3=L2/L4:L6=L5/L7:BOTTOM=L7 |
| SSD_PRSNT#8_R | OTHERS | BUS | 1 | 4.75 | 5 | 10 | 5 | 14 | 6 | 9.5 | 12 | 12 | 12 | 12 |  | 50 Ohms | TOP=L2:L3=L2/L4:L6=L5/L7:BOTTOM=L7 |
| SSD_PRSNT#8_R | OTHERS | BUS | 2 | 5 | 5 | 10 | 5 | 14 | 6 | 10 | 12 | 12 | 12 | 12 |  | 50 Ohms | TOP=L2:L3=L2/L4:L6=L5/L7:BOTTOM=L7 |
| SSD_PRSNT#8_R | OTHERS | BUS | 3 | 5 | 5 | 10 | 5 | 14 | 6 | 10 | 12 | 12 | 12 | 12 |  | 50 Ohms | TOP=L2:L3=L2/L4:L6=L5/L7:BOTTOM=L7 |
| SSD_PRSNT#8_R | OTHERS | BUS | 4 | 5 | 5 | 10 | 5 | 14 | 6 | 10 | 12 | 12 | 12 | 12 |  | 50 Ohms | TOP=L2:L3=L2/L4:L6=L5/L7:BOTTOM=L7 |
| SSD_PRSNT#8_R | OTHERS | BUS | 5 | 5 | 5 | 10 | 5 | 14 | 6 | 10 | 12 | 12 | 12 | 12 |  | 50 Ohms | TOP=L2:L3=L2/L4:L6=L5/L7:BOTTOM=L7 |
| SSD_PRSNT#8_R | OTHERS | BUS | 6 | 5 | 5 | 10 | 5 | 14 | 6 | 10 | 12 | 12 | 12 | 12 |  | 50 Ohms | TOP=L2:L3=L2/L4:L6=L5/L7:BOTTOM=L7 |
| SSD_PRSNT#8_R | OTHERS | BUS | 7 | 5 | 5 | 10 | 5 | 14 | 6 | 10 | 12 | 12 | 12 | 12 |  | 50 Ohms | TOP=L2:L3=L2/L4:L6=L5/L7:BOTTOM=L7 |
| SSD_PRSNT#8_R | OTHERS | BUS | 8 | 4.75 | 5 | 10 | 5 | 14 | 6 | 9.5 | 12 | 12 | 12 | 12 |  | 50 Ohms | TOP=L2:L3=L2/L4:L6=L5/L7:BOTTOM=L7 |
| SSD_PRSNT#9 | OTHERS | BUS | 1 | 4.75 | 5 | 10 | 5 | 14 | 6 | 9.5 | 12 | 12 | 12 | 12 |  | 50 Ohms | TOP=L2:L3=L2/L4:L6=L5/L7:BOTTOM=L7 |
| SSD_PRSNT#9 | OTHERS | BUS | 2 | 5 | 5 | 10 | 5 | 14 | 6 | 10 | 12 | 12 | 12 | 12 |  | 50 Ohms | TOP=L2:L3=L2/L4:L6=L5/L7:BOTTOM=L7 |
| SSD_PRSNT#9 | OTHERS | BUS | 3 | 5 | 5 | 10 | 5 | 14 | 6 | 10 | 12 | 12 | 12 | 12 |  | 50 Ohms | TOP=L2:L3=L2/L4:L6=L5/L7:BOTTOM=L7 |
| SSD_PRSNT#9 | OTHERS | BUS | 4 | 5 | 5 | 10 | 5 | 14 | 6 | 10 | 12 | 12 | 12 | 12 |  | 50 Ohms | TOP=L2:L3=L2/L4:L6=L5/L7:BOTTOM=L7 |
| SSD_PRSNT#9 | OTHERS | BUS | 5 | 5 | 5 | 10 | 5 | 14 | 6 | 10 | 12 | 12 | 12 | 12 |  | 50 Ohms | TOP=L2:L3=L2/L4:L6=L5/L7:BOTTOM=L7 |
| SSD_PRSNT#9 | OTHERS | BUS | 6 | 5 | 5 | 10 | 5 | 14 | 6 | 10 | 12 | 12 | 12 | 12 |  | 50 Ohms | TOP=L2:L3=L2/L4:L6=L5/L7:BOTTOM=L7 |
| SSD_PRSNT#9 | OTHERS | BUS | 7 | 5 | 5 | 10 | 5 | 14 | 6 | 10 | 12 | 12 | 12 | 12 |  | 50 Ohms | TOP=L2:L3=L2/L4:L6=L5/L7:BOTTOM=L7 |
| SSD_PRSNT#9 | OTHERS | BUS | 8 | 4.75 | 5 | 10 | 5 | 14 | 6 | 9.5 | 12 | 12 | 12 | 12 |  | 50 Ohms | TOP=L2:L3=L2/L4:L6=L5/L7:BOTTOM=L7 |
| SSD_PRSNT#9_R | OTHERS | BUS | 1 | 4.75 | 5 | 10 | 5 | 14 | 6 | 9.5 | 12 | 12 | 12 | 12 |  | 50 Ohms | TOP=L2:L3=L2/L4:L6=L5/L7:BOTTOM=L7 |
| SSD_PRSNT#9_R | OTHERS | BUS | 2 | 5 | 5 | 10 | 5 | 14 | 6 | 10 | 12 | 12 | 12 | 12 |  | 50 Ohms | TOP=L2:L3=L2/L4:L6=L5/L7:BOTTOM=L7 |
| SSD_PRSNT#9_R | OTHERS | BUS | 3 | 5 | 5 | 10 | 5 | 14 | 6 | 10 | 12 | 12 | 12 | 12 |  | 50 Ohms | TOP=L2:L3=L2/L4:L6=L5/L7:BOTTOM=L7 |
| SSD_PRSNT#9_R | OTHERS | BUS | 4 | 5 | 5 | 10 | 5 | 14 | 6 | 10 | 12 | 12 | 12 | 12 |  | 50 Ohms | TOP=L2:L3=L2/L4:L6=L5/L7:BOTTOM=L7 |
| SSD_PRSNT#9_R | OTHERS | BUS | 5 | 5 | 5 | 10 | 5 | 14 | 6 | 10 | 12 | 12 | 12 | 12 |  | 50 Ohms | TOP=L2:L3=L2/L4:L6=L5/L7:BOTTOM=L7 |
| SSD_PRSNT#9_R | OTHERS | BUS | 6 | 5 | 5 | 10 | 5 | 14 | 6 | 10 | 12 | 12 | 12 | 12 |  | 50 Ohms | TOP=L2:L3=L2/L4:L6=L5/L7:BOTTOM=L7 |
| SSD_PRSNT#9_R | OTHERS | BUS | 7 | 5 | 5 | 10 | 5 | 14 | 6 | 10 | 12 | 12 | 12 | 12 |  | 50 Ohms | TOP=L2:L3=L2/L4:L6=L5/L7:BOTTOM=L7 |
| SSD_PRSNT#9_R | OTHERS | BUS | 8 | 4.75 | 5 | 10 | 5 | 14 | 6 | 9.5 | 12 | 12 | 12 | 12 |  | 50 Ohms | TOP=L2:L3=L2/L4:L6=L5/L7:BOTTOM=L7 |
| SSD_PWREN0 | OTHERS | BUS | 1 | 4.75 | 5 | 10 | 5 | 14 | 6 | 9.5 | 12 | 12 | 12 | 12 |  | 50 Ohms | TOP=L2:L3=L2/L4:L6=L5/L7:BOTTOM=L7 |
| SSD_PWREN0 | OTHERS | BUS | 2 | 5 | 5 | 10 | 5 | 14 | 6 | 10 | 12 | 12 | 12 | 12 |  | 50 Ohms | TOP=L2:L3=L2/L4:L6=L5/L7:BOTTOM=L7 |
| SSD_PWREN0 | OTHERS | BUS | 3 | 5 | 5 | 10 | 5 | 14 | 6 | 10 | 12 | 12 | 12 | 12 |  | 50 Ohms | TOP=L2:L3=L2/L4:L6=L5/L7:BOTTOM=L7 |
| SSD_PWREN0 | OTHERS | BUS | 4 | 5 | 5 | 10 | 5 | 14 | 6 | 10 | 12 | 12 | 12 | 12 |  | 50 Ohms | TOP=L2:L3=L2/L4:L6=L5/L7:BOTTOM=L7 |
| SSD_PWREN0 | OTHERS | BUS | 5 | 5 | 5 | 10 | 5 | 14 | 6 | 10 | 12 | 12 | 12 | 12 |  | 50 Ohms | TOP=L2:L3=L2/L4:L6=L5/L7:BOTTOM=L7 |
| SSD_PWREN0 | OTHERS | BUS | 6 | 5 | 5 | 10 | 5 | 14 | 6 | 10 | 12 | 12 | 12 | 12 |  | 50 Ohms | TOP=L2:L3=L2/L4:L6=L5/L7:BOTTOM=L7 |
| SSD_PWREN0 | OTHERS | BUS | 7 | 5 | 5 | 10 | 5 | 14 | 6 | 10 | 12 | 12 | 12 | 12 |  | 50 Ohms | TOP=L2:L3=L2/L4:L6=L5/L7:BOTTOM=L7 |
| SSD_PWREN0 | OTHERS | BUS | 8 | 4.75 | 5 | 10 | 5 | 14 | 6 | 9.5 | 12 | 12 | 12 | 12 |  | 50 Ohms | TOP=L2:L3=L2/L4:L6=L5/L7:BOTTOM=L7 |
| SSD_PWREN0_R | OTHERS | BUS | 1 | 4.75 | 5 | 10 | 5 | 14 | 6 | 9.5 | 12 | 12 | 12 | 12 |  | 50 Ohms | TOP=L2:L3=L2/L4:L6=L5/L7:BOTTOM=L7 |
| SSD_PWREN0_R | OTHERS | BUS | 2 | 5 | 5 | 10 | 5 | 14 | 6 | 10 | 12 | 12 | 12 | 12 |  | 50 Ohms | TOP=L2:L3=L2/L4:L6=L5/L7:BOTTOM=L7 |
| SSD_PWREN0_R | OTHERS | BUS | 3 | 5 | 5 | 10 | 5 | 14 | 6 | 10 | 12 | 12 | 12 | 12 |  | 50 Ohms | TOP=L2:L3=L2/L4:L6=L5/L7:BOTTOM=L7 |
| SSD_PWREN0_R | OTHERS | BUS | 4 | 5 | 5 | 10 | 5 | 14 | 6 | 10 | 12 | 12 | 12 | 12 |  | 50 Ohms | TOP=L2:L3=L2/L4:L6=L5/L7:BOTTOM=L7 |
| SSD_PWREN0_R | OTHERS | BUS | 5 | 5 | 5 | 10 | 5 | 14 | 6 | 10 | 12 | 12 | 12 | 12 |  | 50 Ohms | TOP=L2:L3=L2/L4:L6=L5/L7:BOTTOM=L7 |
| SSD_PWREN0_R | OTHERS | BUS | 6 | 5 | 5 | 10 | 5 | 14 | 6 | 10 | 12 | 12 | 12 | 12 |  | 50 Ohms | TOP=L2:L3=L2/L4:L6=L5/L7:BOTTOM=L7 |
| SSD_PWREN0_R | OTHERS | BUS | 7 | 5 | 5 | 10 | 5 | 14 | 6 | 10 | 12 | 12 | 12 | 12 |  | 50 Ohms | TOP=L2:L3=L2/L4:L6=L5/L7:BOTTOM=L7 |
| SSD_PWREN0_R | OTHERS | BUS | 8 | 4.75 | 5 | 10 | 5 | 14 | 6 | 9.5 | 12 | 12 | 12 | 12 |  | 50 Ohms | TOP=L2:L3=L2/L4:L6=L5/L7:BOTTOM=L7 |
| SSD_PWREN1 | OTHERS | BUS | 1 | 4.75 | 5 | 10 | 5 | 14 | 6 | 9.5 | 12 | 12 | 12 | 12 |  | 50 Ohms | TOP=L2:L3=L2/L4:L6=L5/L7:BOTTOM=L7 |
| SSD_PWREN1 | OTHERS | BUS | 2 | 5 | 5 | 10 | 5 | 14 | 6 | 10 | 12 | 12 | 12 | 12 |  | 50 Ohms | TOP=L2:L3=L2/L4:L6=L5/L7:BOTTOM=L7 |
| SSD_PWREN1 | OTHERS | BUS | 3 | 5 | 5 | 10 | 5 | 14 | 6 | 10 | 12 | 12 | 12 | 12 |  | 50 Ohms | TOP=L2:L3=L2/L4:L6=L5/L7:BOTTOM=L7 |
| SSD_PWREN1 | OTHERS | BUS | 4 | 5 | 5 | 10 | 5 | 14 | 6 | 10 | 12 | 12 | 12 | 12 |  | 50 Ohms | TOP=L2:L3=L2/L4:L6=L5/L7:BOTTOM=L7 |
| SSD_PWREN1 | OTHERS | BUS | 5 | 5 | 5 | 10 | 5 | 14 | 6 | 10 | 12 | 12 | 12 | 12 |  | 50 Ohms | TOP=L2:L3=L2/L4:L6=L5/L7:BOTTOM=L7 |
| SSD_PWREN1 | OTHERS | BUS | 6 | 5 | 5 | 10 | 5 | 14 | 6 | 10 | 12 | 12 | 12 | 12 |  | 50 Ohms | TOP=L2:L3=L2/L4:L6=L5/L7:BOTTOM=L7 |
| SSD_PWREN1 | OTHERS | BUS | 7 | 5 | 5 | 10 | 5 | 14 | 6 | 10 | 12 | 12 | 12 | 12 |  | 50 Ohms | TOP=L2:L3=L2/L4:L6=L5/L7:BOTTOM=L7 |
| SSD_PWREN1 | OTHERS | BUS | 8 | 4.75 | 5 | 10 | 5 | 14 | 6 | 9.5 | 12 | 12 | 12 | 12 |  | 50 Ohms | TOP=L2:L3=L2/L4:L6=L5/L7:BOTTOM=L7 |
| SSD_PWREN1_R | OTHERS | BUS | 1 | 4.75 | 5 | 10 | 5 | 14 | 6 | 9.5 | 12 | 12 | 12 | 12 |  | 50 Ohms | TOP=L2:L3=L2/L4:L6=L5/L7:BOTTOM=L7 |
| SSD_PWREN1_R | OTHERS | BUS | 2 | 5 | 5 | 10 | 5 | 14 | 6 | 10 | 12 | 12 | 12 | 12 |  | 50 Ohms | TOP=L2:L3=L2/L4:L6=L5/L7:BOTTOM=L7 |
| SSD_PWREN1_R | OTHERS | BUS | 3 | 5 | 5 | 10 | 5 | 14 | 6 | 10 | 12 | 12 | 12 | 12 |  | 50 Ohms | TOP=L2:L3=L2/L4:L6=L5/L7:BOTTOM=L7 |
| SSD_PWREN1_R | OTHERS | BUS | 4 | 5 | 5 | 10 | 5 | 14 | 6 | 10 | 12 | 12 | 12 | 12 |  | 50 Ohms | TOP=L2:L3=L2/L4:L6=L5/L7:BOTTOM=L7 |
| SSD_PWREN1_R | OTHERS | BUS | 5 | 5 | 5 | 10 | 5 | 14 | 6 | 10 | 12 | 12 | 12 | 12 |  | 50 Ohms | TOP=L2:L3=L2/L4:L6=L5/L7:BOTTOM=L7 |
| SSD_PWREN1_R | OTHERS | BUS | 6 | 5 | 5 | 10 | 5 | 14 | 6 | 10 | 12 | 12 | 12 | 12 |  | 50 Ohms | TOP=L2:L3=L2/L4:L6=L5/L7:BOTTOM=L7 |
| SSD_PWREN1_R | OTHERS | BUS | 7 | 5 | 5 | 10 | 5 | 14 | 6 | 10 | 12 | 12 | 12 | 12 |  | 50 Ohms | TOP=L2:L3=L2/L4:L6=L5/L7:BOTTOM=L7 |
| SSD_PWREN1_R | OTHERS | BUS | 8 | 4.75 | 5 | 10 | 5 | 14 | 6 | 9.5 | 12 | 12 | 12 | 12 |  | 50 Ohms | TOP=L2:L3=L2/L4:L6=L5/L7:BOTTOM=L7 |
| SSD_PWREN10 | OTHERS | BUS | 1 | 4.75 | 5 | 10 | 5 | 14 | 6 | 9.5 | 12 | 12 | 12 | 12 |  | 50 Ohms | TOP=L2:L3=L2/L4:L6=L5/L7:BOTTOM=L7 |
| SSD_PWREN10 | OTHERS | BUS | 2 | 5 | 5 | 10 | 5 | 14 | 6 | 10 | 12 | 12 | 12 | 12 |  | 50 Ohms | TOP=L2:L3=L2/L4:L6=L5/L7:BOTTOM=L7 |
| SSD_PWREN10 | OTHERS | BUS | 3 | 5 | 5 | 10 | 5 | 14 | 6 | 10 | 12 | 12 | 12 | 12 |  | 50 Ohms | TOP=L2:L3=L2/L4:L6=L5/L7:BOTTOM=L7 |
| SSD_PWREN10 | OTHERS | BUS | 4 | 5 | 5 | 10 | 5 | 14 | 6 | 10 | 12 | 12 | 12 | 12 |  | 50 Ohms | TOP=L2:L3=L2/L4:L6=L5/L7:BOTTOM=L7 |
| SSD_PWREN10 | OTHERS | BUS | 5 | 5 | 5 | 10 | 5 | 14 | 6 | 10 | 12 | 12 | 12 | 12 |  | 50 Ohms | TOP=L2:L3=L2/L4:L6=L5/L7:BOTTOM=L7 |
| SSD_PWREN10 | OTHERS | BUS | 6 | 5 | 5 | 10 | 5 | 14 | 6 | 10 | 12 | 12 | 12 | 12 |  | 50 Ohms | TOP=L2:L3=L2/L4:L6=L5/L7:BOTTOM=L7 |
| SSD_PWREN10 | OTHERS | BUS | 7 | 5 | 5 | 10 | 5 | 14 | 6 | 10 | 12 | 12 | 12 | 12 |  | 50 Ohms | TOP=L2:L3=L2/L4:L6=L5/L7:BOTTOM=L7 |
| SSD_PWREN10 | OTHERS | BUS | 8 | 4.75 | 5 | 10 | 5 | 14 | 6 | 9.5 | 12 | 12 | 12 | 12 |  | 50 Ohms | TOP=L2:L3=L2/L4:L6=L5/L7:BOTTOM=L7 |
| SSD_PWREN10_R | OTHERS | BUS | 1 | 4.75 | 5 | 10 | 5 | 14 | 6 | 9.5 | 12 | 12 | 12 | 12 |  | 50 Ohms | TOP=L2:L3=L2/L4:L6=L5/L7:BOTTOM=L7 |
| SSD_PWREN10_R | OTHERS | BUS | 2 | 5 | 5 | 10 | 5 | 14 | 6 | 10 | 12 | 12 | 12 | 12 |  | 50 Ohms | TOP=L2:L3=L2/L4:L6=L5/L7:BOTTOM=L7 |
| SSD_PWREN10_R | OTHERS | BUS | 3 | 5 | 5 | 10 | 5 | 14 | 6 | 10 | 12 | 12 | 12 | 12 |  | 50 Ohms | TOP=L2:L3=L2/L4:L6=L5/L7:BOTTOM=L7 |
| SSD_PWREN10_R | OTHERS | BUS | 4 | 5 | 5 | 10 | 5 | 14 | 6 | 10 | 12 | 12 | 12 | 12 |  | 50 Ohms | TOP=L2:L3=L2/L4:L6=L5/L7:BOTTOM=L7 |
| SSD_PWREN10_R | OTHERS | BUS | 5 | 5 | 5 | 10 | 5 | 14 | 6 | 10 | 12 | 12 | 12 | 12 |  | 50 Ohms | TOP=L2:L3=L2/L4:L6=L5/L7:BOTTOM=L7 |
| SSD_PWREN10_R | OTHERS | BUS | 6 | 5 | 5 | 10 | 5 | 14 | 6 | 10 | 12 | 12 | 12 | 12 |  | 50 Ohms | TOP=L2:L3=L2/L4:L6=L5/L7:BOTTOM=L7 |
| SSD_PWREN10_R | OTHERS | BUS | 7 | 5 | 5 | 10 | 5 | 14 | 6 | 10 | 12 | 12 | 12 | 12 |  | 50 Ohms | TOP=L2:L3=L2/L4:L6=L5/L7:BOTTOM=L7 |
| SSD_PWREN10_R | OTHERS | BUS | 8 | 4.75 | 5 | 10 | 5 | 14 | 6 | 9.5 | 12 | 12 | 12 | 12 |  | 50 Ohms | TOP=L2:L3=L2/L4:L6=L5/L7:BOTTOM=L7 |
| SSD_PWREN11 | OTHERS | BUS | 1 | 4.75 | 5 | 10 | 5 | 14 | 6 | 9.5 | 12 | 12 | 12 | 12 |  | 50 Ohms | TOP=L2:L3=L2/L4:L6=L5/L7:BOTTOM=L7 |
| SSD_PWREN11 | OTHERS | BUS | 2 | 5 | 5 | 10 | 5 | 14 | 6 | 10 | 12 | 12 | 12 | 12 |  | 50 Ohms | TOP=L2:L3=L2/L4:L6=L5/L7:BOTTOM=L7 |
| SSD_PWREN11 | OTHERS | BUS | 3 | 5 | 5 | 10 | 5 | 14 | 6 | 10 | 12 | 12 | 12 | 12 |  | 50 Ohms | TOP=L2:L3=L2/L4:L6=L5/L7:BOTTOM=L7 |
| SSD_PWREN11 | OTHERS | BUS | 4 | 5 | 5 | 10 | 5 | 14 | 6 | 10 | 12 | 12 | 12 | 12 |  | 50 Ohms | TOP=L2:L3=L2/L4:L6=L5/L7:BOTTOM=L7 |
| SSD_PWREN11 | OTHERS | BUS | 5 | 5 | 5 | 10 | 5 | 14 | 6 | 10 | 12 | 12 | 12 | 12 |  | 50 Ohms | TOP=L2:L3=L2/L4:L6=L5/L7:BOTTOM=L7 |
| SSD_PWREN11 | OTHERS | BUS | 6 | 5 | 5 | 10 | 5 | 14 | 6 | 10 | 12 | 12 | 12 | 12 |  | 50 Ohms | TOP=L2:L3=L2/L4:L6=L5/L7:BOTTOM=L7 |
| SSD_PWREN11 | OTHERS | BUS | 7 | 5 | 5 | 10 | 5 | 14 | 6 | 10 | 12 | 12 | 12 | 12 |  | 50 Ohms | TOP=L2:L3=L2/L4:L6=L5/L7:BOTTOM=L7 |
| SSD_PWREN11 | OTHERS | BUS | 8 | 4.75 | 5 | 10 | 5 | 14 | 6 | 9.5 | 12 | 12 | 12 | 12 |  | 50 Ohms | TOP=L2:L3=L2/L4:L6=L5/L7:BOTTOM=L7 |
| SSD_PWREN11_R | OTHERS | BUS | 1 | 4.75 | 5 | 10 | 5 | 14 | 6 | 9.5 | 12 | 12 | 12 | 12 |  | 50 Ohms | TOP=L2:L3=L2/L4:L6=L5/L7:BOTTOM=L7 |
| SSD_PWREN11_R | OTHERS | BUS | 2 | 5 | 5 | 10 | 5 | 14 | 6 | 10 | 12 | 12 | 12 | 12 |  | 50 Ohms | TOP=L2:L3=L2/L4:L6=L5/L7:BOTTOM=L7 |
| SSD_PWREN11_R | OTHERS | BUS | 3 | 5 | 5 | 10 | 5 | 14 | 6 | 10 | 12 | 12 | 12 | 12 |  | 50 Ohms | TOP=L2:L3=L2/L4:L6=L5/L7:BOTTOM=L7 |
| SSD_PWREN11_R | OTHERS | BUS | 4 | 5 | 5 | 10 | 5 | 14 | 6 | 10 | 12 | 12 | 12 | 12 |  | 50 Ohms | TOP=L2:L3=L2/L4:L6=L5/L7:BOTTOM=L7 |
| SSD_PWREN11_R | OTHERS | BUS | 5 | 5 | 5 | 10 | 5 | 14 | 6 | 10 | 12 | 12 | 12 | 12 |  | 50 Ohms | TOP=L2:L3=L2/L4:L6=L5/L7:BOTTOM=L7 |
| SSD_PWREN11_R | OTHERS | BUS | 6 | 5 | 5 | 10 | 5 | 14 | 6 | 10 | 12 | 12 | 12 | 12 |  | 50 Ohms | TOP=L2:L3=L2/L4:L6=L5/L7:BOTTOM=L7 |
| SSD_PWREN11_R | OTHERS | BUS | 7 | 5 | 5 | 10 | 5 | 14 | 6 | 10 | 12 | 12 | 12 | 12 |  | 50 Ohms | TOP=L2:L3=L2/L4:L6=L5/L7:BOTTOM=L7 |
| SSD_PWREN11_R | OTHERS | BUS | 8 | 4.75 | 5 | 10 | 5 | 14 | 6 | 9.5 | 12 | 12 | 12 | 12 |  | 50 Ohms | TOP=L2:L3=L2/L4:L6=L5/L7:BOTTOM=L7 |
| SSD_PWREN12 | OTHERS | BUS | 1 | 4.75 | 5 | 10 | 5 | 14 | 6 | 9.5 | 12 | 12 | 12 | 12 |  | 50 Ohms | TOP=L2:L3=L2/L4:L6=L5/L7:BOTTOM=L7 |
| SSD_PWREN12 | OTHERS | BUS | 2 | 5 | 5 | 10 | 5 | 14 | 6 | 10 | 12 | 12 | 12 | 12 |  | 50 Ohms | TOP=L2:L3=L2/L4:L6=L5/L7:BOTTOM=L7 |
| SSD_PWREN12 | OTHERS | BUS | 3 | 5 | 5 | 10 | 5 | 14 | 6 | 10 | 12 | 12 | 12 | 12 |  | 50 Ohms | TOP=L2:L3=L2/L4:L6=L5/L7:BOTTOM=L7 |
| SSD_PWREN12 | OTHERS | BUS | 4 | 5 | 5 | 10 | 5 | 14 | 6 | 10 | 12 | 12 | 12 | 12 |  | 50 Ohms | TOP=L2:L3=L2/L4:L6=L5/L7:BOTTOM=L7 |
| SSD_PWREN12 | OTHERS | BUS | 5 | 5 | 5 | 10 | 5 | 14 | 6 | 10 | 12 | 12 | 12 | 12 |  | 50 Ohms | TOP=L2:L3=L2/L4:L6=L5/L7:BOTTOM=L7 |
| SSD_PWREN12 | OTHERS | BUS | 6 | 5 | 5 | 10 | 5 | 14 | 6 | 10 | 12 | 12 | 12 | 12 |  | 50 Ohms | TOP=L2:L3=L2/L4:L6=L5/L7:BOTTOM=L7 |
| SSD_PWREN12 | OTHERS | BUS | 7 | 5 | 5 | 10 | 5 | 14 | 6 | 10 | 12 | 12 | 12 | 12 |  | 50 Ohms | TOP=L2:L3=L2/L4:L6=L5/L7:BOTTOM=L7 |
| SSD_PWREN12 | OTHERS | BUS | 8 | 4.75 | 5 | 10 | 5 | 14 | 6 | 9.5 | 12 | 12 | 12 | 12 |  | 50 Ohms | TOP=L2:L3=L2/L4:L6=L5/L7:BOTTOM=L7 |
| SSD_PWREN12_R | OTHERS | BUS | 1 | 4.75 | 5 | 10 | 5 | 14 | 6 | 9.5 | 12 | 12 | 12 | 12 |  | 50 Ohms | TOP=L2:L3=L2/L4:L6=L5/L7:BOTTOM=L7 |
| SSD_PWREN12_R | OTHERS | BUS | 2 | 5 | 5 | 10 | 5 | 14 | 6 | 10 | 12 | 12 | 12 | 12 |  | 50 Ohms | TOP=L2:L3=L2/L4:L6=L5/L7:BOTTOM=L7 |
| SSD_PWREN12_R | OTHERS | BUS | 3 | 5 | 5 | 10 | 5 | 14 | 6 | 10 | 12 | 12 | 12 | 12 |  | 50 Ohms | TOP=L2:L3=L2/L4:L6=L5/L7:BOTTOM=L7 |
| SSD_PWREN12_R | OTHERS | BUS | 4 | 5 | 5 | 10 | 5 | 14 | 6 | 10 | 12 | 12 | 12 | 12 |  | 50 Ohms | TOP=L2:L3=L2/L4:L6=L5/L7:BOTTOM=L7 |
| SSD_PWREN12_R | OTHERS | BUS | 5 | 5 | 5 | 10 | 5 | 14 | 6 | 10 | 12 | 12 | 12 | 12 |  | 50 Ohms | TOP=L2:L3=L2/L4:L6=L5/L7:BOTTOM=L7 |
| SSD_PWREN12_R | OTHERS | BUS | 6 | 5 | 5 | 10 | 5 | 14 | 6 | 10 | 12 | 12 | 12 | 12 |  | 50 Ohms | TOP=L2:L3=L2/L4:L6=L5/L7:BOTTOM=L7 |
| SSD_PWREN12_R | OTHERS | BUS | 7 | 5 | 5 | 10 | 5 | 14 | 6 | 10 | 12 | 12 | 12 | 12 |  | 50 Ohms | TOP=L2:L3=L2/L4:L6=L5/L7:BOTTOM=L7 |
| SSD_PWREN12_R | OTHERS | BUS | 8 | 4.75 | 5 | 10 | 5 | 14 | 6 | 9.5 | 12 | 12 | 12 | 12 |  | 50 Ohms | TOP=L2:L3=L2/L4:L6=L5/L7:BOTTOM=L7 |
| SSD_PWREN13 | OTHERS | BUS | 1 | 4.75 | 5 | 10 | 5 | 14 | 6 | 9.5 | 12 | 12 | 12 | 12 |  | 50 Ohms | TOP=L2:L3=L2/L4:L6=L5/L7:BOTTOM=L7 |
| SSD_PWREN13 | OTHERS | BUS | 2 | 5 | 5 | 10 | 5 | 14 | 6 | 10 | 12 | 12 | 12 | 12 |  | 50 Ohms | TOP=L2:L3=L2/L4:L6=L5/L7:BOTTOM=L7 |
| SSD_PWREN13 | OTHERS | BUS | 3 | 5 | 5 | 10 | 5 | 14 | 6 | 10 | 12 | 12 | 12 | 12 |  | 50 Ohms | TOP=L2:L3=L2/L4:L6=L5/L7:BOTTOM=L7 |
| SSD_PWREN13 | OTHERS | BUS | 4 | 5 | 5 | 10 | 5 | 14 | 6 | 10 | 12 | 12 | 12 | 12 |  | 50 Ohms | TOP=L2:L3=L2/L4:L6=L5/L7:BOTTOM=L7 |
| SSD_PWREN13 | OTHERS | BUS | 5 | 5 | 5 | 10 | 5 | 14 | 6 | 10 | 12 | 12 | 12 | 12 |  | 50 Ohms | TOP=L2:L3=L2/L4:L6=L5/L7:BOTTOM=L7 |
| SSD_PWREN13 | OTHERS | BUS | 6 | 5 | 5 | 10 | 5 | 14 | 6 | 10 | 12 | 12 | 12 | 12 |  | 50 Ohms | TOP=L2:L3=L2/L4:L6=L5/L7:BOTTOM=L7 |
| SSD_PWREN13 | OTHERS | BUS | 7 | 5 | 5 | 10 | 5 | 14 | 6 | 10 | 12 | 12 | 12 | 12 |  | 50 Ohms | TOP=L2:L3=L2/L4:L6=L5/L7:BOTTOM=L7 |
| SSD_PWREN13 | OTHERS | BUS | 8 | 4.75 | 5 | 10 | 5 | 14 | 6 | 9.5 | 12 | 12 | 12 | 12 |  | 50 Ohms | TOP=L2:L3=L2/L4:L6=L5/L7:BOTTOM=L7 |
| SSD_PWREN13_R | OTHERS | BUS | 1 | 4.75 | 5 | 10 | 5 | 14 | 6 | 9.5 | 12 | 12 | 12 | 12 |  | 50 Ohms | TOP=L2:L3=L2/L4:L6=L5/L7:BOTTOM=L7 |
| SSD_PWREN13_R | OTHERS | BUS | 2 | 5 | 5 | 10 | 5 | 14 | 6 | 10 | 12 | 12 | 12 | 12 |  | 50 Ohms | TOP=L2:L3=L2/L4:L6=L5/L7:BOTTOM=L7 |
| SSD_PWREN13_R | OTHERS | BUS | 3 | 5 | 5 | 10 | 5 | 14 | 6 | 10 | 12 | 12 | 12 | 12 |  | 50 Ohms | TOP=L2:L3=L2/L4:L6=L5/L7:BOTTOM=L7 |
| SSD_PWREN13_R | OTHERS | BUS | 4 | 5 | 5 | 10 | 5 | 14 | 6 | 10 | 12 | 12 | 12 | 12 |  | 50 Ohms | TOP=L2:L3=L2/L4:L6=L5/L7:BOTTOM=L7 |
| SSD_PWREN13_R | OTHERS | BUS | 5 | 5 | 5 | 10 | 5 | 14 | 6 | 10 | 12 | 12 | 12 | 12 |  | 50 Ohms | TOP=L2:L3=L2/L4:L6=L5/L7:BOTTOM=L7 |
| SSD_PWREN13_R | OTHERS | BUS | 6 | 5 | 5 | 10 | 5 | 14 | 6 | 10 | 12 | 12 | 12 | 12 |  | 50 Ohms | TOP=L2:L3=L2/L4:L6=L5/L7:BOTTOM=L7 |
| SSD_PWREN13_R | OTHERS | BUS | 7 | 5 | 5 | 10 | 5 | 14 | 6 | 10 | 12 | 12 | 12 | 12 |  | 50 Ohms | TOP=L2:L3=L2/L4:L6=L5/L7:BOTTOM=L7 |
| SSD_PWREN13_R | OTHERS | BUS | 8 | 4.75 | 5 | 10 | 5 | 14 | 6 | 9.5 | 12 | 12 | 12 | 12 |  | 50 Ohms | TOP=L2:L3=L2/L4:L6=L5/L7:BOTTOM=L7 |
| SSD_PWREN14 | OTHERS | BUS | 1 | 4.75 | 5 | 10 | 5 | 14 | 6 | 9.5 | 12 | 12 | 12 | 12 |  | 50 Ohms | TOP=L2:L3=L2/L4:L6=L5/L7:BOTTOM=L7 |
| SSD_PWREN14 | OTHERS | BUS | 2 | 5 | 5 | 10 | 5 | 14 | 6 | 10 | 12 | 12 | 12 | 12 |  | 50 Ohms | TOP=L2:L3=L2/L4:L6=L5/L7:BOTTOM=L7 |
| SSD_PWREN14 | OTHERS | BUS | 3 | 5 | 5 | 10 | 5 | 14 | 6 | 10 | 12 | 12 | 12 | 12 |  | 50 Ohms | TOP=L2:L3=L2/L4:L6=L5/L7:BOTTOM=L7 |
| SSD_PWREN14 | OTHERS | BUS | 4 | 5 | 5 | 10 | 5 | 14 | 6 | 10 | 12 | 12 | 12 | 12 |  | 50 Ohms | TOP=L2:L3=L2/L4:L6=L5/L7:BOTTOM=L7 |
| SSD_PWREN14 | OTHERS | BUS | 5 | 5 | 5 | 10 | 5 | 14 | 6 | 10 | 12 | 12 | 12 | 12 |  | 50 Ohms | TOP=L2:L3=L2/L4:L6=L5/L7:BOTTOM=L7 |
| SSD_PWREN14 | OTHERS | BUS | 6 | 5 | 5 | 10 | 5 | 14 | 6 | 10 | 12 | 12 | 12 | 12 |  | 50 Ohms | TOP=L2:L3=L2/L4:L6=L5/L7:BOTTOM=L7 |
| SSD_PWREN14 | OTHERS | BUS | 7 | 5 | 5 | 10 | 5 | 14 | 6 | 10 | 12 | 12 | 12 | 12 |  | 50 Ohms | TOP=L2:L3=L2/L4:L6=L5/L7:BOTTOM=L7 |
| SSD_PWREN14 | OTHERS | BUS | 8 | 4.75 | 5 | 10 | 5 | 14 | 6 | 9.5 | 12 | 12 | 12 | 12 |  | 50 Ohms | TOP=L2:L3=L2/L4:L6=L5/L7:BOTTOM=L7 |
| SSD_PWREN14_R | OTHERS | BUS | 1 | 4.75 | 5 | 10 | 5 | 14 | 6 | 9.5 | 12 | 12 | 12 | 12 |  | 50 Ohms | TOP=L2:L3=L2/L4:L6=L5/L7:BOTTOM=L7 |
| SSD_PWREN14_R | OTHERS | BUS | 2 | 5 | 5 | 10 | 5 | 14 | 6 | 10 | 12 | 12 | 12 | 12 |  | 50 Ohms | TOP=L2:L3=L2/L4:L6=L5/L7:BOTTOM=L7 |
| SSD_PWREN14_R | OTHERS | BUS | 3 | 5 | 5 | 10 | 5 | 14 | 6 | 10 | 12 | 12 | 12 | 12 |  | 50 Ohms | TOP=L2:L3=L2/L4:L6=L5/L7:BOTTOM=L7 |
| SSD_PWREN14_R | OTHERS | BUS | 4 | 5 | 5 | 10 | 5 | 14 | 6 | 10 | 12 | 12 | 12 | 12 |  | 50 Ohms | TOP=L2:L3=L2/L4:L6=L5/L7:BOTTOM=L7 |
| SSD_PWREN14_R | OTHERS | BUS | 5 | 5 | 5 | 10 | 5 | 14 | 6 | 10 | 12 | 12 | 12 | 12 |  | 50 Ohms | TOP=L2:L3=L2/L4:L6=L5/L7:BOTTOM=L7 |
| SSD_PWREN14_R | OTHERS | BUS | 6 | 5 | 5 | 10 | 5 | 14 | 6 | 10 | 12 | 12 | 12 | 12 |  | 50 Ohms | TOP=L2:L3=L2/L4:L6=L5/L7:BOTTOM=L7 |
| SSD_PWREN14_R | OTHERS | BUS | 7 | 5 | 5 | 10 | 5 | 14 | 6 | 10 | 12 | 12 | 12 | 12 |  | 50 Ohms | TOP=L2:L3=L2/L4:L6=L5/L7:BOTTOM=L7 |
| SSD_PWREN14_R | OTHERS | BUS | 8 | 4.75 | 5 | 10 | 5 | 14 | 6 | 9.5 | 12 | 12 | 12 | 12 |  | 50 Ohms | TOP=L2:L3=L2/L4:L6=L5/L7:BOTTOM=L7 |
| SSD_PWREN2 | OTHERS | BUS | 1 | 4.75 | 5 | 10 | 5 | 14 | 6 | 9.5 | 12 | 12 | 12 | 12 |  | 50 Ohms | TOP=L2:L3=L2/L4:L6=L5/L7:BOTTOM=L7 |
| SSD_PWREN2 | OTHERS | BUS | 2 | 5 | 5 | 10 | 5 | 14 | 6 | 10 | 12 | 12 | 12 | 12 |  | 50 Ohms | TOP=L2:L3=L2/L4:L6=L5/L7:BOTTOM=L7 |
| SSD_PWREN2 | OTHERS | BUS | 3 | 5 | 5 | 10 | 5 | 14 | 6 | 10 | 12 | 12 | 12 | 12 |  | 50 Ohms | TOP=L2:L3=L2/L4:L6=L5/L7:BOTTOM=L7 |
| SSD_PWREN2 | OTHERS | BUS | 4 | 5 | 5 | 10 | 5 | 14 | 6 | 10 | 12 | 12 | 12 | 12 |  | 50 Ohms | TOP=L2:L3=L2/L4:L6=L5/L7:BOTTOM=L7 |
| SSD_PWREN2 | OTHERS | BUS | 5 | 5 | 5 | 10 | 5 | 14 | 6 | 10 | 12 | 12 | 12 | 12 |  | 50 Ohms | TOP=L2:L3=L2/L4:L6=L5/L7:BOTTOM=L7 |
| SSD_PWREN2 | OTHERS | BUS | 6 | 5 | 5 | 10 | 5 | 14 | 6 | 10 | 12 | 12 | 12 | 12 |  | 50 Ohms | TOP=L2:L3=L2/L4:L6=L5/L7:BOTTOM=L7 |
| SSD_PWREN2 | OTHERS | BUS | 7 | 5 | 5 | 10 | 5 | 14 | 6 | 10 | 12 | 12 | 12 | 12 |  | 50 Ohms | TOP=L2:L3=L2/L4:L6=L5/L7:BOTTOM=L7 |
| SSD_PWREN2 | OTHERS | BUS | 8 | 4.75 | 5 | 10 | 5 | 14 | 6 | 9.5 | 12 | 12 | 12 | 12 |  | 50 Ohms | TOP=L2:L3=L2/L4:L6=L5/L7:BOTTOM=L7 |
| SSD_PWREN2_R | OTHERS | BUS | 1 | 4.75 | 5 | 10 | 5 | 14 | 6 | 9.5 | 12 | 12 | 12 | 12 |  | 50 Ohms | TOP=L2:L3=L2/L4:L6=L5/L7:BOTTOM=L7 |
| SSD_PWREN2_R | OTHERS | BUS | 2 | 5 | 5 | 10 | 5 | 14 | 6 | 10 | 12 | 12 | 12 | 12 |  | 50 Ohms | TOP=L2:L3=L2/L4:L6=L5/L7:BOTTOM=L7 |
| SSD_PWREN2_R | OTHERS | BUS | 3 | 5 | 5 | 10 | 5 | 14 | 6 | 10 | 12 | 12 | 12 | 12 |  | 50 Ohms | TOP=L2:L3=L2/L4:L6=L5/L7:BOTTOM=L7 |
| SSD_PWREN2_R | OTHERS | BUS | 4 | 5 | 5 | 10 | 5 | 14 | 6 | 10 | 12 | 12 | 12 | 12 |  | 50 Ohms | TOP=L2:L3=L2/L4:L6=L5/L7:BOTTOM=L7 |
| SSD_PWREN2_R | OTHERS | BUS | 5 | 5 | 5 | 10 | 5 | 14 | 6 | 10 | 12 | 12 | 12 | 12 |  | 50 Ohms | TOP=L2:L3=L2/L4:L6=L5/L7:BOTTOM=L7 |
| SSD_PWREN2_R | OTHERS | BUS | 6 | 5 | 5 | 10 | 5 | 14 | 6 | 10 | 12 | 12 | 12 | 12 |  | 50 Ohms | TOP=L2:L3=L2/L4:L6=L5/L7:BOTTOM=L7 |
| SSD_PWREN2_R | OTHERS | BUS | 7 | 5 | 5 | 10 | 5 | 14 | 6 | 10 | 12 | 12 | 12 | 12 |  | 50 Ohms | TOP=L2:L3=L2/L4:L6=L5/L7:BOTTOM=L7 |
| SSD_PWREN2_R | OTHERS | BUS | 8 | 4.75 | 5 | 10 | 5 | 14 | 6 | 9.5 | 12 | 12 | 12 | 12 |  | 50 Ohms | TOP=L2:L3=L2/L4:L6=L5/L7:BOTTOM=L7 |
| SSD_PWREN3 | OTHERS | BUS | 1 | 4.75 | 5 | 10 | 5 | 14 | 6 | 9.5 | 12 | 12 | 12 | 12 |  | 50 Ohms | TOP=L2:L3=L2/L4:L6=L5/L7:BOTTOM=L7 |
| SSD_PWREN3 | OTHERS | BUS | 2 | 5 | 5 | 10 | 5 | 14 | 6 | 10 | 12 | 12 | 12 | 12 |  | 50 Ohms | TOP=L2:L3=L2/L4:L6=L5/L7:BOTTOM=L7 |
| SSD_PWREN3 | OTHERS | BUS | 3 | 5 | 5 | 10 | 5 | 14 | 6 | 10 | 12 | 12 | 12 | 12 |  | 50 Ohms | TOP=L2:L3=L2/L4:L6=L5/L7:BOTTOM=L7 |
| SSD_PWREN3 | OTHERS | BUS | 4 | 5 | 5 | 10 | 5 | 14 | 6 | 10 | 12 | 12 | 12 | 12 |  | 50 Ohms | TOP=L2:L3=L2/L4:L6=L5/L7:BOTTOM=L7 |
| SSD_PWREN3 | OTHERS | BUS | 5 | 5 | 5 | 10 | 5 | 14 | 6 | 10 | 12 | 12 | 12 | 12 |  | 50 Ohms | TOP=L2:L3=L2/L4:L6=L5/L7:BOTTOM=L7 |
| SSD_PWREN3 | OTHERS | BUS | 6 | 5 | 5 | 10 | 5 | 14 | 6 | 10 | 12 | 12 | 12 | 12 |  | 50 Ohms | TOP=L2:L3=L2/L4:L6=L5/L7:BOTTOM=L7 |
| SSD_PWREN3 | OTHERS | BUS | 7 | 5 | 5 | 10 | 5 | 14 | 6 | 10 | 12 | 12 | 12 | 12 |  | 50 Ohms | TOP=L2:L3=L2/L4:L6=L5/L7:BOTTOM=L7 |
| SSD_PWREN3 | OTHERS | BUS | 8 | 4.75 | 5 | 10 | 5 | 14 | 6 | 9.5 | 12 | 12 | 12 | 12 |  | 50 Ohms | TOP=L2:L3=L2/L4:L6=L5/L7:BOTTOM=L7 |
| SSD_PWREN3_R | OTHERS | BUS | 1 | 4.75 | 5 | 10 | 5 | 14 | 6 | 9.5 | 12 | 12 | 12 | 12 |  | 50 Ohms | TOP=L2:L3=L2/L4:L6=L5/L7:BOTTOM=L7 |
| SSD_PWREN3_R | OTHERS | BUS | 2 | 5 | 5 | 10 | 5 | 14 | 6 | 10 | 12 | 12 | 12 | 12 |  | 50 Ohms | TOP=L2:L3=L2/L4:L6=L5/L7:BOTTOM=L7 |
| SSD_PWREN3_R | OTHERS | BUS | 3 | 5 | 5 | 10 | 5 | 14 | 6 | 10 | 12 | 12 | 12 | 12 |  | 50 Ohms | TOP=L2:L3=L2/L4:L6=L5/L7:BOTTOM=L7 |
| SSD_PWREN3_R | OTHERS | BUS | 4 | 5 | 5 | 10 | 5 | 14 | 6 | 10 | 12 | 12 | 12 | 12 |  | 50 Ohms | TOP=L2:L3=L2/L4:L6=L5/L7:BOTTOM=L7 |
| SSD_PWREN3_R | OTHERS | BUS | 5 | 5 | 5 | 10 | 5 | 14 | 6 | 10 | 12 | 12 | 12 | 12 |  | 50 Ohms | TOP=L2:L3=L2/L4:L6=L5/L7:BOTTOM=L7 |
| SSD_PWREN3_R | OTHERS | BUS | 6 | 5 | 5 | 10 | 5 | 14 | 6 | 10 | 12 | 12 | 12 | 12 |  | 50 Ohms | TOP=L2:L3=L2/L4:L6=L5/L7:BOTTOM=L7 |
| SSD_PWREN3_R | OTHERS | BUS | 7 | 5 | 5 | 10 | 5 | 14 | 6 | 10 | 12 | 12 | 12 | 12 |  | 50 Ohms | TOP=L2:L3=L2/L4:L6=L5/L7:BOTTOM=L7 |
| SSD_PWREN3_R | OTHERS | BUS | 8 | 4.75 | 5 | 10 | 5 | 14 | 6 | 9.5 | 12 | 12 | 12 | 12 |  | 50 Ohms | TOP=L2:L3=L2/L4:L6=L5/L7:BOTTOM=L7 |
| SSD_PWREN4 | OTHERS | BUS | 1 | 4.75 | 5 | 10 | 5 | 14 | 6 | 9.5 | 12 | 12 | 12 | 12 |  | 50 Ohms | TOP=L2:L3=L2/L4:L6=L5/L7:BOTTOM=L7 |
| SSD_PWREN4 | OTHERS | BUS | 2 | 5 | 5 | 10 | 5 | 14 | 6 | 10 | 12 | 12 | 12 | 12 |  | 50 Ohms | TOP=L2:L3=L2/L4:L6=L5/L7:BOTTOM=L7 |
| SSD_PWREN4 | OTHERS | BUS | 3 | 5 | 5 | 10 | 5 | 14 | 6 | 10 | 12 | 12 | 12 | 12 |  | 50 Ohms | TOP=L2:L3=L2/L4:L6=L5/L7:BOTTOM=L7 |
| SSD_PWREN4 | OTHERS | BUS | 4 | 5 | 5 | 10 | 5 | 14 | 6 | 10 | 12 | 12 | 12 | 12 |  | 50 Ohms | TOP=L2:L3=L2/L4:L6=L5/L7:BOTTOM=L7 |
| SSD_PWREN4 | OTHERS | BUS | 5 | 5 | 5 | 10 | 5 | 14 | 6 | 10 | 12 | 12 | 12 | 12 |  | 50 Ohms | TOP=L2:L3=L2/L4:L6=L5/L7:BOTTOM=L7 |
| SSD_PWREN4 | OTHERS | BUS | 6 | 5 | 5 | 10 | 5 | 14 | 6 | 10 | 12 | 12 | 12 | 12 |  | 50 Ohms | TOP=L2:L3=L2/L4:L6=L5/L7:BOTTOM=L7 |
| SSD_PWREN4 | OTHERS | BUS | 7 | 5 | 5 | 10 | 5 | 14 | 6 | 10 | 12 | 12 | 12 | 12 |  | 50 Ohms | TOP=L2:L3=L2/L4:L6=L5/L7:BOTTOM=L7 |
| SSD_PWREN4 | OTHERS | BUS | 8 | 4.75 | 5 | 10 | 5 | 14 | 6 | 9.5 | 12 | 12 | 12 | 12 |  | 50 Ohms | TOP=L2:L3=L2/L4:L6=L5/L7:BOTTOM=L7 |
| SSD_PWREN4_R | OTHERS | BUS | 1 | 4.75 | 5 | 10 | 5 | 14 | 6 | 9.5 | 12 | 12 | 12 | 12 |  | 50 Ohms | TOP=L2:L3=L2/L4:L6=L5/L7:BOTTOM=L7 |
| SSD_PWREN4_R | OTHERS | BUS | 2 | 5 | 5 | 10 | 5 | 14 | 6 | 10 | 12 | 12 | 12 | 12 |  | 50 Ohms | TOP=L2:L3=L2/L4:L6=L5/L7:BOTTOM=L7 |
| SSD_PWREN4_R | OTHERS | BUS | 3 | 5 | 5 | 10 | 5 | 14 | 6 | 10 | 12 | 12 | 12 | 12 |  | 50 Ohms | TOP=L2:L3=L2/L4:L6=L5/L7:BOTTOM=L7 |
| SSD_PWREN4_R | OTHERS | BUS | 4 | 5 | 5 | 10 | 5 | 14 | 6 | 10 | 12 | 12 | 12 | 12 |  | 50 Ohms | TOP=L2:L3=L2/L4:L6=L5/L7:BOTTOM=L7 |
| SSD_PWREN4_R | OTHERS | BUS | 5 | 5 | 5 | 10 | 5 | 14 | 6 | 10 | 12 | 12 | 12 | 12 |  | 50 Ohms | TOP=L2:L3=L2/L4:L6=L5/L7:BOTTOM=L7 |
| SSD_PWREN4_R | OTHERS | BUS | 6 | 5 | 5 | 10 | 5 | 14 | 6 | 10 | 12 | 12 | 12 | 12 |  | 50 Ohms | TOP=L2:L3=L2/L4:L6=L5/L7:BOTTOM=L7 |
| SSD_PWREN4_R | OTHERS | BUS | 7 | 5 | 5 | 10 | 5 | 14 | 6 | 10 | 12 | 12 | 12 | 12 |  | 50 Ohms | TOP=L2:L3=L2/L4:L6=L5/L7:BOTTOM=L7 |
| SSD_PWREN4_R | OTHERS | BUS | 8 | 4.75 | 5 | 10 | 5 | 14 | 6 | 9.5 | 12 | 12 | 12 | 12 |  | 50 Ohms | TOP=L2:L3=L2/L4:L6=L5/L7:BOTTOM=L7 |
| SSD_PWREN5 | OTHERS | BUS | 1 | 4.75 | 5 | 10 | 5 | 14 | 6 | 9.5 | 12 | 12 | 12 | 12 |  | 50 Ohms | TOP=L2:L3=L2/L4:L6=L5/L7:BOTTOM=L7 |
| SSD_PWREN5 | OTHERS | BUS | 2 | 5 | 5 | 10 | 5 | 14 | 6 | 10 | 12 | 12 | 12 | 12 |  | 50 Ohms | TOP=L2:L3=L2/L4:L6=L5/L7:BOTTOM=L7 |
| SSD_PWREN5 | OTHERS | BUS | 3 | 5 | 5 | 10 | 5 | 14 | 6 | 10 | 12 | 12 | 12 | 12 |  | 50 Ohms | TOP=L2:L3=L2/L4:L6=L5/L7:BOTTOM=L7 |
| SSD_PWREN5 | OTHERS | BUS | 4 | 5 | 5 | 10 | 5 | 14 | 6 | 10 | 12 | 12 | 12 | 12 |  | 50 Ohms | TOP=L2:L3=L2/L4:L6=L5/L7:BOTTOM=L7 |
| SSD_PWREN5 | OTHERS | BUS | 5 | 5 | 5 | 10 | 5 | 14 | 6 | 10 | 12 | 12 | 12 | 12 |  | 50 Ohms | TOP=L2:L3=L2/L4:L6=L5/L7:BOTTOM=L7 |
| SSD_PWREN5 | OTHERS | BUS | 6 | 5 | 5 | 10 | 5 | 14 | 6 | 10 | 12 | 12 | 12 | 12 |  | 50 Ohms | TOP=L2:L3=L2/L4:L6=L5/L7:BOTTOM=L7 |
| SSD_PWREN5 | OTHERS | BUS | 7 | 5 | 5 | 10 | 5 | 14 | 6 | 10 | 12 | 12 | 12 | 12 |  | 50 Ohms | TOP=L2:L3=L2/L4:L6=L5/L7:BOTTOM=L7 |
| SSD_PWREN5 | OTHERS | BUS | 8 | 4.75 | 5 | 10 | 5 | 14 | 6 | 9.5 | 12 | 12 | 12 | 12 |  | 50 Ohms | TOP=L2:L3=L2/L4:L6=L5/L7:BOTTOM=L7 |
| SSD_PWREN5_R | OTHERS | BUS | 1 | 4.75 | 5 | 10 | 5 | 14 | 6 | 9.5 | 12 | 12 | 12 | 12 |  | 50 Ohms | TOP=L2:L3=L2/L4:L6=L5/L7:BOTTOM=L7 |
| SSD_PWREN5_R | OTHERS | BUS | 2 | 5 | 5 | 10 | 5 | 14 | 6 | 10 | 12 | 12 | 12 | 12 |  | 50 Ohms | TOP=L2:L3=L2/L4:L6=L5/L7:BOTTOM=L7 |
| SSD_PWREN5_R | OTHERS | BUS | 3 | 5 | 5 | 10 | 5 | 14 | 6 | 10 | 12 | 12 | 12 | 12 |  | 50 Ohms | TOP=L2:L3=L2/L4:L6=L5/L7:BOTTOM=L7 |
| SSD_PWREN5_R | OTHERS | BUS | 4 | 5 | 5 | 10 | 5 | 14 | 6 | 10 | 12 | 12 | 12 | 12 |  | 50 Ohms | TOP=L2:L3=L2/L4:L6=L5/L7:BOTTOM=L7 |
| SSD_PWREN5_R | OTHERS | BUS | 5 | 5 | 5 | 10 | 5 | 14 | 6 | 10 | 12 | 12 | 12 | 12 |  | 50 Ohms | TOP=L2:L3=L2/L4:L6=L5/L7:BOTTOM=L7 |
| SSD_PWREN5_R | OTHERS | BUS | 6 | 5 | 5 | 10 | 5 | 14 | 6 | 10 | 12 | 12 | 12 | 12 |  | 50 Ohms | TOP=L2:L3=L2/L4:L6=L5/L7:BOTTOM=L7 |
| SSD_PWREN5_R | OTHERS | BUS | 7 | 5 | 5 | 10 | 5 | 14 | 6 | 10 | 12 | 12 | 12 | 12 |  | 50 Ohms | TOP=L2:L3=L2/L4:L6=L5/L7:BOTTOM=L7 |
| SSD_PWREN5_R | OTHERS | BUS | 8 | 4.75 | 5 | 10 | 5 | 14 | 6 | 9.5 | 12 | 12 | 12 | 12 |  | 50 Ohms | TOP=L2:L3=L2/L4:L6=L5/L7:BOTTOM=L7 |
| SSD_PWREN6 | OTHERS | BUS | 1 | 4.75 | 5 | 10 | 5 | 14 | 6 | 9.5 | 12 | 12 | 12 | 12 |  | 50 Ohms | TOP=L2:L3=L2/L4:L6=L5/L7:BOTTOM=L7 |
| SSD_PWREN6 | OTHERS | BUS | 2 | 5 | 5 | 10 | 5 | 14 | 6 | 10 | 12 | 12 | 12 | 12 |  | 50 Ohms | TOP=L2:L3=L2/L4:L6=L5/L7:BOTTOM=L7 |
| SSD_PWREN6 | OTHERS | BUS | 3 | 5 | 5 | 10 | 5 | 14 | 6 | 10 | 12 | 12 | 12 | 12 |  | 50 Ohms | TOP=L2:L3=L2/L4:L6=L5/L7:BOTTOM=L7 |
| SSD_PWREN6 | OTHERS | BUS | 4 | 5 | 5 | 10 | 5 | 14 | 6 | 10 | 12 | 12 | 12 | 12 |  | 50 Ohms | TOP=L2:L3=L2/L4:L6=L5/L7:BOTTOM=L7 |
| SSD_PWREN6 | OTHERS | BUS | 5 | 5 | 5 | 10 | 5 | 14 | 6 | 10 | 12 | 12 | 12 | 12 |  | 50 Ohms | TOP=L2:L3=L2/L4:L6=L5/L7:BOTTOM=L7 |
| SSD_PWREN6 | OTHERS | BUS | 6 | 5 | 5 | 10 | 5 | 14 | 6 | 10 | 12 | 12 | 12 | 12 |  | 50 Ohms | TOP=L2:L3=L2/L4:L6=L5/L7:BOTTOM=L7 |
| SSD_PWREN6 | OTHERS | BUS | 7 | 5 | 5 | 10 | 5 | 14 | 6 | 10 | 12 | 12 | 12 | 12 |  | 50 Ohms | TOP=L2:L3=L2/L4:L6=L5/L7:BOTTOM=L7 |
| SSD_PWREN6 | OTHERS | BUS | 8 | 4.75 | 5 | 10 | 5 | 14 | 6 | 9.5 | 12 | 12 | 12 | 12 |  | 50 Ohms | TOP=L2:L3=L2/L4:L6=L5/L7:BOTTOM=L7 |
| SSD_PWREN6_R | OTHERS | BUS | 1 | 4.75 | 5 | 10 | 5 | 14 | 6 | 9.5 | 12 | 12 | 12 | 12 |  | 50 Ohms | TOP=L2:L3=L2/L4:L6=L5/L7:BOTTOM=L7 |
| SSD_PWREN6_R | OTHERS | BUS | 2 | 5 | 5 | 10 | 5 | 14 | 6 | 10 | 12 | 12 | 12 | 12 |  | 50 Ohms | TOP=L2:L3=L2/L4:L6=L5/L7:BOTTOM=L7 |
| SSD_PWREN6_R | OTHERS | BUS | 3 | 5 | 5 | 10 | 5 | 14 | 6 | 10 | 12 | 12 | 12 | 12 |  | 50 Ohms | TOP=L2:L3=L2/L4:L6=L5/L7:BOTTOM=L7 |
| SSD_PWREN6_R | OTHERS | BUS | 4 | 5 | 5 | 10 | 5 | 14 | 6 | 10 | 12 | 12 | 12 | 12 |  | 50 Ohms | TOP=L2:L3=L2/L4:L6=L5/L7:BOTTOM=L7 |
| SSD_PWREN6_R | OTHERS | BUS | 5 | 5 | 5 | 10 | 5 | 14 | 6 | 10 | 12 | 12 | 12 | 12 |  | 50 Ohms | TOP=L2:L3=L2/L4:L6=L5/L7:BOTTOM=L7 |
| SSD_PWREN6_R | OTHERS | BUS | 6 | 5 | 5 | 10 | 5 | 14 | 6 | 10 | 12 | 12 | 12 | 12 |  | 50 Ohms | TOP=L2:L3=L2/L4:L6=L5/L7:BOTTOM=L7 |
| SSD_PWREN6_R | OTHERS | BUS | 7 | 5 | 5 | 10 | 5 | 14 | 6 | 10 | 12 | 12 | 12 | 12 |  | 50 Ohms | TOP=L2:L3=L2/L4:L6=L5/L7:BOTTOM=L7 |
| SSD_PWREN6_R | OTHERS | BUS | 8 | 4.75 | 5 | 10 | 5 | 14 | 6 | 9.5 | 12 | 12 | 12 | 12 |  | 50 Ohms | TOP=L2:L3=L2/L4:L6=L5/L7:BOTTOM=L7 |
| SSD_PWREN7 | OTHERS | BUS | 1 | 4.75 | 5 | 10 | 5 | 14 | 6 | 9.5 | 12 | 12 | 12 | 12 |  | 50 Ohms | TOP=L2:L3=L2/L4:L6=L5/L7:BOTTOM=L7 |
| SSD_PWREN7 | OTHERS | BUS | 2 | 5 | 5 | 10 | 5 | 14 | 6 | 10 | 12 | 12 | 12 | 12 |  | 50 Ohms | TOP=L2:L3=L2/L4:L6=L5/L7:BOTTOM=L7 |
| SSD_PWREN7 | OTHERS | BUS | 3 | 5 | 5 | 10 | 5 | 14 | 6 | 10 | 12 | 12 | 12 | 12 |  | 50 Ohms | TOP=L2:L3=L2/L4:L6=L5/L7:BOTTOM=L7 |
| SSD_PWREN7 | OTHERS | BUS | 4 | 5 | 5 | 10 | 5 | 14 | 6 | 10 | 12 | 12 | 12 | 12 |  | 50 Ohms | TOP=L2:L3=L2/L4:L6=L5/L7:BOTTOM=L7 |
| SSD_PWREN7 | OTHERS | BUS | 5 | 5 | 5 | 10 | 5 | 14 | 6 | 10 | 12 | 12 | 12 | 12 |  | 50 Ohms | TOP=L2:L3=L2/L4:L6=L5/L7:BOTTOM=L7 |
| SSD_PWREN7 | OTHERS | BUS | 6 | 5 | 5 | 10 | 5 | 14 | 6 | 10 | 12 | 12 | 12 | 12 |  | 50 Ohms | TOP=L2:L3=L2/L4:L6=L5/L7:BOTTOM=L7 |
| SSD_PWREN7 | OTHERS | BUS | 7 | 5 | 5 | 10 | 5 | 14 | 6 | 10 | 12 | 12 | 12 | 12 |  | 50 Ohms | TOP=L2:L3=L2/L4:L6=L5/L7:BOTTOM=L7 |
| SSD_PWREN7 | OTHERS | BUS | 8 | 4.75 | 5 | 10 | 5 | 14 | 6 | 9.5 | 12 | 12 | 12 | 12 |  | 50 Ohms | TOP=L2:L3=L2/L4:L6=L5/L7:BOTTOM=L7 |
| SSD_PWREN7_R | OTHERS | BUS | 1 | 4.75 | 5 | 10 | 5 | 14 | 6 | 9.5 | 12 | 12 | 12 | 12 |  | 50 Ohms | TOP=L2:L3=L2/L4:L6=L5/L7:BOTTOM=L7 |
| SSD_PWREN7_R | OTHERS | BUS | 2 | 5 | 5 | 10 | 5 | 14 | 6 | 10 | 12 | 12 | 12 | 12 |  | 50 Ohms | TOP=L2:L3=L2/L4:L6=L5/L7:BOTTOM=L7 |
| SSD_PWREN7_R | OTHERS | BUS | 3 | 5 | 5 | 10 | 5 | 14 | 6 | 10 | 12 | 12 | 12 | 12 |  | 50 Ohms | TOP=L2:L3=L2/L4:L6=L5/L7:BOTTOM=L7 |
| SSD_PWREN7_R | OTHERS | BUS | 4 | 5 | 5 | 10 | 5 | 14 | 6 | 10 | 12 | 12 | 12 | 12 |  | 50 Ohms | TOP=L2:L3=L2/L4:L6=L5/L7:BOTTOM=L7 |
| SSD_PWREN7_R | OTHERS | BUS | 5 | 5 | 5 | 10 | 5 | 14 | 6 | 10 | 12 | 12 | 12 | 12 |  | 50 Ohms | TOP=L2:L3=L2/L4:L6=L5/L7:BOTTOM=L7 |
| SSD_PWREN7_R | OTHERS | BUS | 6 | 5 | 5 | 10 | 5 | 14 | 6 | 10 | 12 | 12 | 12 | 12 |  | 50 Ohms | TOP=L2:L3=L2/L4:L6=L5/L7:BOTTOM=L7 |
| SSD_PWREN7_R | OTHERS | BUS | 7 | 5 | 5 | 10 | 5 | 14 | 6 | 10 | 12 | 12 | 12 | 12 |  | 50 Ohms | TOP=L2:L3=L2/L4:L6=L5/L7:BOTTOM=L7 |
| SSD_PWREN7_R | OTHERS | BUS | 8 | 4.75 | 5 | 10 | 5 | 14 | 6 | 9.5 | 12 | 12 | 12 | 12 |  | 50 Ohms | TOP=L2:L3=L2/L4:L6=L5/L7:BOTTOM=L7 |
| SSD_PWREN8 | OTHERS | BUS | 1 | 4.75 | 5 | 10 | 5 | 14 | 6 | 9.5 | 12 | 12 | 12 | 12 |  | 50 Ohms | TOP=L2:L3=L2/L4:L6=L5/L7:BOTTOM=L7 |
| SSD_PWREN8 | OTHERS | BUS | 2 | 5 | 5 | 10 | 5 | 14 | 6 | 10 | 12 | 12 | 12 | 12 |  | 50 Ohms | TOP=L2:L3=L2/L4:L6=L5/L7:BOTTOM=L7 |
| SSD_PWREN8 | OTHERS | BUS | 3 | 5 | 5 | 10 | 5 | 14 | 6 | 10 | 12 | 12 | 12 | 12 |  | 50 Ohms | TOP=L2:L3=L2/L4:L6=L5/L7:BOTTOM=L7 |
| SSD_PWREN8 | OTHERS | BUS | 4 | 5 | 5 | 10 | 5 | 14 | 6 | 10 | 12 | 12 | 12 | 12 |  | 50 Ohms | TOP=L2:L3=L2/L4:L6=L5/L7:BOTTOM=L7 |
| SSD_PWREN8 | OTHERS | BUS | 5 | 5 | 5 | 10 | 5 | 14 | 6 | 10 | 12 | 12 | 12 | 12 |  | 50 Ohms | TOP=L2:L3=L2/L4:L6=L5/L7:BOTTOM=L7 |
| SSD_PWREN8 | OTHERS | BUS | 6 | 5 | 5 | 10 | 5 | 14 | 6 | 10 | 12 | 12 | 12 | 12 |  | 50 Ohms | TOP=L2:L3=L2/L4:L6=L5/L7:BOTTOM=L7 |
| SSD_PWREN8 | OTHERS | BUS | 7 | 5 | 5 | 10 | 5 | 14 | 6 | 10 | 12 | 12 | 12 | 12 |  | 50 Ohms | TOP=L2:L3=L2/L4:L6=L5/L7:BOTTOM=L7 |
| SSD_PWREN8 | OTHERS | BUS | 8 | 4.75 | 5 | 10 | 5 | 14 | 6 | 9.5 | 12 | 12 | 12 | 12 |  | 50 Ohms | TOP=L2:L3=L2/L4:L6=L5/L7:BOTTOM=L7 |
| SSD_PWREN8_R | OTHERS | BUS | 1 | 4.75 | 5 | 10 | 5 | 14 | 6 | 9.5 | 12 | 12 | 12 | 12 |  | 50 Ohms | TOP=L2:L3=L2/L4:L6=L5/L7:BOTTOM=L7 |
| SSD_PWREN8_R | OTHERS | BUS | 2 | 5 | 5 | 10 | 5 | 14 | 6 | 10 | 12 | 12 | 12 | 12 |  | 50 Ohms | TOP=L2:L3=L2/L4:L6=L5/L7:BOTTOM=L7 |
| SSD_PWREN8_R | OTHERS | BUS | 3 | 5 | 5 | 10 | 5 | 14 | 6 | 10 | 12 | 12 | 12 | 12 |  | 50 Ohms | TOP=L2:L3=L2/L4:L6=L5/L7:BOTTOM=L7 |
| SSD_PWREN8_R | OTHERS | BUS | 4 | 5 | 5 | 10 | 5 | 14 | 6 | 10 | 12 | 12 | 12 | 12 |  | 50 Ohms | TOP=L2:L3=L2/L4:L6=L5/L7:BOTTOM=L7 |
| SSD_PWREN8_R | OTHERS | BUS | 5 | 5 | 5 | 10 | 5 | 14 | 6 | 10 | 12 | 12 | 12 | 12 |  | 50 Ohms | TOP=L2:L3=L2/L4:L6=L5/L7:BOTTOM=L7 |
| SSD_PWREN8_R | OTHERS | BUS | 6 | 5 | 5 | 10 | 5 | 14 | 6 | 10 | 12 | 12 | 12 | 12 |  | 50 Ohms | TOP=L2:L3=L2/L4:L6=L5/L7:BOTTOM=L7 |
| SSD_PWREN8_R | OTHERS | BUS | 7 | 5 | 5 | 10 | 5 | 14 | 6 | 10 | 12 | 12 | 12 | 12 |  | 50 Ohms | TOP=L2:L3=L2/L4:L6=L5/L7:BOTTOM=L7 |
| SSD_PWREN8_R | OTHERS | BUS | 8 | 4.75 | 5 | 10 | 5 | 14 | 6 | 9.5 | 12 | 12 | 12 | 12 |  | 50 Ohms | TOP=L2:L3=L2/L4:L6=L5/L7:BOTTOM=L7 |
| SSD_PWREN9 | OTHERS | BUS | 1 | 4.75 | 5 | 10 | 5 | 14 | 6 | 9.5 | 12 | 12 | 12 | 12 |  | 50 Ohms | TOP=L2:L3=L2/L4:L6=L5/L7:BOTTOM=L7 |
| SSD_PWREN9 | OTHERS | BUS | 2 | 5 | 5 | 10 | 5 | 14 | 6 | 10 | 12 | 12 | 12 | 12 |  | 50 Ohms | TOP=L2:L3=L2/L4:L6=L5/L7:BOTTOM=L7 |
| SSD_PWREN9 | OTHERS | BUS | 3 | 5 | 5 | 10 | 5 | 14 | 6 | 10 | 12 | 12 | 12 | 12 |  | 50 Ohms | TOP=L2:L3=L2/L4:L6=L5/L7:BOTTOM=L7 |
| SSD_PWREN9 | OTHERS | BUS | 4 | 5 | 5 | 10 | 5 | 14 | 6 | 10 | 12 | 12 | 12 | 12 |  | 50 Ohms | TOP=L2:L3=L2/L4:L6=L5/L7:BOTTOM=L7 |
| SSD_PWREN9 | OTHERS | BUS | 5 | 5 | 5 | 10 | 5 | 14 | 6 | 10 | 12 | 12 | 12 | 12 |  | 50 Ohms | TOP=L2:L3=L2/L4:L6=L5/L7:BOTTOM=L7 |
| SSD_PWREN9 | OTHERS | BUS | 6 | 5 | 5 | 10 | 5 | 14 | 6 | 10 | 12 | 12 | 12 | 12 |  | 50 Ohms | TOP=L2:L3=L2/L4:L6=L5/L7:BOTTOM=L7 |
| SSD_PWREN9 | OTHERS | BUS | 7 | 5 | 5 | 10 | 5 | 14 | 6 | 10 | 12 | 12 | 12 | 12 |  | 50 Ohms | TOP=L2:L3=L2/L4:L6=L5/L7:BOTTOM=L7 |
| SSD_PWREN9 | OTHERS | BUS | 8 | 4.75 | 5 | 10 | 5 | 14 | 6 | 9.5 | 12 | 12 | 12 | 12 |  | 50 Ohms | TOP=L2:L3=L2/L4:L6=L5/L7:BOTTOM=L7 |
| SSD_PWREN9_R | OTHERS | BUS | 1 | 4.75 | 5 | 10 | 5 | 14 | 6 | 9.5 | 12 | 12 | 12 | 12 |  | 50 Ohms | TOP=L2:L3=L2/L4:L6=L5/L7:BOTTOM=L7 |
| SSD_PWREN9_R | OTHERS | BUS | 2 | 5 | 5 | 10 | 5 | 14 | 6 | 10 | 12 | 12 | 12 | 12 |  | 50 Ohms | TOP=L2:L3=L2/L4:L6=L5/L7:BOTTOM=L7 |
| SSD_PWREN9_R | OTHERS | BUS | 3 | 5 | 5 | 10 | 5 | 14 | 6 | 10 | 12 | 12 | 12 | 12 |  | 50 Ohms | TOP=L2:L3=L2/L4:L6=L5/L7:BOTTOM=L7 |
| SSD_PWREN9_R | OTHERS | BUS | 4 | 5 | 5 | 10 | 5 | 14 | 6 | 10 | 12 | 12 | 12 | 12 |  | 50 Ohms | TOP=L2:L3=L2/L4:L6=L5/L7:BOTTOM=L7 |
| SSD_PWREN9_R | OTHERS | BUS | 5 | 5 | 5 | 10 | 5 | 14 | 6 | 10 | 12 | 12 | 12 | 12 |  | 50 Ohms | TOP=L2:L3=L2/L4:L6=L5/L7:BOTTOM=L7 |
| SSD_PWREN9_R | OTHERS | BUS | 6 | 5 | 5 | 10 | 5 | 14 | 6 | 10 | 12 | 12 | 12 | 12 |  | 50 Ohms | TOP=L2:L3=L2/L4:L6=L5/L7:BOTTOM=L7 |
| SSD_PWREN9_R | OTHERS | BUS | 7 | 5 | 5 | 10 | 5 | 14 | 6 | 10 | 12 | 12 | 12 | 12 |  | 50 Ohms | TOP=L2:L3=L2/L4:L6=L5/L7:BOTTOM=L7 |
| SSD_PWREN9_R | OTHERS | BUS | 8 | 4.75 | 5 | 10 | 5 | 14 | 6 | 9.5 | 12 | 12 | 12 | 12 |  | 50 Ohms | TOP=L2:L3=L2/L4:L6=L5/L7:BOTTOM=L7 |
| TCA9554_INT_N | OTHERS | BUS | 1 | 4.75 | 5 | 10 | 5 | 14 | 6 | 9.5 | 12 | 12 | 12 | 12 |  | 50 Ohms | TOP=L2:L3=L2/L4:L6=L5/L7:BOTTOM=L7 |
| TCA9554_INT_N | OTHERS | BUS | 2 | 5 | 5 | 10 | 5 | 14 | 6 | 10 | 12 | 12 | 12 | 12 |  | 50 Ohms | TOP=L2:L3=L2/L4:L6=L5/L7:BOTTOM=L7 |
| TCA9554_INT_N | OTHERS | BUS | 3 | 5 | 5 | 10 | 5 | 14 | 6 | 10 | 12 | 12 | 12 | 12 |  | 50 Ohms | TOP=L2:L3=L2/L4:L6=L5/L7:BOTTOM=L7 |
| TCA9554_INT_N | OTHERS | BUS | 4 | 5 | 5 | 10 | 5 | 14 | 6 | 10 | 12 | 12 | 12 | 12 |  | 50 Ohms | TOP=L2:L3=L2/L4:L6=L5/L7:BOTTOM=L7 |
| TCA9554_INT_N | OTHERS | BUS | 5 | 5 | 5 | 10 | 5 | 14 | 6 | 10 | 12 | 12 | 12 | 12 |  | 50 Ohms | TOP=L2:L3=L2/L4:L6=L5/L7:BOTTOM=L7 |
| TCA9554_INT_N | OTHERS | BUS | 6 | 5 | 5 | 10 | 5 | 14 | 6 | 10 | 12 | 12 | 12 | 12 |  | 50 Ohms | TOP=L2:L3=L2/L4:L6=L5/L7:BOTTOM=L7 |
| TCA9554_INT_N | OTHERS | BUS | 7 | 5 | 5 | 10 | 5 | 14 | 6 | 10 | 12 | 12 | 12 | 12 |  | 50 Ohms | TOP=L2:L3=L2/L4:L6=L5/L7:BOTTOM=L7 |
| TCA9554_INT_N | OTHERS | BUS | 8 | 4.75 | 5 | 10 | 5 | 14 | 6 | 9.5 | 12 | 12 | 12 | 12 |  | 50 Ohms | TOP=L2:L3=L2/L4:L6=L5/L7:BOTTOM=L7 |
| TCA9554_INT_N_R | OTHERS | BUS | 1 | 4.75 | 5 | 10 | 5 | 14 | 6 | 9.5 | 12 | 12 | 12 | 12 |  | 50 Ohms | TOP=L2:L3=L2/L4:L6=L5/L7:BOTTOM=L7 |
| TCA9554_INT_N_R | OTHERS | BUS | 2 | 5 | 5 | 10 | 5 | 14 | 6 | 10 | 12 | 12 | 12 | 12 |  | 50 Ohms | TOP=L2:L3=L2/L4:L6=L5/L7:BOTTOM=L7 |
| TCA9554_INT_N_R | OTHERS | BUS | 3 | 5 | 5 | 10 | 5 | 14 | 6 | 10 | 12 | 12 | 12 | 12 |  | 50 Ohms | TOP=L2:L3=L2/L4:L6=L5/L7:BOTTOM=L7 |
| TCA9554_INT_N_R | OTHERS | BUS | 4 | 5 | 5 | 10 | 5 | 14 | 6 | 10 | 12 | 12 | 12 | 12 |  | 50 Ohms | TOP=L2:L3=L2/L4:L6=L5/L7:BOTTOM=L7 |
| TCA9554_INT_N_R | OTHERS | BUS | 5 | 5 | 5 | 10 | 5 | 14 | 6 | 10 | 12 | 12 | 12 | 12 |  | 50 Ohms | TOP=L2:L3=L2/L4:L6=L5/L7:BOTTOM=L7 |
| TCA9554_INT_N_R | OTHERS | BUS | 6 | 5 | 5 | 10 | 5 | 14 | 6 | 10 | 12 | 12 | 12 | 12 |  | 50 Ohms | TOP=L2:L3=L2/L4:L6=L5/L7:BOTTOM=L7 |
| TCA9554_INT_N_R | OTHERS | BUS | 7 | 5 | 5 | 10 | 5 | 14 | 6 | 10 | 12 | 12 | 12 | 12 |  | 50 Ohms | TOP=L2:L3=L2/L4:L6=L5/L7:BOTTOM=L7 |
| TCA9554_INT_N_R | OTHERS | BUS | 8 | 4.75 | 5 | 10 | 5 | 14 | 6 | 9.5 | 12 | 12 | 12 | 12 |  | 50 Ohms | TOP=L2:L3=L2/L4:L6=L5/L7:BOTTOM=L7 |
| TEMP_1_A0 | OTHERS | BUS | 1 | 4.75 | 5 | 10 | 5 | 14 | 6 | 9.5 | 12 | 12 | 12 | 12 |  | 50 Ohms | TOP=L2:L3=L2/L4:L6=L5/L7:BOTTOM=L7 |
| TEMP_1_A0 | OTHERS | BUS | 2 | 5 | 5 | 10 | 5 | 14 | 6 | 10 | 12 | 12 | 12 | 12 |  | 50 Ohms | TOP=L2:L3=L2/L4:L6=L5/L7:BOTTOM=L7 |
| TEMP_1_A0 | OTHERS | BUS | 3 | 5 | 5 | 10 | 5 | 14 | 6 | 10 | 12 | 12 | 12 | 12 |  | 50 Ohms | TOP=L2:L3=L2/L4:L6=L5/L7:BOTTOM=L7 |
| TEMP_1_A0 | OTHERS | BUS | 4 | 5 | 5 | 10 | 5 | 14 | 6 | 10 | 12 | 12 | 12 | 12 |  | 50 Ohms | TOP=L2:L3=L2/L4:L6=L5/L7:BOTTOM=L7 |
| TEMP_1_A0 | OTHERS | BUS | 5 | 5 | 5 | 10 | 5 | 14 | 6 | 10 | 12 | 12 | 12 | 12 |  | 50 Ohms | TOP=L2:L3=L2/L4:L6=L5/L7:BOTTOM=L7 |
| TEMP_1_A0 | OTHERS | BUS | 6 | 5 | 5 | 10 | 5 | 14 | 6 | 10 | 12 | 12 | 12 | 12 |  | 50 Ohms | TOP=L2:L3=L2/L4:L6=L5/L7:BOTTOM=L7 |
| TEMP_1_A0 | OTHERS | BUS | 7 | 5 | 5 | 10 | 5 | 14 | 6 | 10 | 12 | 12 | 12 | 12 |  | 50 Ohms | TOP=L2:L3=L2/L4:L6=L5/L7:BOTTOM=L7 |
| TEMP_1_A0 | OTHERS | BUS | 8 | 4.75 | 5 | 10 | 5 | 14 | 6 | 9.5 | 12 | 12 | 12 | 12 |  | 50 Ohms | TOP=L2:L3=L2/L4:L6=L5/L7:BOTTOM=L7 |
| TEMP_1_A1 | OTHERS | BUS | 1 | 4.75 | 5 | 10 | 5 | 14 | 6 | 9.5 | 12 | 12 | 12 | 12 |  | 50 Ohms | TOP=L2:L3=L2/L4:L6=L5/L7:BOTTOM=L7 |
| TEMP_1_A1 | OTHERS | BUS | 2 | 5 | 5 | 10 | 5 | 14 | 6 | 10 | 12 | 12 | 12 | 12 |  | 50 Ohms | TOP=L2:L3=L2/L4:L6=L5/L7:BOTTOM=L7 |
| TEMP_1_A1 | OTHERS | BUS | 3 | 5 | 5 | 10 | 5 | 14 | 6 | 10 | 12 | 12 | 12 | 12 |  | 50 Ohms | TOP=L2:L3=L2/L4:L6=L5/L7:BOTTOM=L7 |
| TEMP_1_A1 | OTHERS | BUS | 4 | 5 | 5 | 10 | 5 | 14 | 6 | 10 | 12 | 12 | 12 | 12 |  | 50 Ohms | TOP=L2:L3=L2/L4:L6=L5/L7:BOTTOM=L7 |
| TEMP_1_A1 | OTHERS | BUS | 5 | 5 | 5 | 10 | 5 | 14 | 6 | 10 | 12 | 12 | 12 | 12 |  | 50 Ohms | TOP=L2:L3=L2/L4:L6=L5/L7:BOTTOM=L7 |
| TEMP_1_A1 | OTHERS | BUS | 6 | 5 | 5 | 10 | 5 | 14 | 6 | 10 | 12 | 12 | 12 | 12 |  | 50 Ohms | TOP=L2:L3=L2/L4:L6=L5/L7:BOTTOM=L7 |
| TEMP_1_A1 | OTHERS | BUS | 7 | 5 | 5 | 10 | 5 | 14 | 6 | 10 | 12 | 12 | 12 | 12 |  | 50 Ohms | TOP=L2:L3=L2/L4:L6=L5/L7:BOTTOM=L7 |
| TEMP_1_A1 | OTHERS | BUS | 8 | 4.75 | 5 | 10 | 5 | 14 | 6 | 9.5 | 12 | 12 | 12 | 12 |  | 50 Ohms | TOP=L2:L3=L2/L4:L6=L5/L7:BOTTOM=L7 |
| TEMP_2_A0 | OTHERS | BUS | 1 | 4.75 | 5 | 10 | 5 | 14 | 6 | 9.5 | 12 | 12 | 12 | 12 |  | 50 Ohms | TOP=L2:L3=L2/L4:L6=L5/L7:BOTTOM=L7 |
| TEMP_2_A0 | OTHERS | BUS | 2 | 5 | 5 | 10 | 5 | 14 | 6 | 10 | 12 | 12 | 12 | 12 |  | 50 Ohms | TOP=L2:L3=L2/L4:L6=L5/L7:BOTTOM=L7 |
| TEMP_2_A0 | OTHERS | BUS | 3 | 5 | 5 | 10 | 5 | 14 | 6 | 10 | 12 | 12 | 12 | 12 |  | 50 Ohms | TOP=L2:L3=L2/L4:L6=L5/L7:BOTTOM=L7 |
| TEMP_2_A0 | OTHERS | BUS | 4 | 5 | 5 | 10 | 5 | 14 | 6 | 10 | 12 | 12 | 12 | 12 |  | 50 Ohms | TOP=L2:L3=L2/L4:L6=L5/L7:BOTTOM=L7 |
| TEMP_2_A0 | OTHERS | BUS | 5 | 5 | 5 | 10 | 5 | 14 | 6 | 10 | 12 | 12 | 12 | 12 |  | 50 Ohms | TOP=L2:L3=L2/L4:L6=L5/L7:BOTTOM=L7 |
| TEMP_2_A0 | OTHERS | BUS | 6 | 5 | 5 | 10 | 5 | 14 | 6 | 10 | 12 | 12 | 12 | 12 |  | 50 Ohms | TOP=L2:L3=L2/L4:L6=L5/L7:BOTTOM=L7 |
| TEMP_2_A0 | OTHERS | BUS | 7 | 5 | 5 | 10 | 5 | 14 | 6 | 10 | 12 | 12 | 12 | 12 |  | 50 Ohms | TOP=L2:L3=L2/L4:L6=L5/L7:BOTTOM=L7 |
| TEMP_2_A0 | OTHERS | BUS | 8 | 4.75 | 5 | 10 | 5 | 14 | 6 | 9.5 | 12 | 12 | 12 | 12 |  | 50 Ohms | TOP=L2:L3=L2/L4:L6=L5/L7:BOTTOM=L7 |
| TEMP_2_A1 | OTHERS | BUS | 1 | 4.75 | 5 | 10 | 5 | 14 | 6 | 9.5 | 12 | 12 | 12 | 12 |  | 50 Ohms | TOP=L2:L3=L2/L4:L6=L5/L7:BOTTOM=L7 |
| TEMP_2_A1 | OTHERS | BUS | 2 | 5 | 5 | 10 | 5 | 14 | 6 | 10 | 12 | 12 | 12 | 12 |  | 50 Ohms | TOP=L2:L3=L2/L4:L6=L5/L7:BOTTOM=L7 |
| TEMP_2_A1 | OTHERS | BUS | 3 | 5 | 5 | 10 | 5 | 14 | 6 | 10 | 12 | 12 | 12 | 12 |  | 50 Ohms | TOP=L2:L3=L2/L4:L6=L5/L7:BOTTOM=L7 |
| TEMP_2_A1 | OTHERS | BUS | 4 | 5 | 5 | 10 | 5 | 14 | 6 | 10 | 12 | 12 | 12 | 12 |  | 50 Ohms | TOP=L2:L3=L2/L4:L6=L5/L7:BOTTOM=L7 |
| TEMP_2_A1 | OTHERS | BUS | 5 | 5 | 5 | 10 | 5 | 14 | 6 | 10 | 12 | 12 | 12 | 12 |  | 50 Ohms | TOP=L2:L3=L2/L4:L6=L5/L7:BOTTOM=L7 |
| TEMP_2_A1 | OTHERS | BUS | 6 | 5 | 5 | 10 | 5 | 14 | 6 | 10 | 12 | 12 | 12 | 12 |  | 50 Ohms | TOP=L2:L3=L2/L4:L6=L5/L7:BOTTOM=L7 |
| TEMP_2_A1 | OTHERS | BUS | 7 | 5 | 5 | 10 | 5 | 14 | 6 | 10 | 12 | 12 | 12 | 12 |  | 50 Ohms | TOP=L2:L3=L2/L4:L6=L5/L7:BOTTOM=L7 |
| TEMP_2_A1 | OTHERS | BUS | 8 | 4.75 | 5 | 10 | 5 | 14 | 6 | 9.5 | 12 | 12 | 12 | 12 |  | 50 Ohms | TOP=L2:L3=L2/L4:L6=L5/L7:BOTTOM=L7 |
| TEMP_2_A2 | OTHERS | BUS | 1 | 4.75 | 5 | 10 | 5 | 14 | 6 | 9.5 | 12 | 12 | 12 | 12 |  | 50 Ohms | TOP=L2:L3=L2/L4:L6=L5/L7:BOTTOM=L7 |
| TEMP_2_A2 | OTHERS | BUS | 2 | 5 | 5 | 10 | 5 | 14 | 6 | 10 | 12 | 12 | 12 | 12 |  | 50 Ohms | TOP=L2:L3=L2/L4:L6=L5/L7:BOTTOM=L7 |
| TEMP_2_A2 | OTHERS | BUS | 3 | 5 | 5 | 10 | 5 | 14 | 6 | 10 | 12 | 12 | 12 | 12 |  | 50 Ohms | TOP=L2:L3=L2/L4:L6=L5/L7:BOTTOM=L7 |
| TEMP_2_A2 | OTHERS | BUS | 4 | 5 | 5 | 10 | 5 | 14 | 6 | 10 | 12 | 12 | 12 | 12 |  | 50 Ohms | TOP=L2:L3=L2/L4:L6=L5/L7:BOTTOM=L7 |
| TEMP_2_A2 | OTHERS | BUS | 5 | 5 | 5 | 10 | 5 | 14 | 6 | 10 | 12 | 12 | 12 | 12 |  | 50 Ohms | TOP=L2:L3=L2/L4:L6=L5/L7:BOTTOM=L7 |
| TEMP_2_A2 | OTHERS | BUS | 6 | 5 | 5 | 10 | 5 | 14 | 6 | 10 | 12 | 12 | 12 | 12 |  | 50 Ohms | TOP=L2:L3=L2/L4:L6=L5/L7:BOTTOM=L7 |
| TEMP_2_A2 | OTHERS | BUS | 7 | 5 | 5 | 10 | 5 | 14 | 6 | 10 | 12 | 12 | 12 | 12 |  | 50 Ohms | TOP=L2:L3=L2/L4:L6=L5/L7:BOTTOM=L7 |
| TEMP_2_A2 | OTHERS | BUS | 8 | 4.75 | 5 | 10 | 5 | 14 | 6 | 9.5 | 12 | 12 | 12 | 12 |  | 50 Ohms | TOP=L2:L3=L2/L4:L6=L5/L7:BOTTOM=L7 |
| TEMP_2_ALERT | OTHERS | BUS | 1 | 4.75 | 5 | 10 | 5 | 14 | 6 | 9.5 | 12 | 12 | 12 | 12 |  | 50 Ohms | TOP=L2:L3=L2/L4:L6=L5/L7:BOTTOM=L7 |
| TEMP_2_ALERT | OTHERS | BUS | 2 | 5 | 5 | 10 | 5 | 14 | 6 | 10 | 12 | 12 | 12 | 12 |  | 50 Ohms | TOP=L2:L3=L2/L4:L6=L5/L7:BOTTOM=L7 |
| TEMP_2_ALERT | OTHERS | BUS | 3 | 5 | 5 | 10 | 5 | 14 | 6 | 10 | 12 | 12 | 12 | 12 |  | 50 Ohms | TOP=L2:L3=L2/L4:L6=L5/L7:BOTTOM=L7 |
| TEMP_2_ALERT | OTHERS | BUS | 4 | 5 | 5 | 10 | 5 | 14 | 6 | 10 | 12 | 12 | 12 | 12 |  | 50 Ohms | TOP=L2:L3=L2/L4:L6=L5/L7:BOTTOM=L7 |
| TEMP_2_ALERT | OTHERS | BUS | 5 | 5 | 5 | 10 | 5 | 14 | 6 | 10 | 12 | 12 | 12 | 12 |  | 50 Ohms | TOP=L2:L3=L2/L4:L6=L5/L7:BOTTOM=L7 |
| TEMP_2_ALERT | OTHERS | BUS | 6 | 5 | 5 | 10 | 5 | 14 | 6 | 10 | 12 | 12 | 12 | 12 |  | 50 Ohms | TOP=L2:L3=L2/L4:L6=L5/L7:BOTTOM=L7 |
| TEMP_2_ALERT | OTHERS | BUS | 7 | 5 | 5 | 10 | 5 | 14 | 6 | 10 | 12 | 12 | 12 | 12 |  | 50 Ohms | TOP=L2:L3=L2/L4:L6=L5/L7:BOTTOM=L7 |
| TEMP_2_ALERT | OTHERS | BUS | 8 | 4.75 | 5 | 10 | 5 | 14 | 6 | 9.5 | 12 | 12 | 12 | 12 |  | 50 Ohms | TOP=L2:L3=L2/L4:L6=L5/L7:BOTTOM=L7 |
| TEMP_3_A0 | OTHERS | BUS | 1 | 4.75 | 5 | 10 | 5 | 14 | 6 | 9.5 | 12 | 12 | 12 | 12 |  | 50 Ohms | TOP=L2:L3=L2/L4:L6=L5/L7:BOTTOM=L7 |
| TEMP_3_A0 | OTHERS | BUS | 2 | 5 | 5 | 10 | 5 | 14 | 6 | 10 | 12 | 12 | 12 | 12 |  | 50 Ohms | TOP=L2:L3=L2/L4:L6=L5/L7:BOTTOM=L7 |
| TEMP_3_A0 | OTHERS | BUS | 3 | 5 | 5 | 10 | 5 | 14 | 6 | 10 | 12 | 12 | 12 | 12 |  | 50 Ohms | TOP=L2:L3=L2/L4:L6=L5/L7:BOTTOM=L7 |
| TEMP_3_A0 | OTHERS | BUS | 4 | 5 | 5 | 10 | 5 | 14 | 6 | 10 | 12 | 12 | 12 | 12 |  | 50 Ohms | TOP=L2:L3=L2/L4:L6=L5/L7:BOTTOM=L7 |
| TEMP_3_A0 | OTHERS | BUS | 5 | 5 | 5 | 10 | 5 | 14 | 6 | 10 | 12 | 12 | 12 | 12 |  | 50 Ohms | TOP=L2:L3=L2/L4:L6=L5/L7:BOTTOM=L7 |
| TEMP_3_A0 | OTHERS | BUS | 6 | 5 | 5 | 10 | 5 | 14 | 6 | 10 | 12 | 12 | 12 | 12 |  | 50 Ohms | TOP=L2:L3=L2/L4:L6=L5/L7:BOTTOM=L7 |
| TEMP_3_A0 | OTHERS | BUS | 7 | 5 | 5 | 10 | 5 | 14 | 6 | 10 | 12 | 12 | 12 | 12 |  | 50 Ohms | TOP=L2:L3=L2/L4:L6=L5/L7:BOTTOM=L7 |
| TEMP_3_A0 | OTHERS | BUS | 8 | 4.75 | 5 | 10 | 5 | 14 | 6 | 9.5 | 12 | 12 | 12 | 12 |  | 50 Ohms | TOP=L2:L3=L2/L4:L6=L5/L7:BOTTOM=L7 |
| TEMP_3_A1 | OTHERS | BUS | 1 | 4.75 | 5 | 10 | 5 | 14 | 6 | 9.5 | 12 | 12 | 12 | 12 |  | 50 Ohms | TOP=L2:L3=L2/L4:L6=L5/L7:BOTTOM=L7 |
| TEMP_3_A1 | OTHERS | BUS | 2 | 5 | 5 | 10 | 5 | 14 | 6 | 10 | 12 | 12 | 12 | 12 |  | 50 Ohms | TOP=L2:L3=L2/L4:L6=L5/L7:BOTTOM=L7 |
| TEMP_3_A1 | OTHERS | BUS | 3 | 5 | 5 | 10 | 5 | 14 | 6 | 10 | 12 | 12 | 12 | 12 |  | 50 Ohms | TOP=L2:L3=L2/L4:L6=L5/L7:BOTTOM=L7 |
| TEMP_3_A1 | OTHERS | BUS | 4 | 5 | 5 | 10 | 5 | 14 | 6 | 10 | 12 | 12 | 12 | 12 |  | 50 Ohms | TOP=L2:L3=L2/L4:L6=L5/L7:BOTTOM=L7 |
| TEMP_3_A1 | OTHERS | BUS | 5 | 5 | 5 | 10 | 5 | 14 | 6 | 10 | 12 | 12 | 12 | 12 |  | 50 Ohms | TOP=L2:L3=L2/L4:L6=L5/L7:BOTTOM=L7 |
| TEMP_3_A1 | OTHERS | BUS | 6 | 5 | 5 | 10 | 5 | 14 | 6 | 10 | 12 | 12 | 12 | 12 |  | 50 Ohms | TOP=L2:L3=L2/L4:L6=L5/L7:BOTTOM=L7 |
| TEMP_3_A1 | OTHERS | BUS | 7 | 5 | 5 | 10 | 5 | 14 | 6 | 10 | 12 | 12 | 12 | 12 |  | 50 Ohms | TOP=L2:L3=L2/L4:L6=L5/L7:BOTTOM=L7 |
| TEMP_3_A1 | OTHERS | BUS | 8 | 4.75 | 5 | 10 | 5 | 14 | 6 | 9.5 | 12 | 12 | 12 | 12 |  | 50 Ohms | TOP=L2:L3=L2/L4:L6=L5/L7:BOTTOM=L7 |
| TEMP_3_A2 | OTHERS | BUS | 1 | 4.75 | 5 | 10 | 5 | 14 | 6 | 9.5 | 12 | 12 | 12 | 12 |  | 50 Ohms | TOP=L2:L3=L2/L4:L6=L5/L7:BOTTOM=L7 |
| TEMP_3_A2 | OTHERS | BUS | 2 | 5 | 5 | 10 | 5 | 14 | 6 | 10 | 12 | 12 | 12 | 12 |  | 50 Ohms | TOP=L2:L3=L2/L4:L6=L5/L7:BOTTOM=L7 |
| TEMP_3_A2 | OTHERS | BUS | 3 | 5 | 5 | 10 | 5 | 14 | 6 | 10 | 12 | 12 | 12 | 12 |  | 50 Ohms | TOP=L2:L3=L2/L4:L6=L5/L7:BOTTOM=L7 |
| TEMP_3_A2 | OTHERS | BUS | 4 | 5 | 5 | 10 | 5 | 14 | 6 | 10 | 12 | 12 | 12 | 12 |  | 50 Ohms | TOP=L2:L3=L2/L4:L6=L5/L7:BOTTOM=L7 |
| TEMP_3_A2 | OTHERS | BUS | 5 | 5 | 5 | 10 | 5 | 14 | 6 | 10 | 12 | 12 | 12 | 12 |  | 50 Ohms | TOP=L2:L3=L2/L4:L6=L5/L7:BOTTOM=L7 |
| TEMP_3_A2 | OTHERS | BUS | 6 | 5 | 5 | 10 | 5 | 14 | 6 | 10 | 12 | 12 | 12 | 12 |  | 50 Ohms | TOP=L2:L3=L2/L4:L6=L5/L7:BOTTOM=L7 |
| TEMP_3_A2 | OTHERS | BUS | 7 | 5 | 5 | 10 | 5 | 14 | 6 | 10 | 12 | 12 | 12 | 12 |  | 50 Ohms | TOP=L2:L3=L2/L4:L6=L5/L7:BOTTOM=L7 |
| TEMP_3_A2 | OTHERS | BUS | 8 | 4.75 | 5 | 10 | 5 | 14 | 6 | 9.5 | 12 | 12 | 12 | 12 |  | 50 Ohms | TOP=L2:L3=L2/L4:L6=L5/L7:BOTTOM=L7 |
| TEMP_3_ALERT | OTHERS | BUS | 1 | 4.75 | 5 | 10 | 5 | 14 | 6 | 9.5 | 12 | 12 | 12 | 12 |  | 50 Ohms | TOP=L2:L3=L2/L4:L6=L5/L7:BOTTOM=L7 |
| TEMP_3_ALERT | OTHERS | BUS | 2 | 5 | 5 | 10 | 5 | 14 | 6 | 10 | 12 | 12 | 12 | 12 |  | 50 Ohms | TOP=L2:L3=L2/L4:L6=L5/L7:BOTTOM=L7 |
| TEMP_3_ALERT | OTHERS | BUS | 3 | 5 | 5 | 10 | 5 | 14 | 6 | 10 | 12 | 12 | 12 | 12 |  | 50 Ohms | TOP=L2:L3=L2/L4:L6=L5/L7:BOTTOM=L7 |
| TEMP_3_ALERT | OTHERS | BUS | 4 | 5 | 5 | 10 | 5 | 14 | 6 | 10 | 12 | 12 | 12 | 12 |  | 50 Ohms | TOP=L2:L3=L2/L4:L6=L5/L7:BOTTOM=L7 |
| TEMP_3_ALERT | OTHERS | BUS | 5 | 5 | 5 | 10 | 5 | 14 | 6 | 10 | 12 | 12 | 12 | 12 |  | 50 Ohms | TOP=L2:L3=L2/L4:L6=L5/L7:BOTTOM=L7 |
| TEMP_3_ALERT | OTHERS | BUS | 6 | 5 | 5 | 10 | 5 | 14 | 6 | 10 | 12 | 12 | 12 | 12 |  | 50 Ohms | TOP=L2:L3=L2/L4:L6=L5/L7:BOTTOM=L7 |
| TEMP_3_ALERT | OTHERS | BUS | 7 | 5 | 5 | 10 | 5 | 14 | 6 | 10 | 12 | 12 | 12 | 12 |  | 50 Ohms | TOP=L2:L3=L2/L4:L6=L5/L7:BOTTOM=L7 |
| TEMP_3_ALERT | OTHERS | BUS | 8 | 4.75 | 5 | 10 | 5 | 14 | 6 | 9.5 | 12 | 12 | 12 | 12 |  | 50 Ohms | TOP=L2:L3=L2/L4:L6=L5/L7:BOTTOM=L7 |
| THERM_BASE_R | OTHERS | BUS | 1 | 4.75 | 5 | 10 | 5 | 14 | 6 | 9.5 | 12 | 12 | 12 | 12 |  | 50 Ohms | TOP=L2:L3=L2/L4:L6=L5/L7:BOTTOM=L7 |
| THERM_BASE_R | OTHERS | BUS | 2 | 5 | 5 | 10 | 5 | 14 | 6 | 10 | 12 | 12 | 12 | 12 |  | 50 Ohms | TOP=L2:L3=L2/L4:L6=L5/L7:BOTTOM=L7 |
| THERM_BASE_R | OTHERS | BUS | 3 | 5 | 5 | 10 | 5 | 14 | 6 | 10 | 12 | 12 | 12 | 12 |  | 50 Ohms | TOP=L2:L3=L2/L4:L6=L5/L7:BOTTOM=L7 |
| THERM_BASE_R | OTHERS | BUS | 4 | 5 | 5 | 10 | 5 | 14 | 6 | 10 | 12 | 12 | 12 | 12 |  | 50 Ohms | TOP=L2:L3=L2/L4:L6=L5/L7:BOTTOM=L7 |
| THERM_BASE_R | OTHERS | BUS | 5 | 5 | 5 | 10 | 5 | 14 | 6 | 10 | 12 | 12 | 12 | 12 |  | 50 Ohms | TOP=L2:L3=L2/L4:L6=L5/L7:BOTTOM=L7 |
| THERM_BASE_R | OTHERS | BUS | 6 | 5 | 5 | 10 | 5 | 14 | 6 | 10 | 12 | 12 | 12 | 12 |  | 50 Ohms | TOP=L2:L3=L2/L4:L6=L5/L7:BOTTOM=L7 |
| THERM_BASE_R | OTHERS | BUS | 7 | 5 | 5 | 10 | 5 | 14 | 6 | 10 | 12 | 12 | 12 | 12 |  | 50 Ohms | TOP=L2:L3=L2/L4:L6=L5/L7:BOTTOM=L7 |
| THERM_BASE_R | OTHERS | BUS | 8 | 4.75 | 5 | 10 | 5 | 14 | 6 | 9.5 | 12 | 12 | 12 | 12 |  | 50 Ohms | TOP=L2:L3=L2/L4:L6=L5/L7:BOTTOM=L7 |
| THERM_EMIT_R | OTHERS | BUS | 1 | 4.75 | 5 | 10 | 5 | 14 | 6 | 9.5 | 12 | 12 | 12 | 12 |  | 50 Ohms | TOP=L2:L3=L2/L4:L6=L5/L7:BOTTOM=L7 |
| THERM_EMIT_R | OTHERS | BUS | 2 | 5 | 5 | 10 | 5 | 14 | 6 | 10 | 12 | 12 | 12 | 12 |  | 50 Ohms | TOP=L2:L3=L2/L4:L6=L5/L7:BOTTOM=L7 |
| THERM_EMIT_R | OTHERS | BUS | 3 | 5 | 5 | 10 | 5 | 14 | 6 | 10 | 12 | 12 | 12 | 12 |  | 50 Ohms | TOP=L2:L3=L2/L4:L6=L5/L7:BOTTOM=L7 |
| THERM_EMIT_R | OTHERS | BUS | 4 | 5 | 5 | 10 | 5 | 14 | 6 | 10 | 12 | 12 | 12 | 12 |  | 50 Ohms | TOP=L2:L3=L2/L4:L6=L5/L7:BOTTOM=L7 |
| THERM_EMIT_R | OTHERS | BUS | 5 | 5 | 5 | 10 | 5 | 14 | 6 | 10 | 12 | 12 | 12 | 12 |  | 50 Ohms | TOP=L2:L3=L2/L4:L6=L5/L7:BOTTOM=L7 |
| THERM_EMIT_R | OTHERS | BUS | 6 | 5 | 5 | 10 | 5 | 14 | 6 | 10 | 12 | 12 | 12 | 12 |  | 50 Ohms | TOP=L2:L3=L2/L4:L6=L5/L7:BOTTOM=L7 |
| THERM_EMIT_R | OTHERS | BUS | 7 | 5 | 5 | 10 | 5 | 14 | 6 | 10 | 12 | 12 | 12 | 12 |  | 50 Ohms | TOP=L2:L3=L2/L4:L6=L5/L7:BOTTOM=L7 |
| THERM_EMIT_R | OTHERS | BUS | 8 | 4.75 | 5 | 10 | 5 | 14 | 6 | 9.5 | 12 | 12 | 12 | 12 |  | 50 Ohms | TOP=L2:L3=L2/L4:L6=L5/L7:BOTTOM=L7 |
| TP_BMC_GPIOJ4 | OTHERS | BUS | 1 | 4.75 | 5 | 10 | 5 | 14 | 6 | 9.5 | 12 | 12 | 12 | 12 |  | 50 Ohms | TOP=L2:L3=L2/L4:L6=L5/L7:BOTTOM=L7 |
| TP_BMC_GPIOJ4 | OTHERS | BUS | 2 | 5 | 5 | 10 | 5 | 14 | 6 | 10 | 12 | 12 | 12 | 12 |  | 50 Ohms | TOP=L2:L3=L2/L4:L6=L5/L7:BOTTOM=L7 |
| TP_BMC_GPIOJ4 | OTHERS | BUS | 3 | 5 | 5 | 10 | 5 | 14 | 6 | 10 | 12 | 12 | 12 | 12 |  | 50 Ohms | TOP=L2:L3=L2/L4:L6=L5/L7:BOTTOM=L7 |
| TP_BMC_GPIOJ4 | OTHERS | BUS | 4 | 5 | 5 | 10 | 5 | 14 | 6 | 10 | 12 | 12 | 12 | 12 |  | 50 Ohms | TOP=L2:L3=L2/L4:L6=L5/L7:BOTTOM=L7 |
| TP_BMC_GPIOJ4 | OTHERS | BUS | 5 | 5 | 5 | 10 | 5 | 14 | 6 | 10 | 12 | 12 | 12 | 12 |  | 50 Ohms | TOP=L2:L3=L2/L4:L6=L5/L7:BOTTOM=L7 |
| TP_BMC_GPIOJ4 | OTHERS | BUS | 6 | 5 | 5 | 10 | 5 | 14 | 6 | 10 | 12 | 12 | 12 | 12 |  | 50 Ohms | TOP=L2:L3=L2/L4:L6=L5/L7:BOTTOM=L7 |
| TP_BMC_GPIOJ4 | OTHERS | BUS | 7 | 5 | 5 | 10 | 5 | 14 | 6 | 10 | 12 | 12 | 12 | 12 |  | 50 Ohms | TOP=L2:L3=L2/L4:L6=L5/L7:BOTTOM=L7 |
| TP_BMC_GPIOJ4 | OTHERS | BUS | 8 | 4.75 | 5 | 10 | 5 | 14 | 6 | 9.5 | 12 | 12 | 12 | 12 |  | 50 Ohms | TOP=L2:L3=L2/L4:L6=L5/L7:BOTTOM=L7 |
| TP_BMC_GPIOJ5 | OTHERS | BUS | 1 | 4.75 | 5 | 10 | 5 | 14 | 6 | 9.5 | 12 | 12 | 12 | 12 |  | 50 Ohms | TOP=L2:L3=L2/L4:L6=L5/L7:BOTTOM=L7 |
| TP_BMC_GPIOJ5 | OTHERS | BUS | 2 | 5 | 5 | 10 | 5 | 14 | 6 | 10 | 12 | 12 | 12 | 12 |  | 50 Ohms | TOP=L2:L3=L2/L4:L6=L5/L7:BOTTOM=L7 |
| TP_BMC_GPIOJ5 | OTHERS | BUS | 3 | 5 | 5 | 10 | 5 | 14 | 6 | 10 | 12 | 12 | 12 | 12 |  | 50 Ohms | TOP=L2:L3=L2/L4:L6=L5/L7:BOTTOM=L7 |
| TP_BMC_GPIOJ5 | OTHERS | BUS | 4 | 5 | 5 | 10 | 5 | 14 | 6 | 10 | 12 | 12 | 12 | 12 |  | 50 Ohms | TOP=L2:L3=L2/L4:L6=L5/L7:BOTTOM=L7 |
| TP_BMC_GPIOJ5 | OTHERS | BUS | 5 | 5 | 5 | 10 | 5 | 14 | 6 | 10 | 12 | 12 | 12 | 12 |  | 50 Ohms | TOP=L2:L3=L2/L4:L6=L5/L7:BOTTOM=L7 |
| TP_BMC_GPIOJ5 | OTHERS | BUS | 6 | 5 | 5 | 10 | 5 | 14 | 6 | 10 | 12 | 12 | 12 | 12 |  | 50 Ohms | TOP=L2:L3=L2/L4:L6=L5/L7:BOTTOM=L7 |
| TP_BMC_GPIOJ5 | OTHERS | BUS | 7 | 5 | 5 | 10 | 5 | 14 | 6 | 10 | 12 | 12 | 12 | 12 |  | 50 Ohms | TOP=L2:L3=L2/L4:L6=L5/L7:BOTTOM=L7 |
| TP_BMC_GPIOJ5 | OTHERS | BUS | 8 | 4.75 | 5 | 10 | 5 | 14 | 6 | 9.5 | 12 | 12 | 12 | 12 |  | 50 Ohms | TOP=L2:L3=L2/L4:L6=L5/L7:BOTTOM=L7 |
| TP_BMC_GPIOJ6 | OTHERS | BUS | 1 | 4.75 | 5 | 10 | 5 | 14 | 6 | 9.5 | 12 | 12 | 12 | 12 |  | 50 Ohms | TOP=L2:L3=L2/L4:L6=L5/L7:BOTTOM=L7 |
| TP_BMC_GPIOJ6 | OTHERS | BUS | 2 | 5 | 5 | 10 | 5 | 14 | 6 | 10 | 12 | 12 | 12 | 12 |  | 50 Ohms | TOP=L2:L3=L2/L4:L6=L5/L7:BOTTOM=L7 |
| TP_BMC_GPIOJ6 | OTHERS | BUS | 3 | 5 | 5 | 10 | 5 | 14 | 6 | 10 | 12 | 12 | 12 | 12 |  | 50 Ohms | TOP=L2:L3=L2/L4:L6=L5/L7:BOTTOM=L7 |
| TP_BMC_GPIOJ6 | OTHERS | BUS | 4 | 5 | 5 | 10 | 5 | 14 | 6 | 10 | 12 | 12 | 12 | 12 |  | 50 Ohms | TOP=L2:L3=L2/L4:L6=L5/L7:BOTTOM=L7 |
| TP_BMC_GPIOJ6 | OTHERS | BUS | 5 | 5 | 5 | 10 | 5 | 14 | 6 | 10 | 12 | 12 | 12 | 12 |  | 50 Ohms | TOP=L2:L3=L2/L4:L6=L5/L7:BOTTOM=L7 |
| TP_BMC_GPIOJ6 | OTHERS | BUS | 6 | 5 | 5 | 10 | 5 | 14 | 6 | 10 | 12 | 12 | 12 | 12 |  | 50 Ohms | TOP=L2:L3=L2/L4:L6=L5/L7:BOTTOM=L7 |
| TP_BMC_GPIOJ6 | OTHERS | BUS | 7 | 5 | 5 | 10 | 5 | 14 | 6 | 10 | 12 | 12 | 12 | 12 |  | 50 Ohms | TOP=L2:L3=L2/L4:L6=L5/L7:BOTTOM=L7 |
| TP_BMC_GPIOJ6 | OTHERS | BUS | 8 | 4.75 | 5 | 10 | 5 | 14 | 6 | 9.5 | 12 | 12 | 12 | 12 |  | 50 Ohms | TOP=L2:L3=L2/L4:L6=L5/L7:BOTTOM=L7 |
| TP_BMC_GPIOJ7 | OTHERS | BUS | 1 | 4.75 | 5 | 10 | 5 | 14 | 6 | 9.5 | 12 | 12 | 12 | 12 |  | 50 Ohms | TOP=L2:L3=L2/L4:L6=L5/L7:BOTTOM=L7 |
| TP_BMC_GPIOJ7 | OTHERS | BUS | 2 | 5 | 5 | 10 | 5 | 14 | 6 | 10 | 12 | 12 | 12 | 12 |  | 50 Ohms | TOP=L2:L3=L2/L4:L6=L5/L7:BOTTOM=L7 |
| TP_BMC_GPIOJ7 | OTHERS | BUS | 3 | 5 | 5 | 10 | 5 | 14 | 6 | 10 | 12 | 12 | 12 | 12 |  | 50 Ohms | TOP=L2:L3=L2/L4:L6=L5/L7:BOTTOM=L7 |
| TP_BMC_GPIOJ7 | OTHERS | BUS | 4 | 5 | 5 | 10 | 5 | 14 | 6 | 10 | 12 | 12 | 12 | 12 |  | 50 Ohms | TOP=L2:L3=L2/L4:L6=L5/L7:BOTTOM=L7 |
| TP_BMC_GPIOJ7 | OTHERS | BUS | 5 | 5 | 5 | 10 | 5 | 14 | 6 | 10 | 12 | 12 | 12 | 12 |  | 50 Ohms | TOP=L2:L3=L2/L4:L6=L5/L7:BOTTOM=L7 |
| TP_BMC_GPIOJ7 | OTHERS | BUS | 6 | 5 | 5 | 10 | 5 | 14 | 6 | 10 | 12 | 12 | 12 | 12 |  | 50 Ohms | TOP=L2:L3=L2/L4:L6=L5/L7:BOTTOM=L7 |
| TP_BMC_GPIOJ7 | OTHERS | BUS | 7 | 5 | 5 | 10 | 5 | 14 | 6 | 10 | 12 | 12 | 12 | 12 |  | 50 Ohms | TOP=L2:L3=L2/L4:L6=L5/L7:BOTTOM=L7 |
| TP_BMC_GPIOJ7 | OTHERS | BUS | 8 | 4.75 | 5 | 10 | 5 | 14 | 6 | 9.5 | 12 | 12 | 12 | 12 |  | 50 Ohms | TOP=L2:L3=L2/L4:L6=L5/L7:BOTTOM=L7 |
| TP_BMC0_LPC_LAD0 | OTHERS | BUS | 1 | 4.75 | 5 | 10 | 5 | 14 | 6 | 9.5 | 12 | 12 | 12 | 12 |  | 50 Ohms | TOP=L2:L3=L2/L4:L6=L5/L7:BOTTOM=L7 |
| TP_BMC0_LPC_LAD0 | OTHERS | BUS | 2 | 5 | 5 | 10 | 5 | 14 | 6 | 10 | 12 | 12 | 12 | 12 |  | 50 Ohms | TOP=L2:L3=L2/L4:L6=L5/L7:BOTTOM=L7 |
| TP_BMC0_LPC_LAD0 | OTHERS | BUS | 3 | 5 | 5 | 10 | 5 | 14 | 6 | 10 | 12 | 12 | 12 | 12 |  | 50 Ohms | TOP=L2:L3=L2/L4:L6=L5/L7:BOTTOM=L7 |
| TP_BMC0_LPC_LAD0 | OTHERS | BUS | 4 | 5 | 5 | 10 | 5 | 14 | 6 | 10 | 12 | 12 | 12 | 12 |  | 50 Ohms | TOP=L2:L3=L2/L4:L6=L5/L7:BOTTOM=L7 |
| TP_BMC0_LPC_LAD0 | OTHERS | BUS | 5 | 5 | 5 | 10 | 5 | 14 | 6 | 10 | 12 | 12 | 12 | 12 |  | 50 Ohms | TOP=L2:L3=L2/L4:L6=L5/L7:BOTTOM=L7 |
| TP_BMC0_LPC_LAD0 | OTHERS | BUS | 6 | 5 | 5 | 10 | 5 | 14 | 6 | 10 | 12 | 12 | 12 | 12 |  | 50 Ohms | TOP=L2:L3=L2/L4:L6=L5/L7:BOTTOM=L7 |
| TP_BMC0_LPC_LAD0 | OTHERS | BUS | 7 | 5 | 5 | 10 | 5 | 14 | 6 | 10 | 12 | 12 | 12 | 12 |  | 50 Ohms | TOP=L2:L3=L2/L4:L6=L5/L7:BOTTOM=L7 |
| TP_BMC0_LPC_LAD0 | OTHERS | BUS | 8 | 4.75 | 5 | 10 | 5 | 14 | 6 | 9.5 | 12 | 12 | 12 | 12 |  | 50 Ohms | TOP=L2:L3=L2/L4:L6=L5/L7:BOTTOM=L7 |
| TP_BMC0_LPC_LAD1 | OTHERS | BUS | 1 | 4.75 | 5 | 10 | 5 | 14 | 6 | 9.5 | 12 | 12 | 12 | 12 |  | 50 Ohms | TOP=L2:L3=L2/L4:L6=L5/L7:BOTTOM=L7 |
| TP_BMC0_LPC_LAD1 | OTHERS | BUS | 2 | 5 | 5 | 10 | 5 | 14 | 6 | 10 | 12 | 12 | 12 | 12 |  | 50 Ohms | TOP=L2:L3=L2/L4:L6=L5/L7:BOTTOM=L7 |
| TP_BMC0_LPC_LAD1 | OTHERS | BUS | 3 | 5 | 5 | 10 | 5 | 14 | 6 | 10 | 12 | 12 | 12 | 12 |  | 50 Ohms | TOP=L2:L3=L2/L4:L6=L5/L7:BOTTOM=L7 |
| TP_BMC0_LPC_LAD1 | OTHERS | BUS | 4 | 5 | 5 | 10 | 5 | 14 | 6 | 10 | 12 | 12 | 12 | 12 |  | 50 Ohms | TOP=L2:L3=L2/L4:L6=L5/L7:BOTTOM=L7 |
| TP_BMC0_LPC_LAD1 | OTHERS | BUS | 5 | 5 | 5 | 10 | 5 | 14 | 6 | 10 | 12 | 12 | 12 | 12 |  | 50 Ohms | TOP=L2:L3=L2/L4:L6=L5/L7:BOTTOM=L7 |
| TP_BMC0_LPC_LAD1 | OTHERS | BUS | 6 | 5 | 5 | 10 | 5 | 14 | 6 | 10 | 12 | 12 | 12 | 12 |  | 50 Ohms | TOP=L2:L3=L2/L4:L6=L5/L7:BOTTOM=L7 |
| TP_BMC0_LPC_LAD1 | OTHERS | BUS | 7 | 5 | 5 | 10 | 5 | 14 | 6 | 10 | 12 | 12 | 12 | 12 |  | 50 Ohms | TOP=L2:L3=L2/L4:L6=L5/L7:BOTTOM=L7 |
| TP_BMC0_LPC_LAD1 | OTHERS | BUS | 8 | 4.75 | 5 | 10 | 5 | 14 | 6 | 9.5 | 12 | 12 | 12 | 12 |  | 50 Ohms | TOP=L2:L3=L2/L4:L6=L5/L7:BOTTOM=L7 |
| TP_BMC0_LPC_LAD2 | OTHERS | BUS | 1 | 4.75 | 5 | 10 | 5 | 14 | 6 | 9.5 | 12 | 12 | 12 | 12 |  | 50 Ohms | TOP=L2:L3=L2/L4:L6=L5/L7:BOTTOM=L7 |
| TP_BMC0_LPC_LAD2 | OTHERS | BUS | 2 | 5 | 5 | 10 | 5 | 14 | 6 | 10 | 12 | 12 | 12 | 12 |  | 50 Ohms | TOP=L2:L3=L2/L4:L6=L5/L7:BOTTOM=L7 |
| TP_BMC0_LPC_LAD2 | OTHERS | BUS | 3 | 5 | 5 | 10 | 5 | 14 | 6 | 10 | 12 | 12 | 12 | 12 |  | 50 Ohms | TOP=L2:L3=L2/L4:L6=L5/L7:BOTTOM=L7 |
| TP_BMC0_LPC_LAD2 | OTHERS | BUS | 4 | 5 | 5 | 10 | 5 | 14 | 6 | 10 | 12 | 12 | 12 | 12 |  | 50 Ohms | TOP=L2:L3=L2/L4:L6=L5/L7:BOTTOM=L7 |
| TP_BMC0_LPC_LAD2 | OTHERS | BUS | 5 | 5 | 5 | 10 | 5 | 14 | 6 | 10 | 12 | 12 | 12 | 12 |  | 50 Ohms | TOP=L2:L3=L2/L4:L6=L5/L7:BOTTOM=L7 |
| TP_BMC0_LPC_LAD2 | OTHERS | BUS | 6 | 5 | 5 | 10 | 5 | 14 | 6 | 10 | 12 | 12 | 12 | 12 |  | 50 Ohms | TOP=L2:L3=L2/L4:L6=L5/L7:BOTTOM=L7 |
| TP_BMC0_LPC_LAD2 | OTHERS | BUS | 7 | 5 | 5 | 10 | 5 | 14 | 6 | 10 | 12 | 12 | 12 | 12 |  | 50 Ohms | TOP=L2:L3=L2/L4:L6=L5/L7:BOTTOM=L7 |
| TP_BMC0_LPC_LAD2 | OTHERS | BUS | 8 | 4.75 | 5 | 10 | 5 | 14 | 6 | 9.5 | 12 | 12 | 12 | 12 |  | 50 Ohms | TOP=L2:L3=L2/L4:L6=L5/L7:BOTTOM=L7 |
| TP_BMC0_LPC_LAD3 | OTHERS | BUS | 1 | 4.75 | 5 | 10 | 5 | 14 | 6 | 9.5 | 12 | 12 | 12 | 12 |  | 50 Ohms | TOP=L2:L3=L2/L4:L6=L5/L7:BOTTOM=L7 |
| TP_BMC0_LPC_LAD3 | OTHERS | BUS | 2 | 5 | 5 | 10 | 5 | 14 | 6 | 10 | 12 | 12 | 12 | 12 |  | 50 Ohms | TOP=L2:L3=L2/L4:L6=L5/L7:BOTTOM=L7 |
| TP_BMC0_LPC_LAD3 | OTHERS | BUS | 3 | 5 | 5 | 10 | 5 | 14 | 6 | 10 | 12 | 12 | 12 | 12 |  | 50 Ohms | TOP=L2:L3=L2/L4:L6=L5/L7:BOTTOM=L7 |
| TP_BMC0_LPC_LAD3 | OTHERS | BUS | 4 | 5 | 5 | 10 | 5 | 14 | 6 | 10 | 12 | 12 | 12 | 12 |  | 50 Ohms | TOP=L2:L3=L2/L4:L6=L5/L7:BOTTOM=L7 |
| TP_BMC0_LPC_LAD3 | OTHERS | BUS | 5 | 5 | 5 | 10 | 5 | 14 | 6 | 10 | 12 | 12 | 12 | 12 |  | 50 Ohms | TOP=L2:L3=L2/L4:L6=L5/L7:BOTTOM=L7 |
| TP_BMC0_LPC_LAD3 | OTHERS | BUS | 6 | 5 | 5 | 10 | 5 | 14 | 6 | 10 | 12 | 12 | 12 | 12 |  | 50 Ohms | TOP=L2:L3=L2/L4:L6=L5/L7:BOTTOM=L7 |
| TP_BMC0_LPC_LAD3 | OTHERS | BUS | 7 | 5 | 5 | 10 | 5 | 14 | 6 | 10 | 12 | 12 | 12 | 12 |  | 50 Ohms | TOP=L2:L3=L2/L4:L6=L5/L7:BOTTOM=L7 |
| TP_BMC0_LPC_LAD3 | OTHERS | BUS | 8 | 4.75 | 5 | 10 | 5 | 14 | 6 | 9.5 | 12 | 12 | 12 | 12 |  | 50 Ohms | TOP=L2:L3=L2/L4:L6=L5/L7:BOTTOM=L7 |
| TP_GPIOA3 | OTHERS | BUS | 1 | 4.75 | 5 | 10 | 5 | 14 | 6 | 9.5 | 12 | 12 | 12 | 12 |  | 50 Ohms | TOP=L2:L3=L2/L4:L6=L5/L7:BOTTOM=L7 |
| TP_GPIOA3 | OTHERS | BUS | 2 | 5 | 5 | 10 | 5 | 14 | 6 | 10 | 12 | 12 | 12 | 12 |  | 50 Ohms | TOP=L2:L3=L2/L4:L6=L5/L7:BOTTOM=L7 |
| TP_GPIOA3 | OTHERS | BUS | 3 | 5 | 5 | 10 | 5 | 14 | 6 | 10 | 12 | 12 | 12 | 12 |  | 50 Ohms | TOP=L2:L3=L2/L4:L6=L5/L7:BOTTOM=L7 |
| TP_GPIOA3 | OTHERS | BUS | 4 | 5 | 5 | 10 | 5 | 14 | 6 | 10 | 12 | 12 | 12 | 12 |  | 50 Ohms | TOP=L2:L3=L2/L4:L6=L5/L7:BOTTOM=L7 |
| TP_GPIOA3 | OTHERS | BUS | 5 | 5 | 5 | 10 | 5 | 14 | 6 | 10 | 12 | 12 | 12 | 12 |  | 50 Ohms | TOP=L2:L3=L2/L4:L6=L5/L7:BOTTOM=L7 |
| TP_GPIOA3 | OTHERS | BUS | 6 | 5 | 5 | 10 | 5 | 14 | 6 | 10 | 12 | 12 | 12 | 12 |  | 50 Ohms | TOP=L2:L3=L2/L4:L6=L5/L7:BOTTOM=L7 |
| TP_GPIOA3 | OTHERS | BUS | 7 | 5 | 5 | 10 | 5 | 14 | 6 | 10 | 12 | 12 | 12 | 12 |  | 50 Ohms | TOP=L2:L3=L2/L4:L6=L5/L7:BOTTOM=L7 |
| TP_GPIOA3 | OTHERS | BUS | 8 | 4.75 | 5 | 10 | 5 | 14 | 6 | 9.5 | 12 | 12 | 12 | 12 |  | 50 Ohms | TOP=L2:L3=L2/L4:L6=L5/L7:BOTTOM=L7 |
| TP_GPIOA6 | OTHERS | BUS | 1 | 4.75 | 5 | 10 | 5 | 14 | 6 | 9.5 | 12 | 12 | 12 | 12 |  | 50 Ohms | TOP=L2:L3=L2/L4:L6=L5/L7:BOTTOM=L7 |
| TP_GPIOA6 | OTHERS | BUS | 2 | 5 | 5 | 10 | 5 | 14 | 6 | 10 | 12 | 12 | 12 | 12 |  | 50 Ohms | TOP=L2:L3=L2/L4:L6=L5/L7:BOTTOM=L7 |
| TP_GPIOA6 | OTHERS | BUS | 3 | 5 | 5 | 10 | 5 | 14 | 6 | 10 | 12 | 12 | 12 | 12 |  | 50 Ohms | TOP=L2:L3=L2/L4:L6=L5/L7:BOTTOM=L7 |
| TP_GPIOA6 | OTHERS | BUS | 4 | 5 | 5 | 10 | 5 | 14 | 6 | 10 | 12 | 12 | 12 | 12 |  | 50 Ohms | TOP=L2:L3=L2/L4:L6=L5/L7:BOTTOM=L7 |
| TP_GPIOA6 | OTHERS | BUS | 5 | 5 | 5 | 10 | 5 | 14 | 6 | 10 | 12 | 12 | 12 | 12 |  | 50 Ohms | TOP=L2:L3=L2/L4:L6=L5/L7:BOTTOM=L7 |
| TP_GPIOA6 | OTHERS | BUS | 6 | 5 | 5 | 10 | 5 | 14 | 6 | 10 | 12 | 12 | 12 | 12 |  | 50 Ohms | TOP=L2:L3=L2/L4:L6=L5/L7:BOTTOM=L7 |
| TP_GPIOA6 | OTHERS | BUS | 7 | 5 | 5 | 10 | 5 | 14 | 6 | 10 | 12 | 12 | 12 | 12 |  | 50 Ohms | TOP=L2:L3=L2/L4:L6=L5/L7:BOTTOM=L7 |
| TP_GPIOA6 | OTHERS | BUS | 8 | 4.75 | 5 | 10 | 5 | 14 | 6 | 9.5 | 12 | 12 | 12 | 12 |  | 50 Ohms | TOP=L2:L3=L2/L4:L6=L5/L7:BOTTOM=L7 |
| TP_GPIOA7 | OTHERS | BUS | 1 | 4.75 | 5 | 10 | 5 | 14 | 6 | 9.5 | 12 | 12 | 12 | 12 |  | 50 Ohms | TOP=L2:L3=L2/L4:L6=L5/L7:BOTTOM=L7 |
| TP_GPIOA7 | OTHERS | BUS | 2 | 5 | 5 | 10 | 5 | 14 | 6 | 10 | 12 | 12 | 12 | 12 |  | 50 Ohms | TOP=L2:L3=L2/L4:L6=L5/L7:BOTTOM=L7 |
| TP_GPIOA7 | OTHERS | BUS | 3 | 5 | 5 | 10 | 5 | 14 | 6 | 10 | 12 | 12 | 12 | 12 |  | 50 Ohms | TOP=L2:L3=L2/L4:L6=L5/L7:BOTTOM=L7 |
| TP_GPIOA7 | OTHERS | BUS | 4 | 5 | 5 | 10 | 5 | 14 | 6 | 10 | 12 | 12 | 12 | 12 |  | 50 Ohms | TOP=L2:L3=L2/L4:L6=L5/L7:BOTTOM=L7 |
| TP_GPIOA7 | OTHERS | BUS | 5 | 5 | 5 | 10 | 5 | 14 | 6 | 10 | 12 | 12 | 12 | 12 |  | 50 Ohms | TOP=L2:L3=L2/L4:L6=L5/L7:BOTTOM=L7 |
| TP_GPIOA7 | OTHERS | BUS | 6 | 5 | 5 | 10 | 5 | 14 | 6 | 10 | 12 | 12 | 12 | 12 |  | 50 Ohms | TOP=L2:L3=L2/L4:L6=L5/L7:BOTTOM=L7 |
| TP_GPIOA7 | OTHERS | BUS | 7 | 5 | 5 | 10 | 5 | 14 | 6 | 10 | 12 | 12 | 12 | 12 |  | 50 Ohms | TOP=L2:L3=L2/L4:L6=L5/L7:BOTTOM=L7 |
| TP_GPIOA7 | OTHERS | BUS | 8 | 4.75 | 5 | 10 | 5 | 14 | 6 | 9.5 | 12 | 12 | 12 | 12 |  | 50 Ohms | TOP=L2:L3=L2/L4:L6=L5/L7:BOTTOM=L7 |
| TP_GPIOB2 | OTHERS | BUS | 1 | 4.75 | 5 | 10 | 5 | 14 | 6 | 9.5 | 12 | 12 | 12 | 12 |  | 50 Ohms | TOP=L2:L3=L2/L4:L6=L5/L7:BOTTOM=L7 |
| TP_GPIOB2 | OTHERS | BUS | 2 | 5 | 5 | 10 | 5 | 14 | 6 | 10 | 12 | 12 | 12 | 12 |  | 50 Ohms | TOP=L2:L3=L2/L4:L6=L5/L7:BOTTOM=L7 |
| TP_GPIOB2 | OTHERS | BUS | 3 | 5 | 5 | 10 | 5 | 14 | 6 | 10 | 12 | 12 | 12 | 12 |  | 50 Ohms | TOP=L2:L3=L2/L4:L6=L5/L7:BOTTOM=L7 |
| TP_GPIOB2 | OTHERS | BUS | 4 | 5 | 5 | 10 | 5 | 14 | 6 | 10 | 12 | 12 | 12 | 12 |  | 50 Ohms | TOP=L2:L3=L2/L4:L6=L5/L7:BOTTOM=L7 |
| TP_GPIOB2 | OTHERS | BUS | 5 | 5 | 5 | 10 | 5 | 14 | 6 | 10 | 12 | 12 | 12 | 12 |  | 50 Ohms | TOP=L2:L3=L2/L4:L6=L5/L7:BOTTOM=L7 |
| TP_GPIOB2 | OTHERS | BUS | 6 | 5 | 5 | 10 | 5 | 14 | 6 | 10 | 12 | 12 | 12 | 12 |  | 50 Ohms | TOP=L2:L3=L2/L4:L6=L5/L7:BOTTOM=L7 |
| TP_GPIOB2 | OTHERS | BUS | 7 | 5 | 5 | 10 | 5 | 14 | 6 | 10 | 12 | 12 | 12 | 12 |  | 50 Ohms | TOP=L2:L3=L2/L4:L6=L5/L7:BOTTOM=L7 |
| TP_GPIOB2 | OTHERS | BUS | 8 | 4.75 | 5 | 10 | 5 | 14 | 6 | 9.5 | 12 | 12 | 12 | 12 |  | 50 Ohms | TOP=L2:L3=L2/L4:L6=L5/L7:BOTTOM=L7 |
| TP_GPIOB5 | OTHERS | BUS | 1 | 4.75 | 5 | 10 | 5 | 14 | 6 | 9.5 | 12 | 12 | 12 | 12 |  | 50 Ohms | TOP=L2:L3=L2/L4:L6=L5/L7:BOTTOM=L7 |
| TP_GPIOB5 | OTHERS | BUS | 2 | 5 | 5 | 10 | 5 | 14 | 6 | 10 | 12 | 12 | 12 | 12 |  | 50 Ohms | TOP=L2:L3=L2/L4:L6=L5/L7:BOTTOM=L7 |
| TP_GPIOB5 | OTHERS | BUS | 3 | 5 | 5 | 10 | 5 | 14 | 6 | 10 | 12 | 12 | 12 | 12 |  | 50 Ohms | TOP=L2:L3=L2/L4:L6=L5/L7:BOTTOM=L7 |
| TP_GPIOB5 | OTHERS | BUS | 4 | 5 | 5 | 10 | 5 | 14 | 6 | 10 | 12 | 12 | 12 | 12 |  | 50 Ohms | TOP=L2:L3=L2/L4:L6=L5/L7:BOTTOM=L7 |
| TP_GPIOB5 | OTHERS | BUS | 5 | 5 | 5 | 10 | 5 | 14 | 6 | 10 | 12 | 12 | 12 | 12 |  | 50 Ohms | TOP=L2:L3=L2/L4:L6=L5/L7:BOTTOM=L7 |
| TP_GPIOB5 | OTHERS | BUS | 6 | 5 | 5 | 10 | 5 | 14 | 6 | 10 | 12 | 12 | 12 | 12 |  | 50 Ohms | TOP=L2:L3=L2/L4:L6=L5/L7:BOTTOM=L7 |
| TP_GPIOB5 | OTHERS | BUS | 7 | 5 | 5 | 10 | 5 | 14 | 6 | 10 | 12 | 12 | 12 | 12 |  | 50 Ohms | TOP=L2:L3=L2/L4:L6=L5/L7:BOTTOM=L7 |
| TP_GPIOB5 | OTHERS | BUS | 8 | 4.75 | 5 | 10 | 5 | 14 | 6 | 9.5 | 12 | 12 | 12 | 12 |  | 50 Ohms | TOP=L2:L3=L2/L4:L6=L5/L7:BOTTOM=L7 |
| TP_GPIOB6 | OTHERS | BUS | 1 | 4.75 | 5 | 10 | 5 | 14 | 6 | 9.5 | 12 | 12 | 12 | 12 |  | 50 Ohms | TOP=L2:L3=L2/L4:L6=L5/L7:BOTTOM=L7 |
| TP_GPIOB6 | OTHERS | BUS | 2 | 5 | 5 | 10 | 5 | 14 | 6 | 10 | 12 | 12 | 12 | 12 |  | 50 Ohms | TOP=L2:L3=L2/L4:L6=L5/L7:BOTTOM=L7 |
| TP_GPIOB6 | OTHERS | BUS | 3 | 5 | 5 | 10 | 5 | 14 | 6 | 10 | 12 | 12 | 12 | 12 |  | 50 Ohms | TOP=L2:L3=L2/L4:L6=L5/L7:BOTTOM=L7 |
| TP_GPIOB6 | OTHERS | BUS | 4 | 5 | 5 | 10 | 5 | 14 | 6 | 10 | 12 | 12 | 12 | 12 |  | 50 Ohms | TOP=L2:L3=L2/L4:L6=L5/L7:BOTTOM=L7 |
| TP_GPIOB6 | OTHERS | BUS | 5 | 5 | 5 | 10 | 5 | 14 | 6 | 10 | 12 | 12 | 12 | 12 |  | 50 Ohms | TOP=L2:L3=L2/L4:L6=L5/L7:BOTTOM=L7 |
| TP_GPIOB6 | OTHERS | BUS | 6 | 5 | 5 | 10 | 5 | 14 | 6 | 10 | 12 | 12 | 12 | 12 |  | 50 Ohms | TOP=L2:L3=L2/L4:L6=L5/L7:BOTTOM=L7 |
| TP_GPIOB6 | OTHERS | BUS | 7 | 5 | 5 | 10 | 5 | 14 | 6 | 10 | 12 | 12 | 12 | 12 |  | 50 Ohms | TOP=L2:L3=L2/L4:L6=L5/L7:BOTTOM=L7 |
| TP_GPIOB6 | OTHERS | BUS | 8 | 4.75 | 5 | 10 | 5 | 14 | 6 | 9.5 | 12 | 12 | 12 | 12 |  | 50 Ohms | TOP=L2:L3=L2/L4:L6=L5/L7:BOTTOM=L7 |
| TP_GPIOD0 | OTHERS | BUS | 1 | 4.75 | 5 | 10 | 5 | 14 | 6 | 9.5 | 12 | 12 | 12 | 12 |  | 50 Ohms | TOP=L2:L3=L2/L4:L6=L5/L7:BOTTOM=L7 |
| TP_GPIOD0 | OTHERS | BUS | 2 | 5 | 5 | 10 | 5 | 14 | 6 | 10 | 12 | 12 | 12 | 12 |  | 50 Ohms | TOP=L2:L3=L2/L4:L6=L5/L7:BOTTOM=L7 |
| TP_GPIOD0 | OTHERS | BUS | 3 | 5 | 5 | 10 | 5 | 14 | 6 | 10 | 12 | 12 | 12 | 12 |  | 50 Ohms | TOP=L2:L3=L2/L4:L6=L5/L7:BOTTOM=L7 |
| TP_GPIOD0 | OTHERS | BUS | 4 | 5 | 5 | 10 | 5 | 14 | 6 | 10 | 12 | 12 | 12 | 12 |  | 50 Ohms | TOP=L2:L3=L2/L4:L6=L5/L7:BOTTOM=L7 |
| TP_GPIOD0 | OTHERS | BUS | 5 | 5 | 5 | 10 | 5 | 14 | 6 | 10 | 12 | 12 | 12 | 12 |  | 50 Ohms | TOP=L2:L3=L2/L4:L6=L5/L7:BOTTOM=L7 |
| TP_GPIOD0 | OTHERS | BUS | 6 | 5 | 5 | 10 | 5 | 14 | 6 | 10 | 12 | 12 | 12 | 12 |  | 50 Ohms | TOP=L2:L3=L2/L4:L6=L5/L7:BOTTOM=L7 |
| TP_GPIOD0 | OTHERS | BUS | 7 | 5 | 5 | 10 | 5 | 14 | 6 | 10 | 12 | 12 | 12 | 12 |  | 50 Ohms | TOP=L2:L3=L2/L4:L6=L5/L7:BOTTOM=L7 |
| TP_GPIOD0 | OTHERS | BUS | 8 | 4.75 | 5 | 10 | 5 | 14 | 6 | 9.5 | 12 | 12 | 12 | 12 |  | 50 Ohms | TOP=L2:L3=L2/L4:L6=L5/L7:BOTTOM=L7 |
| TP_GPIOD1 | OTHERS | BUS | 1 | 4.75 | 5 | 10 | 5 | 14 | 6 | 9.5 | 12 | 12 | 12 | 12 |  | 50 Ohms | TOP=L2:L3=L2/L4:L6=L5/L7:BOTTOM=L7 |
| TP_GPIOD1 | OTHERS | BUS | 2 | 5 | 5 | 10 | 5 | 14 | 6 | 10 | 12 | 12 | 12 | 12 |  | 50 Ohms | TOP=L2:L3=L2/L4:L6=L5/L7:BOTTOM=L7 |
| TP_GPIOD1 | OTHERS | BUS | 3 | 5 | 5 | 10 | 5 | 14 | 6 | 10 | 12 | 12 | 12 | 12 |  | 50 Ohms | TOP=L2:L3=L2/L4:L6=L5/L7:BOTTOM=L7 |
| TP_GPIOD1 | OTHERS | BUS | 4 | 5 | 5 | 10 | 5 | 14 | 6 | 10 | 12 | 12 | 12 | 12 |  | 50 Ohms | TOP=L2:L3=L2/L4:L6=L5/L7:BOTTOM=L7 |
| TP_GPIOD1 | OTHERS | BUS | 5 | 5 | 5 | 10 | 5 | 14 | 6 | 10 | 12 | 12 | 12 | 12 |  | 50 Ohms | TOP=L2:L3=L2/L4:L6=L5/L7:BOTTOM=L7 |
| TP_GPIOD1 | OTHERS | BUS | 6 | 5 | 5 | 10 | 5 | 14 | 6 | 10 | 12 | 12 | 12 | 12 |  | 50 Ohms | TOP=L2:L3=L2/L4:L6=L5/L7:BOTTOM=L7 |
| TP_GPIOD1 | OTHERS | BUS | 7 | 5 | 5 | 10 | 5 | 14 | 6 | 10 | 12 | 12 | 12 | 12 |  | 50 Ohms | TOP=L2:L3=L2/L4:L6=L5/L7:BOTTOM=L7 |
| TP_GPIOD1 | OTHERS | BUS | 8 | 4.75 | 5 | 10 | 5 | 14 | 6 | 9.5 | 12 | 12 | 12 | 12 |  | 50 Ohms | TOP=L2:L3=L2/L4:L6=L5/L7:BOTTOM=L7 |
| TP_GPIOD2 | OTHERS | BUS | 1 | 4.75 | 5 | 10 | 5 | 14 | 6 | 9.5 | 12 | 12 | 12 | 12 |  | 50 Ohms | TOP=L2:L3=L2/L4:L6=L5/L7:BOTTOM=L7 |
| TP_GPIOD2 | OTHERS | BUS | 2 | 5 | 5 | 10 | 5 | 14 | 6 | 10 | 12 | 12 | 12 | 12 |  | 50 Ohms | TOP=L2:L3=L2/L4:L6=L5/L7:BOTTOM=L7 |
| TP_GPIOD2 | OTHERS | BUS | 3 | 5 | 5 | 10 | 5 | 14 | 6 | 10 | 12 | 12 | 12 | 12 |  | 50 Ohms | TOP=L2:L3=L2/L4:L6=L5/L7:BOTTOM=L7 |
| TP_GPIOD2 | OTHERS | BUS | 4 | 5 | 5 | 10 | 5 | 14 | 6 | 10 | 12 | 12 | 12 | 12 |  | 50 Ohms | TOP=L2:L3=L2/L4:L6=L5/L7:BOTTOM=L7 |
| TP_GPIOD2 | OTHERS | BUS | 5 | 5 | 5 | 10 | 5 | 14 | 6 | 10 | 12 | 12 | 12 | 12 |  | 50 Ohms | TOP=L2:L3=L2/L4:L6=L5/L7:BOTTOM=L7 |
| TP_GPIOD2 | OTHERS | BUS | 6 | 5 | 5 | 10 | 5 | 14 | 6 | 10 | 12 | 12 | 12 | 12 |  | 50 Ohms | TOP=L2:L3=L2/L4:L6=L5/L7:BOTTOM=L7 |
| TP_GPIOD2 | OTHERS | BUS | 7 | 5 | 5 | 10 | 5 | 14 | 6 | 10 | 12 | 12 | 12 | 12 |  | 50 Ohms | TOP=L2:L3=L2/L4:L6=L5/L7:BOTTOM=L7 |
| TP_GPIOD2 | OTHERS | BUS | 8 | 4.75 | 5 | 10 | 5 | 14 | 6 | 9.5 | 12 | 12 | 12 | 12 |  | 50 Ohms | TOP=L2:L3=L2/L4:L6=L5/L7:BOTTOM=L7 |
| TP_GPIOD3 | OTHERS | BUS | 1 | 4.75 | 5 | 10 | 5 | 14 | 6 | 9.5 | 12 | 12 | 12 | 12 |  | 50 Ohms | TOP=L2:L3=L2/L4:L6=L5/L7:BOTTOM=L7 |
| TP_GPIOD3 | OTHERS | BUS | 2 | 5 | 5 | 10 | 5 | 14 | 6 | 10 | 12 | 12 | 12 | 12 |  | 50 Ohms | TOP=L2:L3=L2/L4:L6=L5/L7:BOTTOM=L7 |
| TP_GPIOD3 | OTHERS | BUS | 3 | 5 | 5 | 10 | 5 | 14 | 6 | 10 | 12 | 12 | 12 | 12 |  | 50 Ohms | TOP=L2:L3=L2/L4:L6=L5/L7:BOTTOM=L7 |
| TP_GPIOD3 | OTHERS | BUS | 4 | 5 | 5 | 10 | 5 | 14 | 6 | 10 | 12 | 12 | 12 | 12 |  | 50 Ohms | TOP=L2:L3=L2/L4:L6=L5/L7:BOTTOM=L7 |
| TP_GPIOD3 | OTHERS | BUS | 5 | 5 | 5 | 10 | 5 | 14 | 6 | 10 | 12 | 12 | 12 | 12 |  | 50 Ohms | TOP=L2:L3=L2/L4:L6=L5/L7:BOTTOM=L7 |
| TP_GPIOD3 | OTHERS | BUS | 6 | 5 | 5 | 10 | 5 | 14 | 6 | 10 | 12 | 12 | 12 | 12 |  | 50 Ohms | TOP=L2:L3=L2/L4:L6=L5/L7:BOTTOM=L7 |
| TP_GPIOD3 | OTHERS | BUS | 7 | 5 | 5 | 10 | 5 | 14 | 6 | 10 | 12 | 12 | 12 | 12 |  | 50 Ohms | TOP=L2:L3=L2/L4:L6=L5/L7:BOTTOM=L7 |
| TP_GPIOD3 | OTHERS | BUS | 8 | 4.75 | 5 | 10 | 5 | 14 | 6 | 9.5 | 12 | 12 | 12 | 12 |  | 50 Ohms | TOP=L2:L3=L2/L4:L6=L5/L7:BOTTOM=L7 |
| TP_GPIOD4 | OTHERS | BUS | 1 | 4.75 | 5 | 10 | 5 | 14 | 6 | 9.5 | 12 | 12 | 12 | 12 |  | 50 Ohms | TOP=L2:L3=L2/L4:L6=L5/L7:BOTTOM=L7 |
| TP_GPIOD4 | OTHERS | BUS | 2 | 5 | 5 | 10 | 5 | 14 | 6 | 10 | 12 | 12 | 12 | 12 |  | 50 Ohms | TOP=L2:L3=L2/L4:L6=L5/L7:BOTTOM=L7 |
| TP_GPIOD4 | OTHERS | BUS | 3 | 5 | 5 | 10 | 5 | 14 | 6 | 10 | 12 | 12 | 12 | 12 |  | 50 Ohms | TOP=L2:L3=L2/L4:L6=L5/L7:BOTTOM=L7 |
| TP_GPIOD4 | OTHERS | BUS | 4 | 5 | 5 | 10 | 5 | 14 | 6 | 10 | 12 | 12 | 12 | 12 |  | 50 Ohms | TOP=L2:L3=L2/L4:L6=L5/L7:BOTTOM=L7 |
| TP_GPIOD4 | OTHERS | BUS | 5 | 5 | 5 | 10 | 5 | 14 | 6 | 10 | 12 | 12 | 12 | 12 |  | 50 Ohms | TOP=L2:L3=L2/L4:L6=L5/L7:BOTTOM=L7 |
| TP_GPIOD4 | OTHERS | BUS | 6 | 5 | 5 | 10 | 5 | 14 | 6 | 10 | 12 | 12 | 12 | 12 |  | 50 Ohms | TOP=L2:L3=L2/L4:L6=L5/L7:BOTTOM=L7 |
| TP_GPIOD4 | OTHERS | BUS | 7 | 5 | 5 | 10 | 5 | 14 | 6 | 10 | 12 | 12 | 12 | 12 |  | 50 Ohms | TOP=L2:L3=L2/L4:L6=L5/L7:BOTTOM=L7 |
| TP_GPIOD4 | OTHERS | BUS | 8 | 4.75 | 5 | 10 | 5 | 14 | 6 | 9.5 | 12 | 12 | 12 | 12 |  | 50 Ohms | TOP=L2:L3=L2/L4:L6=L5/L7:BOTTOM=L7 |
| TP_GPIOD5 | OTHERS | BUS | 1 | 4.75 | 5 | 10 | 5 | 14 | 6 | 9.5 | 12 | 12 | 12 | 12 |  | 50 Ohms | TOP=L2:L3=L2/L4:L6=L5/L7:BOTTOM=L7 |
| TP_GPIOD5 | OTHERS | BUS | 2 | 5 | 5 | 10 | 5 | 14 | 6 | 10 | 12 | 12 | 12 | 12 |  | 50 Ohms | TOP=L2:L3=L2/L4:L6=L5/L7:BOTTOM=L7 |
| TP_GPIOD5 | OTHERS | BUS | 3 | 5 | 5 | 10 | 5 | 14 | 6 | 10 | 12 | 12 | 12 | 12 |  | 50 Ohms | TOP=L2:L3=L2/L4:L6=L5/L7:BOTTOM=L7 |
| TP_GPIOD5 | OTHERS | BUS | 4 | 5 | 5 | 10 | 5 | 14 | 6 | 10 | 12 | 12 | 12 | 12 |  | 50 Ohms | TOP=L2:L3=L2/L4:L6=L5/L7:BOTTOM=L7 |
| TP_GPIOD5 | OTHERS | BUS | 5 | 5 | 5 | 10 | 5 | 14 | 6 | 10 | 12 | 12 | 12 | 12 |  | 50 Ohms | TOP=L2:L3=L2/L4:L6=L5/L7:BOTTOM=L7 |
| TP_GPIOD5 | OTHERS | BUS | 6 | 5 | 5 | 10 | 5 | 14 | 6 | 10 | 12 | 12 | 12 | 12 |  | 50 Ohms | TOP=L2:L3=L2/L4:L6=L5/L7:BOTTOM=L7 |
| TP_GPIOD5 | OTHERS | BUS | 7 | 5 | 5 | 10 | 5 | 14 | 6 | 10 | 12 | 12 | 12 | 12 |  | 50 Ohms | TOP=L2:L3=L2/L4:L6=L5/L7:BOTTOM=L7 |
| TP_GPIOD5 | OTHERS | BUS | 8 | 4.75 | 5 | 10 | 5 | 14 | 6 | 9.5 | 12 | 12 | 12 | 12 |  | 50 Ohms | TOP=L2:L3=L2/L4:L6=L5/L7:BOTTOM=L7 |
| TP_GPIOD7 | OTHERS | BUS | 1 | 4.75 | 5 | 10 | 5 | 14 | 6 | 9.5 | 12 | 12 | 12 | 12 |  | 50 Ohms | TOP=L2:L3=L2/L4:L6=L5/L7:BOTTOM=L7 |
| TP_GPIOD7 | OTHERS | BUS | 2 | 5 | 5 | 10 | 5 | 14 | 6 | 10 | 12 | 12 | 12 | 12 |  | 50 Ohms | TOP=L2:L3=L2/L4:L6=L5/L7:BOTTOM=L7 |
| TP_GPIOD7 | OTHERS | BUS | 3 | 5 | 5 | 10 | 5 | 14 | 6 | 10 | 12 | 12 | 12 | 12 |  | 50 Ohms | TOP=L2:L3=L2/L4:L6=L5/L7:BOTTOM=L7 |
| TP_GPIOD7 | OTHERS | BUS | 4 | 5 | 5 | 10 | 5 | 14 | 6 | 10 | 12 | 12 | 12 | 12 |  | 50 Ohms | TOP=L2:L3=L2/L4:L6=L5/L7:BOTTOM=L7 |
| TP_GPIOD7 | OTHERS | BUS | 5 | 5 | 5 | 10 | 5 | 14 | 6 | 10 | 12 | 12 | 12 | 12 |  | 50 Ohms | TOP=L2:L3=L2/L4:L6=L5/L7:BOTTOM=L7 |
| TP_GPIOD7 | OTHERS | BUS | 6 | 5 | 5 | 10 | 5 | 14 | 6 | 10 | 12 | 12 | 12 | 12 |  | 50 Ohms | TOP=L2:L3=L2/L4:L6=L5/L7:BOTTOM=L7 |
| TP_GPIOD7 | OTHERS | BUS | 7 | 5 | 5 | 10 | 5 | 14 | 6 | 10 | 12 | 12 | 12 | 12 |  | 50 Ohms | TOP=L2:L3=L2/L4:L6=L5/L7:BOTTOM=L7 |
| TP_GPIOD7 | OTHERS | BUS | 8 | 4.75 | 5 | 10 | 5 | 14 | 6 | 9.5 | 12 | 12 | 12 | 12 |  | 50 Ohms | TOP=L2:L3=L2/L4:L6=L5/L7:BOTTOM=L7 |
| TP_GPIOE1 | OTHERS | BUS | 1 | 4.75 | 5 | 10 | 5 | 14 | 6 | 9.5 | 12 | 12 | 12 | 12 |  | 50 Ohms | TOP=L2:L3=L2/L4:L6=L5/L7:BOTTOM=L7 |
| TP_GPIOE1 | OTHERS | BUS | 2 | 5 | 5 | 10 | 5 | 14 | 6 | 10 | 12 | 12 | 12 | 12 |  | 50 Ohms | TOP=L2:L3=L2/L4:L6=L5/L7:BOTTOM=L7 |
| TP_GPIOE1 | OTHERS | BUS | 3 | 5 | 5 | 10 | 5 | 14 | 6 | 10 | 12 | 12 | 12 | 12 |  | 50 Ohms | TOP=L2:L3=L2/L4:L6=L5/L7:BOTTOM=L7 |
| TP_GPIOE1 | OTHERS | BUS | 4 | 5 | 5 | 10 | 5 | 14 | 6 | 10 | 12 | 12 | 12 | 12 |  | 50 Ohms | TOP=L2:L3=L2/L4:L6=L5/L7:BOTTOM=L7 |
| TP_GPIOE1 | OTHERS | BUS | 5 | 5 | 5 | 10 | 5 | 14 | 6 | 10 | 12 | 12 | 12 | 12 |  | 50 Ohms | TOP=L2:L3=L2/L4:L6=L5/L7:BOTTOM=L7 |
| TP_GPIOE1 | OTHERS | BUS | 6 | 5 | 5 | 10 | 5 | 14 | 6 | 10 | 12 | 12 | 12 | 12 |  | 50 Ohms | TOP=L2:L3=L2/L4:L6=L5/L7:BOTTOM=L7 |
| TP_GPIOE1 | OTHERS | BUS | 7 | 5 | 5 | 10 | 5 | 14 | 6 | 10 | 12 | 12 | 12 | 12 |  | 50 Ohms | TOP=L2:L3=L2/L4:L6=L5/L7:BOTTOM=L7 |
| TP_GPIOE1 | OTHERS | BUS | 8 | 4.75 | 5 | 10 | 5 | 14 | 6 | 9.5 | 12 | 12 | 12 | 12 |  | 50 Ohms | TOP=L2:L3=L2/L4:L6=L5/L7:BOTTOM=L7 |
| TP_GPIOE2 | OTHERS | BUS | 1 | 4.75 | 5 | 10 | 5 | 14 | 6 | 9.5 | 12 | 12 | 12 | 12 |  | 50 Ohms | TOP=L2:L3=L2/L4:L6=L5/L7:BOTTOM=L7 |
| TP_GPIOE2 | OTHERS | BUS | 2 | 5 | 5 | 10 | 5 | 14 | 6 | 10 | 12 | 12 | 12 | 12 |  | 50 Ohms | TOP=L2:L3=L2/L4:L6=L5/L7:BOTTOM=L7 |
| TP_GPIOE2 | OTHERS | BUS | 3 | 5 | 5 | 10 | 5 | 14 | 6 | 10 | 12 | 12 | 12 | 12 |  | 50 Ohms | TOP=L2:L3=L2/L4:L6=L5/L7:BOTTOM=L7 |
| TP_GPIOE2 | OTHERS | BUS | 4 | 5 | 5 | 10 | 5 | 14 | 6 | 10 | 12 | 12 | 12 | 12 |  | 50 Ohms | TOP=L2:L3=L2/L4:L6=L5/L7:BOTTOM=L7 |
| TP_GPIOE2 | OTHERS | BUS | 5 | 5 | 5 | 10 | 5 | 14 | 6 | 10 | 12 | 12 | 12 | 12 |  | 50 Ohms | TOP=L2:L3=L2/L4:L6=L5/L7:BOTTOM=L7 |
| TP_GPIOE2 | OTHERS | BUS | 6 | 5 | 5 | 10 | 5 | 14 | 6 | 10 | 12 | 12 | 12 | 12 |  | 50 Ohms | TOP=L2:L3=L2/L4:L6=L5/L7:BOTTOM=L7 |
| TP_GPIOE2 | OTHERS | BUS | 7 | 5 | 5 | 10 | 5 | 14 | 6 | 10 | 12 | 12 | 12 | 12 |  | 50 Ohms | TOP=L2:L3=L2/L4:L6=L5/L7:BOTTOM=L7 |
| TP_GPIOE2 | OTHERS | BUS | 8 | 4.75 | 5 | 10 | 5 | 14 | 6 | 9.5 | 12 | 12 | 12 | 12 |  | 50 Ohms | TOP=L2:L3=L2/L4:L6=L5/L7:BOTTOM=L7 |
| TP_GPIOE3 | OTHERS | BUS | 1 | 4.75 | 5 | 10 | 5 | 14 | 6 | 9.5 | 12 | 12 | 12 | 12 |  | 50 Ohms | TOP=L2:L3=L2/L4:L6=L5/L7:BOTTOM=L7 |
| TP_GPIOE3 | OTHERS | BUS | 2 | 5 | 5 | 10 | 5 | 14 | 6 | 10 | 12 | 12 | 12 | 12 |  | 50 Ohms | TOP=L2:L3=L2/L4:L6=L5/L7:BOTTOM=L7 |
| TP_GPIOE3 | OTHERS | BUS | 3 | 5 | 5 | 10 | 5 | 14 | 6 | 10 | 12 | 12 | 12 | 12 |  | 50 Ohms | TOP=L2:L3=L2/L4:L6=L5/L7:BOTTOM=L7 |
| TP_GPIOE3 | OTHERS | BUS | 4 | 5 | 5 | 10 | 5 | 14 | 6 | 10 | 12 | 12 | 12 | 12 |  | 50 Ohms | TOP=L2:L3=L2/L4:L6=L5/L7:BOTTOM=L7 |
| TP_GPIOE3 | OTHERS | BUS | 5 | 5 | 5 | 10 | 5 | 14 | 6 | 10 | 12 | 12 | 12 | 12 |  | 50 Ohms | TOP=L2:L3=L2/L4:L6=L5/L7:BOTTOM=L7 |
| TP_GPIOE3 | OTHERS | BUS | 6 | 5 | 5 | 10 | 5 | 14 | 6 | 10 | 12 | 12 | 12 | 12 |  | 50 Ohms | TOP=L2:L3=L2/L4:L6=L5/L7:BOTTOM=L7 |
| TP_GPIOE3 | OTHERS | BUS | 7 | 5 | 5 | 10 | 5 | 14 | 6 | 10 | 12 | 12 | 12 | 12 |  | 50 Ohms | TOP=L2:L3=L2/L4:L6=L5/L7:BOTTOM=L7 |
| TP_GPIOE3 | OTHERS | BUS | 8 | 4.75 | 5 | 10 | 5 | 14 | 6 | 9.5 | 12 | 12 | 12 | 12 |  | 50 Ohms | TOP=L2:L3=L2/L4:L6=L5/L7:BOTTOM=L7 |
| TP_GPIOE6 | OTHERS | BUS | 1 | 4.75 | 5 | 10 | 5 | 14 | 6 | 9.5 | 12 | 12 | 12 | 12 |  | 50 Ohms | TOP=L2:L3=L2/L4:L6=L5/L7:BOTTOM=L7 |
| TP_GPIOE6 | OTHERS | BUS | 2 | 5 | 5 | 10 | 5 | 14 | 6 | 10 | 12 | 12 | 12 | 12 |  | 50 Ohms | TOP=L2:L3=L2/L4:L6=L5/L7:BOTTOM=L7 |
| TP_GPIOE6 | OTHERS | BUS | 3 | 5 | 5 | 10 | 5 | 14 | 6 | 10 | 12 | 12 | 12 | 12 |  | 50 Ohms | TOP=L2:L3=L2/L4:L6=L5/L7:BOTTOM=L7 |
| TP_GPIOE6 | OTHERS | BUS | 4 | 5 | 5 | 10 | 5 | 14 | 6 | 10 | 12 | 12 | 12 | 12 |  | 50 Ohms | TOP=L2:L3=L2/L4:L6=L5/L7:BOTTOM=L7 |
| TP_GPIOE6 | OTHERS | BUS | 5 | 5 | 5 | 10 | 5 | 14 | 6 | 10 | 12 | 12 | 12 | 12 |  | 50 Ohms | TOP=L2:L3=L2/L4:L6=L5/L7:BOTTOM=L7 |
| TP_GPIOE6 | OTHERS | BUS | 6 | 5 | 5 | 10 | 5 | 14 | 6 | 10 | 12 | 12 | 12 | 12 |  | 50 Ohms | TOP=L2:L3=L2/L4:L6=L5/L7:BOTTOM=L7 |
| TP_GPIOE6 | OTHERS | BUS | 7 | 5 | 5 | 10 | 5 | 14 | 6 | 10 | 12 | 12 | 12 | 12 |  | 50 Ohms | TOP=L2:L3=L2/L4:L6=L5/L7:BOTTOM=L7 |
| TP_GPIOE6 | OTHERS | BUS | 8 | 4.75 | 5 | 10 | 5 | 14 | 6 | 9.5 | 12 | 12 | 12 | 12 |  | 50 Ohms | TOP=L2:L3=L2/L4:L6=L5/L7:BOTTOM=L7 |
| TP_GPIOE7 | OTHERS | BUS | 1 | 4.75 | 5 | 10 | 5 | 14 | 6 | 9.5 | 12 | 12 | 12 | 12 |  | 50 Ohms | TOP=L2:L3=L2/L4:L6=L5/L7:BOTTOM=L7 |
| TP_GPIOE7 | OTHERS | BUS | 2 | 5 | 5 | 10 | 5 | 14 | 6 | 10 | 12 | 12 | 12 | 12 |  | 50 Ohms | TOP=L2:L3=L2/L4:L6=L5/L7:BOTTOM=L7 |
| TP_GPIOE7 | OTHERS | BUS | 3 | 5 | 5 | 10 | 5 | 14 | 6 | 10 | 12 | 12 | 12 | 12 |  | 50 Ohms | TOP=L2:L3=L2/L4:L6=L5/L7:BOTTOM=L7 |
| TP_GPIOE7 | OTHERS | BUS | 4 | 5 | 5 | 10 | 5 | 14 | 6 | 10 | 12 | 12 | 12 | 12 |  | 50 Ohms | TOP=L2:L3=L2/L4:L6=L5/L7:BOTTOM=L7 |
| TP_GPIOE7 | OTHERS | BUS | 5 | 5 | 5 | 10 | 5 | 14 | 6 | 10 | 12 | 12 | 12 | 12 |  | 50 Ohms | TOP=L2:L3=L2/L4:L6=L5/L7:BOTTOM=L7 |
| TP_GPIOE7 | OTHERS | BUS | 6 | 5 | 5 | 10 | 5 | 14 | 6 | 10 | 12 | 12 | 12 | 12 |  | 50 Ohms | TOP=L2:L3=L2/L4:L6=L5/L7:BOTTOM=L7 |
| TP_GPIOE7 | OTHERS | BUS | 7 | 5 | 5 | 10 | 5 | 14 | 6 | 10 | 12 | 12 | 12 | 12 |  | 50 Ohms | TOP=L2:L3=L2/L4:L6=L5/L7:BOTTOM=L7 |
| TP_GPIOE7 | OTHERS | BUS | 8 | 4.75 | 5 | 10 | 5 | 14 | 6 | 9.5 | 12 | 12 | 12 | 12 |  | 50 Ohms | TOP=L2:L3=L2/L4:L6=L5/L7:BOTTOM=L7 |
| TP_GPIOH3 | OTHERS | BUS | 1 | 4.75 | 5 | 10 | 5 | 14 | 6 | 9.5 | 12 | 12 | 12 | 12 |  | 50 Ohms | TOP=L2:L3=L2/L4:L6=L5/L7:BOTTOM=L7 |
| TP_GPIOH3 | OTHERS | BUS | 2 | 5 | 5 | 10 | 5 | 14 | 6 | 10 | 12 | 12 | 12 | 12 |  | 50 Ohms | TOP=L2:L3=L2/L4:L6=L5/L7:BOTTOM=L7 |
| TP_GPIOH3 | OTHERS | BUS | 3 | 5 | 5 | 10 | 5 | 14 | 6 | 10 | 12 | 12 | 12 | 12 |  | 50 Ohms | TOP=L2:L3=L2/L4:L6=L5/L7:BOTTOM=L7 |
| TP_GPIOH3 | OTHERS | BUS | 4 | 5 | 5 | 10 | 5 | 14 | 6 | 10 | 12 | 12 | 12 | 12 |  | 50 Ohms | TOP=L2:L3=L2/L4:L6=L5/L7:BOTTOM=L7 |
| TP_GPIOH3 | OTHERS | BUS | 5 | 5 | 5 | 10 | 5 | 14 | 6 | 10 | 12 | 12 | 12 | 12 |  | 50 Ohms | TOP=L2:L3=L2/L4:L6=L5/L7:BOTTOM=L7 |
| TP_GPIOH3 | OTHERS | BUS | 6 | 5 | 5 | 10 | 5 | 14 | 6 | 10 | 12 | 12 | 12 | 12 |  | 50 Ohms | TOP=L2:L3=L2/L4:L6=L5/L7:BOTTOM=L7 |
| TP_GPIOH3 | OTHERS | BUS | 7 | 5 | 5 | 10 | 5 | 14 | 6 | 10 | 12 | 12 | 12 | 12 |  | 50 Ohms | TOP=L2:L3=L2/L4:L6=L5/L7:BOTTOM=L7 |
| TP_GPIOH3 | OTHERS | BUS | 8 | 4.75 | 5 | 10 | 5 | 14 | 6 | 9.5 | 12 | 12 | 12 | 12 |  | 50 Ohms | TOP=L2:L3=L2/L4:L6=L5/L7:BOTTOM=L7 |
| TP_GPIOH4 | OTHERS | BUS | 1 | 4.75 | 5 | 10 | 5 | 14 | 6 | 9.5 | 12 | 12 | 12 | 12 |  | 50 Ohms | TOP=L2:L3=L2/L4:L6=L5/L7:BOTTOM=L7 |
| TP_GPIOH4 | OTHERS | BUS | 2 | 5 | 5 | 10 | 5 | 14 | 6 | 10 | 12 | 12 | 12 | 12 |  | 50 Ohms | TOP=L2:L3=L2/L4:L6=L5/L7:BOTTOM=L7 |
| TP_GPIOH4 | OTHERS | BUS | 3 | 5 | 5 | 10 | 5 | 14 | 6 | 10 | 12 | 12 | 12 | 12 |  | 50 Ohms | TOP=L2:L3=L2/L4:L6=L5/L7:BOTTOM=L7 |
| TP_GPIOH4 | OTHERS | BUS | 4 | 5 | 5 | 10 | 5 | 14 | 6 | 10 | 12 | 12 | 12 | 12 |  | 50 Ohms | TOP=L2:L3=L2/L4:L6=L5/L7:BOTTOM=L7 |
| TP_GPIOH4 | OTHERS | BUS | 5 | 5 | 5 | 10 | 5 | 14 | 6 | 10 | 12 | 12 | 12 | 12 |  | 50 Ohms | TOP=L2:L3=L2/L4:L6=L5/L7:BOTTOM=L7 |
| TP_GPIOH4 | OTHERS | BUS | 6 | 5 | 5 | 10 | 5 | 14 | 6 | 10 | 12 | 12 | 12 | 12 |  | 50 Ohms | TOP=L2:L3=L2/L4:L6=L5/L7:BOTTOM=L7 |
| TP_GPIOH4 | OTHERS | BUS | 7 | 5 | 5 | 10 | 5 | 14 | 6 | 10 | 12 | 12 | 12 | 12 |  | 50 Ohms | TOP=L2:L3=L2/L4:L6=L5/L7:BOTTOM=L7 |
| TP_GPIOH4 | OTHERS | BUS | 8 | 4.75 | 5 | 10 | 5 | 14 | 6 | 9.5 | 12 | 12 | 12 | 12 |  | 50 Ohms | TOP=L2:L3=L2/L4:L6=L5/L7:BOTTOM=L7 |
| TP_GPIOH5 | OTHERS | BUS | 1 | 4.75 | 5 | 10 | 5 | 14 | 6 | 9.5 | 12 | 12 | 12 | 12 |  | 50 Ohms | TOP=L2:L3=L2/L4:L6=L5/L7:BOTTOM=L7 |
| TP_GPIOH5 | OTHERS | BUS | 2 | 5 | 5 | 10 | 5 | 14 | 6 | 10 | 12 | 12 | 12 | 12 |  | 50 Ohms | TOP=L2:L3=L2/L4:L6=L5/L7:BOTTOM=L7 |
| TP_GPIOH5 | OTHERS | BUS | 3 | 5 | 5 | 10 | 5 | 14 | 6 | 10 | 12 | 12 | 12 | 12 |  | 50 Ohms | TOP=L2:L3=L2/L4:L6=L5/L7:BOTTOM=L7 |
| TP_GPIOH5 | OTHERS | BUS | 4 | 5 | 5 | 10 | 5 | 14 | 6 | 10 | 12 | 12 | 12 | 12 |  | 50 Ohms | TOP=L2:L3=L2/L4:L6=L5/L7:BOTTOM=L7 |
| TP_GPIOH5 | OTHERS | BUS | 5 | 5 | 5 | 10 | 5 | 14 | 6 | 10 | 12 | 12 | 12 | 12 |  | 50 Ohms | TOP=L2:L3=L2/L4:L6=L5/L7:BOTTOM=L7 |
| TP_GPIOH5 | OTHERS | BUS | 6 | 5 | 5 | 10 | 5 | 14 | 6 | 10 | 12 | 12 | 12 | 12 |  | 50 Ohms | TOP=L2:L3=L2/L4:L6=L5/L7:BOTTOM=L7 |
| TP_GPIOH5 | OTHERS | BUS | 7 | 5 | 5 | 10 | 5 | 14 | 6 | 10 | 12 | 12 | 12 | 12 |  | 50 Ohms | TOP=L2:L3=L2/L4:L6=L5/L7:BOTTOM=L7 |
| TP_GPIOH5 | OTHERS | BUS | 8 | 4.75 | 5 | 10 | 5 | 14 | 6 | 9.5 | 12 | 12 | 12 | 12 |  | 50 Ohms | TOP=L2:L3=L2/L4:L6=L5/L7:BOTTOM=L7 |
| TP_GPIOH6 | OTHERS | BUS | 1 | 4.75 | 5 | 10 | 5 | 14 | 6 | 9.5 | 12 | 12 | 12 | 12 |  | 50 Ohms | TOP=L2:L3=L2/L4:L6=L5/L7:BOTTOM=L7 |
| TP_GPIOH6 | OTHERS | BUS | 2 | 5 | 5 | 10 | 5 | 14 | 6 | 10 | 12 | 12 | 12 | 12 |  | 50 Ohms | TOP=L2:L3=L2/L4:L6=L5/L7:BOTTOM=L7 |
| TP_GPIOH6 | OTHERS | BUS | 3 | 5 | 5 | 10 | 5 | 14 | 6 | 10 | 12 | 12 | 12 | 12 |  | 50 Ohms | TOP=L2:L3=L2/L4:L6=L5/L7:BOTTOM=L7 |
| TP_GPIOH6 | OTHERS | BUS | 4 | 5 | 5 | 10 | 5 | 14 | 6 | 10 | 12 | 12 | 12 | 12 |  | 50 Ohms | TOP=L2:L3=L2/L4:L6=L5/L7:BOTTOM=L7 |
| TP_GPIOH6 | OTHERS | BUS | 5 | 5 | 5 | 10 | 5 | 14 | 6 | 10 | 12 | 12 | 12 | 12 |  | 50 Ohms | TOP=L2:L3=L2/L4:L6=L5/L7:BOTTOM=L7 |
| TP_GPIOH6 | OTHERS | BUS | 6 | 5 | 5 | 10 | 5 | 14 | 6 | 10 | 12 | 12 | 12 | 12 |  | 50 Ohms | TOP=L2:L3=L2/L4:L6=L5/L7:BOTTOM=L7 |
| TP_GPIOH6 | OTHERS | BUS | 7 | 5 | 5 | 10 | 5 | 14 | 6 | 10 | 12 | 12 | 12 | 12 |  | 50 Ohms | TOP=L2:L3=L2/L4:L6=L5/L7:BOTTOM=L7 |
| TP_GPIOH6 | OTHERS | BUS | 8 | 4.75 | 5 | 10 | 5 | 14 | 6 | 9.5 | 12 | 12 | 12 | 12 |  | 50 Ohms | TOP=L2:L3=L2/L4:L6=L5/L7:BOTTOM=L7 |
| TP_GPIOH7 | OTHERS | BUS | 1 | 4.75 | 5 | 10 | 5 | 14 | 6 | 9.5 | 12 | 12 | 12 | 12 |  | 50 Ohms | TOP=L2:L3=L2/L4:L6=L5/L7:BOTTOM=L7 |
| TP_GPIOH7 | OTHERS | BUS | 2 | 5 | 5 | 10 | 5 | 14 | 6 | 10 | 12 | 12 | 12 | 12 |  | 50 Ohms | TOP=L2:L3=L2/L4:L6=L5/L7:BOTTOM=L7 |
| TP_GPIOH7 | OTHERS | BUS | 3 | 5 | 5 | 10 | 5 | 14 | 6 | 10 | 12 | 12 | 12 | 12 |  | 50 Ohms | TOP=L2:L3=L2/L4:L6=L5/L7:BOTTOM=L7 |
| TP_GPIOH7 | OTHERS | BUS | 4 | 5 | 5 | 10 | 5 | 14 | 6 | 10 | 12 | 12 | 12 | 12 |  | 50 Ohms | TOP=L2:L3=L2/L4:L6=L5/L7:BOTTOM=L7 |
| TP_GPIOH7 | OTHERS | BUS | 5 | 5 | 5 | 10 | 5 | 14 | 6 | 10 | 12 | 12 | 12 | 12 |  | 50 Ohms | TOP=L2:L3=L2/L4:L6=L5/L7:BOTTOM=L7 |
| TP_GPIOH7 | OTHERS | BUS | 6 | 5 | 5 | 10 | 5 | 14 | 6 | 10 | 12 | 12 | 12 | 12 |  | 50 Ohms | TOP=L2:L3=L2/L4:L6=L5/L7:BOTTOM=L7 |
| TP_GPIOH7 | OTHERS | BUS | 7 | 5 | 5 | 10 | 5 | 14 | 6 | 10 | 12 | 12 | 12 | 12 |  | 50 Ohms | TOP=L2:L3=L2/L4:L6=L5/L7:BOTTOM=L7 |
| TP_GPIOH7 | OTHERS | BUS | 8 | 4.75 | 5 | 10 | 5 | 14 | 6 | 9.5 | 12 | 12 | 12 | 12 |  | 50 Ohms | TOP=L2:L3=L2/L4:L6=L5/L7:BOTTOM=L7 |
| TP_GPIOI0 | OTHERS | BUS | 1 | 4.75 | 5 | 10 | 5 | 14 | 6 | 9.5 | 12 | 12 | 12 | 12 |  | 50 Ohms | TOP=L2:L3=L2/L4:L6=L5/L7:BOTTOM=L7 |
| TP_GPIOI0 | OTHERS | BUS | 2 | 5 | 5 | 10 | 5 | 14 | 6 | 10 | 12 | 12 | 12 | 12 |  | 50 Ohms | TOP=L2:L3=L2/L4:L6=L5/L7:BOTTOM=L7 |
| TP_GPIOI0 | OTHERS | BUS | 3 | 5 | 5 | 10 | 5 | 14 | 6 | 10 | 12 | 12 | 12 | 12 |  | 50 Ohms | TOP=L2:L3=L2/L4:L6=L5/L7:BOTTOM=L7 |
| TP_GPIOI0 | OTHERS | BUS | 4 | 5 | 5 | 10 | 5 | 14 | 6 | 10 | 12 | 12 | 12 | 12 |  | 50 Ohms | TOP=L2:L3=L2/L4:L6=L5/L7:BOTTOM=L7 |
| TP_GPIOI0 | OTHERS | BUS | 5 | 5 | 5 | 10 | 5 | 14 | 6 | 10 | 12 | 12 | 12 | 12 |  | 50 Ohms | TOP=L2:L3=L2/L4:L6=L5/L7:BOTTOM=L7 |
| TP_GPIOI0 | OTHERS | BUS | 6 | 5 | 5 | 10 | 5 | 14 | 6 | 10 | 12 | 12 | 12 | 12 |  | 50 Ohms | TOP=L2:L3=L2/L4:L6=L5/L7:BOTTOM=L7 |
| TP_GPIOI0 | OTHERS | BUS | 7 | 5 | 5 | 10 | 5 | 14 | 6 | 10 | 12 | 12 | 12 | 12 |  | 50 Ohms | TOP=L2:L3=L2/L4:L6=L5/L7:BOTTOM=L7 |
| TP_GPIOI0 | OTHERS | BUS | 8 | 4.75 | 5 | 10 | 5 | 14 | 6 | 9.5 | 12 | 12 | 12 | 12 |  | 50 Ohms | TOP=L2:L3=L2/L4:L6=L5/L7:BOTTOM=L7 |
| TP_GPIOI1 | OTHERS | BUS | 1 | 4.75 | 5 | 10 | 5 | 14 | 6 | 9.5 | 12 | 12 | 12 | 12 |  | 50 Ohms | TOP=L2:L3=L2/L4:L6=L5/L7:BOTTOM=L7 |
| TP_GPIOI1 | OTHERS | BUS | 2 | 5 | 5 | 10 | 5 | 14 | 6 | 10 | 12 | 12 | 12 | 12 |  | 50 Ohms | TOP=L2:L3=L2/L4:L6=L5/L7:BOTTOM=L7 |
| TP_GPIOI1 | OTHERS | BUS | 3 | 5 | 5 | 10 | 5 | 14 | 6 | 10 | 12 | 12 | 12 | 12 |  | 50 Ohms | TOP=L2:L3=L2/L4:L6=L5/L7:BOTTOM=L7 |
| TP_GPIOI1 | OTHERS | BUS | 4 | 5 | 5 | 10 | 5 | 14 | 6 | 10 | 12 | 12 | 12 | 12 |  | 50 Ohms | TOP=L2:L3=L2/L4:L6=L5/L7:BOTTOM=L7 |
| TP_GPIOI1 | OTHERS | BUS | 5 | 5 | 5 | 10 | 5 | 14 | 6 | 10 | 12 | 12 | 12 | 12 |  | 50 Ohms | TOP=L2:L3=L2/L4:L6=L5/L7:BOTTOM=L7 |
| TP_GPIOI1 | OTHERS | BUS | 6 | 5 | 5 | 10 | 5 | 14 | 6 | 10 | 12 | 12 | 12 | 12 |  | 50 Ohms | TOP=L2:L3=L2/L4:L6=L5/L7:BOTTOM=L7 |
| TP_GPIOI1 | OTHERS | BUS | 7 | 5 | 5 | 10 | 5 | 14 | 6 | 10 | 12 | 12 | 12 | 12 |  | 50 Ohms | TOP=L2:L3=L2/L4:L6=L5/L7:BOTTOM=L7 |
| TP_GPIOI1 | OTHERS | BUS | 8 | 4.75 | 5 | 10 | 5 | 14 | 6 | 9.5 | 12 | 12 | 12 | 12 |  | 50 Ohms | TOP=L2:L3=L2/L4:L6=L5/L7:BOTTOM=L7 |
| TP_GPIOI2 | OTHERS | BUS | 1 | 4.75 | 5 | 10 | 5 | 14 | 6 | 9.5 | 12 | 12 | 12 | 12 |  | 50 Ohms | TOP=L2:L3=L2/L4:L6=L5/L7:BOTTOM=L7 |
| TP_GPIOI2 | OTHERS | BUS | 2 | 5 | 5 | 10 | 5 | 14 | 6 | 10 | 12 | 12 | 12 | 12 |  | 50 Ohms | TOP=L2:L3=L2/L4:L6=L5/L7:BOTTOM=L7 |
| TP_GPIOI2 | OTHERS | BUS | 3 | 5 | 5 | 10 | 5 | 14 | 6 | 10 | 12 | 12 | 12 | 12 |  | 50 Ohms | TOP=L2:L3=L2/L4:L6=L5/L7:BOTTOM=L7 |
| TP_GPIOI2 | OTHERS | BUS | 4 | 5 | 5 | 10 | 5 | 14 | 6 | 10 | 12 | 12 | 12 | 12 |  | 50 Ohms | TOP=L2:L3=L2/L4:L6=L5/L7:BOTTOM=L7 |
| TP_GPIOI2 | OTHERS | BUS | 5 | 5 | 5 | 10 | 5 | 14 | 6 | 10 | 12 | 12 | 12 | 12 |  | 50 Ohms | TOP=L2:L3=L2/L4:L6=L5/L7:BOTTOM=L7 |
| TP_GPIOI2 | OTHERS | BUS | 6 | 5 | 5 | 10 | 5 | 14 | 6 | 10 | 12 | 12 | 12 | 12 |  | 50 Ohms | TOP=L2:L3=L2/L4:L6=L5/L7:BOTTOM=L7 |
| TP_GPIOI2 | OTHERS | BUS | 7 | 5 | 5 | 10 | 5 | 14 | 6 | 10 | 12 | 12 | 12 | 12 |  | 50 Ohms | TOP=L2:L3=L2/L4:L6=L5/L7:BOTTOM=L7 |
| TP_GPIOI2 | OTHERS | BUS | 8 | 4.75 | 5 | 10 | 5 | 14 | 6 | 9.5 | 12 | 12 | 12 | 12 |  | 50 Ohms | TOP=L2:L3=L2/L4:L6=L5/L7:BOTTOM=L7 |
| TP_GPION5 | OTHERS | BUS | 1 | 4.75 | 5 | 10 | 5 | 14 | 6 | 9.5 | 12 | 12 | 12 | 12 |  | 50 Ohms | TOP=L2:L3=L2/L4:L6=L5/L7:BOTTOM=L7 |
| TP_GPION5 | OTHERS | BUS | 2 | 5 | 5 | 10 | 5 | 14 | 6 | 10 | 12 | 12 | 12 | 12 |  | 50 Ohms | TOP=L2:L3=L2/L4:L6=L5/L7:BOTTOM=L7 |
| TP_GPION5 | OTHERS | BUS | 3 | 5 | 5 | 10 | 5 | 14 | 6 | 10 | 12 | 12 | 12 | 12 |  | 50 Ohms | TOP=L2:L3=L2/L4:L6=L5/L7:BOTTOM=L7 |
| TP_GPION5 | OTHERS | BUS | 4 | 5 | 5 | 10 | 5 | 14 | 6 | 10 | 12 | 12 | 12 | 12 |  | 50 Ohms | TOP=L2:L3=L2/L4:L6=L5/L7:BOTTOM=L7 |
| TP_GPION5 | OTHERS | BUS | 5 | 5 | 5 | 10 | 5 | 14 | 6 | 10 | 12 | 12 | 12 | 12 |  | 50 Ohms | TOP=L2:L3=L2/L4:L6=L5/L7:BOTTOM=L7 |
| TP_GPION5 | OTHERS | BUS | 6 | 5 | 5 | 10 | 5 | 14 | 6 | 10 | 12 | 12 | 12 | 12 |  | 50 Ohms | TOP=L2:L3=L2/L4:L6=L5/L7:BOTTOM=L7 |
| TP_GPION5 | OTHERS | BUS | 7 | 5 | 5 | 10 | 5 | 14 | 6 | 10 | 12 | 12 | 12 | 12 |  | 50 Ohms | TOP=L2:L3=L2/L4:L6=L5/L7:BOTTOM=L7 |
| TP_GPION5 | OTHERS | BUS | 8 | 4.75 | 5 | 10 | 5 | 14 | 6 | 9.5 | 12 | 12 | 12 | 12 |  | 50 Ohms | TOP=L2:L3=L2/L4:L6=L5/L7:BOTTOM=L7 |
| TP_GPIOO0 | OTHERS | BUS | 1 | 4.75 | 5 | 10 | 5 | 14 | 6 | 9.5 | 12 | 12 | 12 | 12 |  | 50 Ohms | TOP=L2:L3=L2/L4:L6=L5/L7:BOTTOM=L7 |
| TP_GPIOO0 | OTHERS | BUS | 2 | 5 | 5 | 10 | 5 | 14 | 6 | 10 | 12 | 12 | 12 | 12 |  | 50 Ohms | TOP=L2:L3=L2/L4:L6=L5/L7:BOTTOM=L7 |
| TP_GPIOO0 | OTHERS | BUS | 3 | 5 | 5 | 10 | 5 | 14 | 6 | 10 | 12 | 12 | 12 | 12 |  | 50 Ohms | TOP=L2:L3=L2/L4:L6=L5/L7:BOTTOM=L7 |
| TP_GPIOO0 | OTHERS | BUS | 4 | 5 | 5 | 10 | 5 | 14 | 6 | 10 | 12 | 12 | 12 | 12 |  | 50 Ohms | TOP=L2:L3=L2/L4:L6=L5/L7:BOTTOM=L7 |
| TP_GPIOO0 | OTHERS | BUS | 5 | 5 | 5 | 10 | 5 | 14 | 6 | 10 | 12 | 12 | 12 | 12 |  | 50 Ohms | TOP=L2:L3=L2/L4:L6=L5/L7:BOTTOM=L7 |
| TP_GPIOO0 | OTHERS | BUS | 6 | 5 | 5 | 10 | 5 | 14 | 6 | 10 | 12 | 12 | 12 | 12 |  | 50 Ohms | TOP=L2:L3=L2/L4:L6=L5/L7:BOTTOM=L7 |
| TP_GPIOO0 | OTHERS | BUS | 7 | 5 | 5 | 10 | 5 | 14 | 6 | 10 | 12 | 12 | 12 | 12 |  | 50 Ohms | TOP=L2:L3=L2/L4:L6=L5/L7:BOTTOM=L7 |
| TP_GPIOO0 | OTHERS | BUS | 8 | 4.75 | 5 | 10 | 5 | 14 | 6 | 9.5 | 12 | 12 | 12 | 12 |  | 50 Ohms | TOP=L2:L3=L2/L4:L6=L5/L7:BOTTOM=L7 |
| TP_GPIOO1 | OTHERS | BUS | 1 | 4.75 | 5 | 10 | 5 | 14 | 6 | 9.5 | 12 | 12 | 12 | 12 |  | 50 Ohms | TOP=L2:L3=L2/L4:L6=L5/L7:BOTTOM=L7 |
| TP_GPIOO1 | OTHERS | BUS | 2 | 5 | 5 | 10 | 5 | 14 | 6 | 10 | 12 | 12 | 12 | 12 |  | 50 Ohms | TOP=L2:L3=L2/L4:L6=L5/L7:BOTTOM=L7 |
| TP_GPIOO1 | OTHERS | BUS | 3 | 5 | 5 | 10 | 5 | 14 | 6 | 10 | 12 | 12 | 12 | 12 |  | 50 Ohms | TOP=L2:L3=L2/L4:L6=L5/L7:BOTTOM=L7 |
| TP_GPIOO1 | OTHERS | BUS | 4 | 5 | 5 | 10 | 5 | 14 | 6 | 10 | 12 | 12 | 12 | 12 |  | 50 Ohms | TOP=L2:L3=L2/L4:L6=L5/L7:BOTTOM=L7 |
| TP_GPIOO1 | OTHERS | BUS | 5 | 5 | 5 | 10 | 5 | 14 | 6 | 10 | 12 | 12 | 12 | 12 |  | 50 Ohms | TOP=L2:L3=L2/L4:L6=L5/L7:BOTTOM=L7 |
| TP_GPIOO1 | OTHERS | BUS | 6 | 5 | 5 | 10 | 5 | 14 | 6 | 10 | 12 | 12 | 12 | 12 |  | 50 Ohms | TOP=L2:L3=L2/L4:L6=L5/L7:BOTTOM=L7 |
| TP_GPIOO1 | OTHERS | BUS | 7 | 5 | 5 | 10 | 5 | 14 | 6 | 10 | 12 | 12 | 12 | 12 |  | 50 Ohms | TOP=L2:L3=L2/L4:L6=L5/L7:BOTTOM=L7 |
| TP_GPIOO1 | OTHERS | BUS | 8 | 4.75 | 5 | 10 | 5 | 14 | 6 | 9.5 | 12 | 12 | 12 | 12 |  | 50 Ohms | TOP=L2:L3=L2/L4:L6=L5/L7:BOTTOM=L7 |
| TP_GPIOO2 | OTHERS | BUS | 1 | 4.75 | 5 | 10 | 5 | 14 | 6 | 9.5 | 12 | 12 | 12 | 12 |  | 50 Ohms | TOP=L2:L3=L2/L4:L6=L5/L7:BOTTOM=L7 |
| TP_GPIOO2 | OTHERS | BUS | 2 | 5 | 5 | 10 | 5 | 14 | 6 | 10 | 12 | 12 | 12 | 12 |  | 50 Ohms | TOP=L2:L3=L2/L4:L6=L5/L7:BOTTOM=L7 |
| TP_GPIOO2 | OTHERS | BUS | 3 | 5 | 5 | 10 | 5 | 14 | 6 | 10 | 12 | 12 | 12 | 12 |  | 50 Ohms | TOP=L2:L3=L2/L4:L6=L5/L7:BOTTOM=L7 |
| TP_GPIOO2 | OTHERS | BUS | 4 | 5 | 5 | 10 | 5 | 14 | 6 | 10 | 12 | 12 | 12 | 12 |  | 50 Ohms | TOP=L2:L3=L2/L4:L6=L5/L7:BOTTOM=L7 |
| TP_GPIOO2 | OTHERS | BUS | 5 | 5 | 5 | 10 | 5 | 14 | 6 | 10 | 12 | 12 | 12 | 12 |  | 50 Ohms | TOP=L2:L3=L2/L4:L6=L5/L7:BOTTOM=L7 |
| TP_GPIOO2 | OTHERS | BUS | 6 | 5 | 5 | 10 | 5 | 14 | 6 | 10 | 12 | 12 | 12 | 12 |  | 50 Ohms | TOP=L2:L3=L2/L4:L6=L5/L7:BOTTOM=L7 |
| TP_GPIOO2 | OTHERS | BUS | 7 | 5 | 5 | 10 | 5 | 14 | 6 | 10 | 12 | 12 | 12 | 12 |  | 50 Ohms | TOP=L2:L3=L2/L4:L6=L5/L7:BOTTOM=L7 |
| TP_GPIOO2 | OTHERS | BUS | 8 | 4.75 | 5 | 10 | 5 | 14 | 6 | 9.5 | 12 | 12 | 12 | 12 |  | 50 Ohms | TOP=L2:L3=L2/L4:L6=L5/L7:BOTTOM=L7 |
| TP_GPIOO4 | OTHERS | BUS | 1 | 4.75 | 5 | 10 | 5 | 14 | 6 | 9.5 | 12 | 12 | 12 | 12 |  | 50 Ohms | TOP=L2:L3=L2/L4:L6=L5/L7:BOTTOM=L7 |
| TP_GPIOO4 | OTHERS | BUS | 2 | 5 | 5 | 10 | 5 | 14 | 6 | 10 | 12 | 12 | 12 | 12 |  | 50 Ohms | TOP=L2:L3=L2/L4:L6=L5/L7:BOTTOM=L7 |
| TP_GPIOO4 | OTHERS | BUS | 3 | 5 | 5 | 10 | 5 | 14 | 6 | 10 | 12 | 12 | 12 | 12 |  | 50 Ohms | TOP=L2:L3=L2/L4:L6=L5/L7:BOTTOM=L7 |
| TP_GPIOO4 | OTHERS | BUS | 4 | 5 | 5 | 10 | 5 | 14 | 6 | 10 | 12 | 12 | 12 | 12 |  | 50 Ohms | TOP=L2:L3=L2/L4:L6=L5/L7:BOTTOM=L7 |
| TP_GPIOO4 | OTHERS | BUS | 5 | 5 | 5 | 10 | 5 | 14 | 6 | 10 | 12 | 12 | 12 | 12 |  | 50 Ohms | TOP=L2:L3=L2/L4:L6=L5/L7:BOTTOM=L7 |
| TP_GPIOO4 | OTHERS | BUS | 6 | 5 | 5 | 10 | 5 | 14 | 6 | 10 | 12 | 12 | 12 | 12 |  | 50 Ohms | TOP=L2:L3=L2/L4:L6=L5/L7:BOTTOM=L7 |
| TP_GPIOO4 | OTHERS | BUS | 7 | 5 | 5 | 10 | 5 | 14 | 6 | 10 | 12 | 12 | 12 | 12 |  | 50 Ohms | TOP=L2:L3=L2/L4:L6=L5/L7:BOTTOM=L7 |
| TP_GPIOO4 | OTHERS | BUS | 8 | 4.75 | 5 | 10 | 5 | 14 | 6 | 9.5 | 12 | 12 | 12 | 12 |  | 50 Ohms | TOP=L2:L3=L2/L4:L6=L5/L7:BOTTOM=L7 |
| TP_GPIOO6 | OTHERS | BUS | 1 | 4.75 | 5 | 10 | 5 | 14 | 6 | 9.5 | 12 | 12 | 12 | 12 |  | 50 Ohms | TOP=L2:L3=L2/L4:L6=L5/L7:BOTTOM=L7 |
| TP_GPIOO6 | OTHERS | BUS | 2 | 5 | 5 | 10 | 5 | 14 | 6 | 10 | 12 | 12 | 12 | 12 |  | 50 Ohms | TOP=L2:L3=L2/L4:L6=L5/L7:BOTTOM=L7 |
| TP_GPIOO6 | OTHERS | BUS | 3 | 5 | 5 | 10 | 5 | 14 | 6 | 10 | 12 | 12 | 12 | 12 |  | 50 Ohms | TOP=L2:L3=L2/L4:L6=L5/L7:BOTTOM=L7 |
| TP_GPIOO6 | OTHERS | BUS | 4 | 5 | 5 | 10 | 5 | 14 | 6 | 10 | 12 | 12 | 12 | 12 |  | 50 Ohms | TOP=L2:L3=L2/L4:L6=L5/L7:BOTTOM=L7 |
| TP_GPIOO6 | OTHERS | BUS | 5 | 5 | 5 | 10 | 5 | 14 | 6 | 10 | 12 | 12 | 12 | 12 |  | 50 Ohms | TOP=L2:L3=L2/L4:L6=L5/L7:BOTTOM=L7 |
| TP_GPIOO6 | OTHERS | BUS | 6 | 5 | 5 | 10 | 5 | 14 | 6 | 10 | 12 | 12 | 12 | 12 |  | 50 Ohms | TOP=L2:L3=L2/L4:L6=L5/L7:BOTTOM=L7 |
| TP_GPIOO6 | OTHERS | BUS | 7 | 5 | 5 | 10 | 5 | 14 | 6 | 10 | 12 | 12 | 12 | 12 |  | 50 Ohms | TOP=L2:L3=L2/L4:L6=L5/L7:BOTTOM=L7 |
| TP_GPIOO6 | OTHERS | BUS | 8 | 4.75 | 5 | 10 | 5 | 14 | 6 | 9.5 | 12 | 12 | 12 | 12 |  | 50 Ohms | TOP=L2:L3=L2/L4:L6=L5/L7:BOTTOM=L7 |
| TP_GPIOO7 | OTHERS | BUS | 1 | 4.75 | 5 | 10 | 5 | 14 | 6 | 9.5 | 12 | 12 | 12 | 12 |  | 50 Ohms | TOP=L2:L3=L2/L4:L6=L5/L7:BOTTOM=L7 |
| TP_GPIOO7 | OTHERS | BUS | 2 | 5 | 5 | 10 | 5 | 14 | 6 | 10 | 12 | 12 | 12 | 12 |  | 50 Ohms | TOP=L2:L3=L2/L4:L6=L5/L7:BOTTOM=L7 |
| TP_GPIOO7 | OTHERS | BUS | 3 | 5 | 5 | 10 | 5 | 14 | 6 | 10 | 12 | 12 | 12 | 12 |  | 50 Ohms | TOP=L2:L3=L2/L4:L6=L5/L7:BOTTOM=L7 |
| TP_GPIOO7 | OTHERS | BUS | 4 | 5 | 5 | 10 | 5 | 14 | 6 | 10 | 12 | 12 | 12 | 12 |  | 50 Ohms | TOP=L2:L3=L2/L4:L6=L5/L7:BOTTOM=L7 |
| TP_GPIOO7 | OTHERS | BUS | 5 | 5 | 5 | 10 | 5 | 14 | 6 | 10 | 12 | 12 | 12 | 12 |  | 50 Ohms | TOP=L2:L3=L2/L4:L6=L5/L7:BOTTOM=L7 |
| TP_GPIOO7 | OTHERS | BUS | 6 | 5 | 5 | 10 | 5 | 14 | 6 | 10 | 12 | 12 | 12 | 12 |  | 50 Ohms | TOP=L2:L3=L2/L4:L6=L5/L7:BOTTOM=L7 |
| TP_GPIOO7 | OTHERS | BUS | 7 | 5 | 5 | 10 | 5 | 14 | 6 | 10 | 12 | 12 | 12 | 12 |  | 50 Ohms | TOP=L2:L3=L2/L4:L6=L5/L7:BOTTOM=L7 |
| TP_GPIOO7 | OTHERS | BUS | 8 | 4.75 | 5 | 10 | 5 | 14 | 6 | 9.5 | 12 | 12 | 12 | 12 |  | 50 Ohms | TOP=L2:L3=L2/L4:L6=L5/L7:BOTTOM=L7 |
| TP_GPIOP0 | OTHERS | BUS | 1 | 4.75 | 5 | 10 | 5 | 14 | 6 | 9.5 | 12 | 12 | 12 | 12 |  | 50 Ohms | TOP=L2:L3=L2/L4:L6=L5/L7:BOTTOM=L7 |
| TP_GPIOP0 | OTHERS | BUS | 2 | 5 | 5 | 10 | 5 | 14 | 6 | 10 | 12 | 12 | 12 | 12 |  | 50 Ohms | TOP=L2:L3=L2/L4:L6=L5/L7:BOTTOM=L7 |
| TP_GPIOP0 | OTHERS | BUS | 3 | 5 | 5 | 10 | 5 | 14 | 6 | 10 | 12 | 12 | 12 | 12 |  | 50 Ohms | TOP=L2:L3=L2/L4:L6=L5/L7:BOTTOM=L7 |
| TP_GPIOP0 | OTHERS | BUS | 4 | 5 | 5 | 10 | 5 | 14 | 6 | 10 | 12 | 12 | 12 | 12 |  | 50 Ohms | TOP=L2:L3=L2/L4:L6=L5/L7:BOTTOM=L7 |
| TP_GPIOP0 | OTHERS | BUS | 5 | 5 | 5 | 10 | 5 | 14 | 6 | 10 | 12 | 12 | 12 | 12 |  | 50 Ohms | TOP=L2:L3=L2/L4:L6=L5/L7:BOTTOM=L7 |
| TP_GPIOP0 | OTHERS | BUS | 6 | 5 | 5 | 10 | 5 | 14 | 6 | 10 | 12 | 12 | 12 | 12 |  | 50 Ohms | TOP=L2:L3=L2/L4:L6=L5/L7:BOTTOM=L7 |
| TP_GPIOP0 | OTHERS | BUS | 7 | 5 | 5 | 10 | 5 | 14 | 6 | 10 | 12 | 12 | 12 | 12 |  | 50 Ohms | TOP=L2:L3=L2/L4:L6=L5/L7:BOTTOM=L7 |
| TP_GPIOP0 | OTHERS | BUS | 8 | 4.75 | 5 | 10 | 5 | 14 | 6 | 9.5 | 12 | 12 | 12 | 12 |  | 50 Ohms | TOP=L2:L3=L2/L4:L6=L5/L7:BOTTOM=L7 |
| TP_GPIOP1 | OTHERS | BUS | 1 | 4.75 | 5 | 10 | 5 | 14 | 6 | 9.5 | 12 | 12 | 12 | 12 |  | 50 Ohms | TOP=L2:L3=L2/L4:L6=L5/L7:BOTTOM=L7 |
| TP_GPIOP1 | OTHERS | BUS | 2 | 5 | 5 | 10 | 5 | 14 | 6 | 10 | 12 | 12 | 12 | 12 |  | 50 Ohms | TOP=L2:L3=L2/L4:L6=L5/L7:BOTTOM=L7 |
| TP_GPIOP1 | OTHERS | BUS | 3 | 5 | 5 | 10 | 5 | 14 | 6 | 10 | 12 | 12 | 12 | 12 |  | 50 Ohms | TOP=L2:L3=L2/L4:L6=L5/L7:BOTTOM=L7 |
| TP_GPIOP1 | OTHERS | BUS | 4 | 5 | 5 | 10 | 5 | 14 | 6 | 10 | 12 | 12 | 12 | 12 |  | 50 Ohms | TOP=L2:L3=L2/L4:L6=L5/L7:BOTTOM=L7 |
| TP_GPIOP1 | OTHERS | BUS | 5 | 5 | 5 | 10 | 5 | 14 | 6 | 10 | 12 | 12 | 12 | 12 |  | 50 Ohms | TOP=L2:L3=L2/L4:L6=L5/L7:BOTTOM=L7 |
| TP_GPIOP1 | OTHERS | BUS | 6 | 5 | 5 | 10 | 5 | 14 | 6 | 10 | 12 | 12 | 12 | 12 |  | 50 Ohms | TOP=L2:L3=L2/L4:L6=L5/L7:BOTTOM=L7 |
| TP_GPIOP1 | OTHERS | BUS | 7 | 5 | 5 | 10 | 5 | 14 | 6 | 10 | 12 | 12 | 12 | 12 |  | 50 Ohms | TOP=L2:L3=L2/L4:L6=L5/L7:BOTTOM=L7 |
| TP_GPIOP1 | OTHERS | BUS | 8 | 4.75 | 5 | 10 | 5 | 14 | 6 | 9.5 | 12 | 12 | 12 | 12 |  | 50 Ohms | TOP=L2:L3=L2/L4:L6=L5/L7:BOTTOM=L7 |
| TP_GPIOP2 | OTHERS | BUS | 1 | 4.75 | 5 | 10 | 5 | 14 | 6 | 9.5 | 12 | 12 | 12 | 12 |  | 50 Ohms | TOP=L2:L3=L2/L4:L6=L5/L7:BOTTOM=L7 |
| TP_GPIOP2 | OTHERS | BUS | 2 | 5 | 5 | 10 | 5 | 14 | 6 | 10 | 12 | 12 | 12 | 12 |  | 50 Ohms | TOP=L2:L3=L2/L4:L6=L5/L7:BOTTOM=L7 |
| TP_GPIOP2 | OTHERS | BUS | 3 | 5 | 5 | 10 | 5 | 14 | 6 | 10 | 12 | 12 | 12 | 12 |  | 50 Ohms | TOP=L2:L3=L2/L4:L6=L5/L7:BOTTOM=L7 |
| TP_GPIOP2 | OTHERS | BUS | 4 | 5 | 5 | 10 | 5 | 14 | 6 | 10 | 12 | 12 | 12 | 12 |  | 50 Ohms | TOP=L2:L3=L2/L4:L6=L5/L7:BOTTOM=L7 |
| TP_GPIOP2 | OTHERS | BUS | 5 | 5 | 5 | 10 | 5 | 14 | 6 | 10 | 12 | 12 | 12 | 12 |  | 50 Ohms | TOP=L2:L3=L2/L4:L6=L5/L7:BOTTOM=L7 |
| TP_GPIOP2 | OTHERS | BUS | 6 | 5 | 5 | 10 | 5 | 14 | 6 | 10 | 12 | 12 | 12 | 12 |  | 50 Ohms | TOP=L2:L3=L2/L4:L6=L5/L7:BOTTOM=L7 |
| TP_GPIOP2 | OTHERS | BUS | 7 | 5 | 5 | 10 | 5 | 14 | 6 | 10 | 12 | 12 | 12 | 12 |  | 50 Ohms | TOP=L2:L3=L2/L4:L6=L5/L7:BOTTOM=L7 |
| TP_GPIOP2 | OTHERS | BUS | 8 | 4.75 | 5 | 10 | 5 | 14 | 6 | 9.5 | 12 | 12 | 12 | 12 |  | 50 Ohms | TOP=L2:L3=L2/L4:L6=L5/L7:BOTTOM=L7 |
| TP_GPIOP4 | OTHERS | BUS | 1 | 4.75 | 5 | 10 | 5 | 14 | 6 | 9.5 | 12 | 12 | 12 | 12 |  | 50 Ohms | TOP=L2:L3=L2/L4:L6=L5/L7:BOTTOM=L7 |
| TP_GPIOP4 | OTHERS | BUS | 2 | 5 | 5 | 10 | 5 | 14 | 6 | 10 | 12 | 12 | 12 | 12 |  | 50 Ohms | TOP=L2:L3=L2/L4:L6=L5/L7:BOTTOM=L7 |
| TP_GPIOP4 | OTHERS | BUS | 3 | 5 | 5 | 10 | 5 | 14 | 6 | 10 | 12 | 12 | 12 | 12 |  | 50 Ohms | TOP=L2:L3=L2/L4:L6=L5/L7:BOTTOM=L7 |
| TP_GPIOP4 | OTHERS | BUS | 4 | 5 | 5 | 10 | 5 | 14 | 6 | 10 | 12 | 12 | 12 | 12 |  | 50 Ohms | TOP=L2:L3=L2/L4:L6=L5/L7:BOTTOM=L7 |
| TP_GPIOP4 | OTHERS | BUS | 5 | 5 | 5 | 10 | 5 | 14 | 6 | 10 | 12 | 12 | 12 | 12 |  | 50 Ohms | TOP=L2:L3=L2/L4:L6=L5/L7:BOTTOM=L7 |
| TP_GPIOP4 | OTHERS | BUS | 6 | 5 | 5 | 10 | 5 | 14 | 6 | 10 | 12 | 12 | 12 | 12 |  | 50 Ohms | TOP=L2:L3=L2/L4:L6=L5/L7:BOTTOM=L7 |
| TP_GPIOP4 | OTHERS | BUS | 7 | 5 | 5 | 10 | 5 | 14 | 6 | 10 | 12 | 12 | 12 | 12 |  | 50 Ohms | TOP=L2:L3=L2/L4:L6=L5/L7:BOTTOM=L7 |
| TP_GPIOP4 | OTHERS | BUS | 8 | 4.75 | 5 | 10 | 5 | 14 | 6 | 9.5 | 12 | 12 | 12 | 12 |  | 50 Ohms | TOP=L2:L3=L2/L4:L6=L5/L7:BOTTOM=L7 |
| TP_GPIOP6 | OTHERS | BUS | 1 | 4.75 | 5 | 10 | 5 | 14 | 6 | 9.5 | 12 | 12 | 12 | 12 |  | 50 Ohms | TOP=L2:L3=L2/L4:L6=L5/L7:BOTTOM=L7 |
| TP_GPIOP6 | OTHERS | BUS | 2 | 5 | 5 | 10 | 5 | 14 | 6 | 10 | 12 | 12 | 12 | 12 |  | 50 Ohms | TOP=L2:L3=L2/L4:L6=L5/L7:BOTTOM=L7 |
| TP_GPIOP6 | OTHERS | BUS | 3 | 5 | 5 | 10 | 5 | 14 | 6 | 10 | 12 | 12 | 12 | 12 |  | 50 Ohms | TOP=L2:L3=L2/L4:L6=L5/L7:BOTTOM=L7 |
| TP_GPIOP6 | OTHERS | BUS | 4 | 5 | 5 | 10 | 5 | 14 | 6 | 10 | 12 | 12 | 12 | 12 |  | 50 Ohms | TOP=L2:L3=L2/L4:L6=L5/L7:BOTTOM=L7 |
| TP_GPIOP6 | OTHERS | BUS | 5 | 5 | 5 | 10 | 5 | 14 | 6 | 10 | 12 | 12 | 12 | 12 |  | 50 Ohms | TOP=L2:L3=L2/L4:L6=L5/L7:BOTTOM=L7 |
| TP_GPIOP6 | OTHERS | BUS | 6 | 5 | 5 | 10 | 5 | 14 | 6 | 10 | 12 | 12 | 12 | 12 |  | 50 Ohms | TOP=L2:L3=L2/L4:L6=L5/L7:BOTTOM=L7 |
| TP_GPIOP6 | OTHERS | BUS | 7 | 5 | 5 | 10 | 5 | 14 | 6 | 10 | 12 | 12 | 12 | 12 |  | 50 Ohms | TOP=L2:L3=L2/L4:L6=L5/L7:BOTTOM=L7 |
| TP_GPIOP6 | OTHERS | BUS | 8 | 4.75 | 5 | 10 | 5 | 14 | 6 | 9.5 | 12 | 12 | 12 | 12 |  | 50 Ohms | TOP=L2:L3=L2/L4:L6=L5/L7:BOTTOM=L7 |
| TP_GPIOS4 | OTHERS | BUS | 1 | 4.75 | 5 | 10 | 5 | 14 | 6 | 9.5 | 12 | 12 | 12 | 12 |  | 50 Ohms | TOP=L2:L3=L2/L4:L6=L5/L7:BOTTOM=L7 |
| TP_GPIOS4 | OTHERS | BUS | 2 | 5 | 5 | 10 | 5 | 14 | 6 | 10 | 12 | 12 | 12 | 12 |  | 50 Ohms | TOP=L2:L3=L2/L4:L6=L5/L7:BOTTOM=L7 |
| TP_GPIOS4 | OTHERS | BUS | 3 | 5 | 5 | 10 | 5 | 14 | 6 | 10 | 12 | 12 | 12 | 12 |  | 50 Ohms | TOP=L2:L3=L2/L4:L6=L5/L7:BOTTOM=L7 |
| TP_GPIOS4 | OTHERS | BUS | 4 | 5 | 5 | 10 | 5 | 14 | 6 | 10 | 12 | 12 | 12 | 12 |  | 50 Ohms | TOP=L2:L3=L2/L4:L6=L5/L7:BOTTOM=L7 |
| TP_GPIOS4 | OTHERS | BUS | 5 | 5 | 5 | 10 | 5 | 14 | 6 | 10 | 12 | 12 | 12 | 12 |  | 50 Ohms | TOP=L2:L3=L2/L4:L6=L5/L7:BOTTOM=L7 |
| TP_GPIOS4 | OTHERS | BUS | 6 | 5 | 5 | 10 | 5 | 14 | 6 | 10 | 12 | 12 | 12 | 12 |  | 50 Ohms | TOP=L2:L3=L2/L4:L6=L5/L7:BOTTOM=L7 |
| TP_GPIOS4 | OTHERS | BUS | 7 | 5 | 5 | 10 | 5 | 14 | 6 | 10 | 12 | 12 | 12 | 12 |  | 50 Ohms | TOP=L2:L3=L2/L4:L6=L5/L7:BOTTOM=L7 |
| TP_GPIOS4 | OTHERS | BUS | 8 | 4.75 | 5 | 10 | 5 | 14 | 6 | 9.5 | 12 | 12 | 12 | 12 |  | 50 Ohms | TOP=L2:L3=L2/L4:L6=L5/L7:BOTTOM=L7 |
| TP_GPIOT6 | OTHERS | BUS | 1 | 4.75 | 5 | 10 | 5 | 14 | 6 | 9.5 | 12 | 12 | 12 | 12 |  | 50 Ohms | TOP=L2:L3=L2/L4:L6=L5/L7:BOTTOM=L7 |
| TP_GPIOT6 | OTHERS | BUS | 2 | 5 | 5 | 10 | 5 | 14 | 6 | 10 | 12 | 12 | 12 | 12 |  | 50 Ohms | TOP=L2:L3=L2/L4:L6=L5/L7:BOTTOM=L7 |
| TP_GPIOT6 | OTHERS | BUS | 3 | 5 | 5 | 10 | 5 | 14 | 6 | 10 | 12 | 12 | 12 | 12 |  | 50 Ohms | TOP=L2:L3=L2/L4:L6=L5/L7:BOTTOM=L7 |
| TP_GPIOT6 | OTHERS | BUS | 4 | 5 | 5 | 10 | 5 | 14 | 6 | 10 | 12 | 12 | 12 | 12 |  | 50 Ohms | TOP=L2:L3=L2/L4:L6=L5/L7:BOTTOM=L7 |
| TP_GPIOT6 | OTHERS | BUS | 5 | 5 | 5 | 10 | 5 | 14 | 6 | 10 | 12 | 12 | 12 | 12 |  | 50 Ohms | TOP=L2:L3=L2/L4:L6=L5/L7:BOTTOM=L7 |
| TP_GPIOT6 | OTHERS | BUS | 6 | 5 | 5 | 10 | 5 | 14 | 6 | 10 | 12 | 12 | 12 | 12 |  | 50 Ohms | TOP=L2:L3=L2/L4:L6=L5/L7:BOTTOM=L7 |
| TP_GPIOT6 | OTHERS | BUS | 7 | 5 | 5 | 10 | 5 | 14 | 6 | 10 | 12 | 12 | 12 | 12 |  | 50 Ohms | TOP=L2:L3=L2/L4:L6=L5/L7:BOTTOM=L7 |
| TP_GPIOT6 | OTHERS | BUS | 8 | 4.75 | 5 | 10 | 5 | 14 | 6 | 9.5 | 12 | 12 | 12 | 12 |  | 50 Ohms | TOP=L2:L3=L2/L4:L6=L5/L7:BOTTOM=L7 |
| TP_GPIOT7 | OTHERS | BUS | 1 | 4.75 | 5 | 10 | 5 | 14 | 6 | 9.5 | 12 | 12 | 12 | 12 |  | 50 Ohms | TOP=L2:L3=L2/L4:L6=L5/L7:BOTTOM=L7 |
| TP_GPIOT7 | OTHERS | BUS | 2 | 5 | 5 | 10 | 5 | 14 | 6 | 10 | 12 | 12 | 12 | 12 |  | 50 Ohms | TOP=L2:L3=L2/L4:L6=L5/L7:BOTTOM=L7 |
| TP_GPIOT7 | OTHERS | BUS | 3 | 5 | 5 | 10 | 5 | 14 | 6 | 10 | 12 | 12 | 12 | 12 |  | 50 Ohms | TOP=L2:L3=L2/L4:L6=L5/L7:BOTTOM=L7 |
| TP_GPIOT7 | OTHERS | BUS | 4 | 5 | 5 | 10 | 5 | 14 | 6 | 10 | 12 | 12 | 12 | 12 |  | 50 Ohms | TOP=L2:L3=L2/L4:L6=L5/L7:BOTTOM=L7 |
| TP_GPIOT7 | OTHERS | BUS | 5 | 5 | 5 | 10 | 5 | 14 | 6 | 10 | 12 | 12 | 12 | 12 |  | 50 Ohms | TOP=L2:L3=L2/L4:L6=L5/L7:BOTTOM=L7 |
| TP_GPIOT7 | OTHERS | BUS | 6 | 5 | 5 | 10 | 5 | 14 | 6 | 10 | 12 | 12 | 12 | 12 |  | 50 Ohms | TOP=L2:L3=L2/L4:L6=L5/L7:BOTTOM=L7 |
| TP_GPIOT7 | OTHERS | BUS | 7 | 5 | 5 | 10 | 5 | 14 | 6 | 10 | 12 | 12 | 12 | 12 |  | 50 Ohms | TOP=L2:L3=L2/L4:L6=L5/L7:BOTTOM=L7 |
| TP_GPIOT7 | OTHERS | BUS | 8 | 4.75 | 5 | 10 | 5 | 14 | 6 | 9.5 | 12 | 12 | 12 | 12 |  | 50 Ohms | TOP=L2:L3=L2/L4:L6=L5/L7:BOTTOM=L7 |
| TP_GPIOU0 | OTHERS | BUS | 1 | 4.75 | 5 | 10 | 5 | 14 | 6 | 9.5 | 12 | 12 | 12 | 12 |  | 50 Ohms | TOP=L2:L3=L2/L4:L6=L5/L7:BOTTOM=L7 |
| TP_GPIOU0 | OTHERS | BUS | 2 | 5 | 5 | 10 | 5 | 14 | 6 | 10 | 12 | 12 | 12 | 12 |  | 50 Ohms | TOP=L2:L3=L2/L4:L6=L5/L7:BOTTOM=L7 |
| TP_GPIOU0 | OTHERS | BUS | 3 | 5 | 5 | 10 | 5 | 14 | 6 | 10 | 12 | 12 | 12 | 12 |  | 50 Ohms | TOP=L2:L3=L2/L4:L6=L5/L7:BOTTOM=L7 |
| TP_GPIOU0 | OTHERS | BUS | 4 | 5 | 5 | 10 | 5 | 14 | 6 | 10 | 12 | 12 | 12 | 12 |  | 50 Ohms | TOP=L2:L3=L2/L4:L6=L5/L7:BOTTOM=L7 |
| TP_GPIOU0 | OTHERS | BUS | 5 | 5 | 5 | 10 | 5 | 14 | 6 | 10 | 12 | 12 | 12 | 12 |  | 50 Ohms | TOP=L2:L3=L2/L4:L6=L5/L7:BOTTOM=L7 |
| TP_GPIOU0 | OTHERS | BUS | 6 | 5 | 5 | 10 | 5 | 14 | 6 | 10 | 12 | 12 | 12 | 12 |  | 50 Ohms | TOP=L2:L3=L2/L4:L6=L5/L7:BOTTOM=L7 |
| TP_GPIOU0 | OTHERS | BUS | 7 | 5 | 5 | 10 | 5 | 14 | 6 | 10 | 12 | 12 | 12 | 12 |  | 50 Ohms | TOP=L2:L3=L2/L4:L6=L5/L7:BOTTOM=L7 |
| TP_GPIOU0 | OTHERS | BUS | 8 | 4.75 | 5 | 10 | 5 | 14 | 6 | 9.5 | 12 | 12 | 12 | 12 |  | 50 Ohms | TOP=L2:L3=L2/L4:L6=L5/L7:BOTTOM=L7 |
| TP_GPIOU1 | OTHERS | BUS | 1 | 4.75 | 5 | 10 | 5 | 14 | 6 | 9.5 | 12 | 12 | 12 | 12 |  | 50 Ohms | TOP=L2:L3=L2/L4:L6=L5/L7:BOTTOM=L7 |
| TP_GPIOU1 | OTHERS | BUS | 2 | 5 | 5 | 10 | 5 | 14 | 6 | 10 | 12 | 12 | 12 | 12 |  | 50 Ohms | TOP=L2:L3=L2/L4:L6=L5/L7:BOTTOM=L7 |
| TP_GPIOU1 | OTHERS | BUS | 3 | 5 | 5 | 10 | 5 | 14 | 6 | 10 | 12 | 12 | 12 | 12 |  | 50 Ohms | TOP=L2:L3=L2/L4:L6=L5/L7:BOTTOM=L7 |
| TP_GPIOU1 | OTHERS | BUS | 4 | 5 | 5 | 10 | 5 | 14 | 6 | 10 | 12 | 12 | 12 | 12 |  | 50 Ohms | TOP=L2:L3=L2/L4:L6=L5/L7:BOTTOM=L7 |
| TP_GPIOU1 | OTHERS | BUS | 5 | 5 | 5 | 10 | 5 | 14 | 6 | 10 | 12 | 12 | 12 | 12 |  | 50 Ohms | TOP=L2:L3=L2/L4:L6=L5/L7:BOTTOM=L7 |
| TP_GPIOU1 | OTHERS | BUS | 6 | 5 | 5 | 10 | 5 | 14 | 6 | 10 | 12 | 12 | 12 | 12 |  | 50 Ohms | TOP=L2:L3=L2/L4:L6=L5/L7:BOTTOM=L7 |
| TP_GPIOU1 | OTHERS | BUS | 7 | 5 | 5 | 10 | 5 | 14 | 6 | 10 | 12 | 12 | 12 | 12 |  | 50 Ohms | TOP=L2:L3=L2/L4:L6=L5/L7:BOTTOM=L7 |
| TP_GPIOU1 | OTHERS | BUS | 8 | 4.75 | 5 | 10 | 5 | 14 | 6 | 9.5 | 12 | 12 | 12 | 12 |  | 50 Ohms | TOP=L2:L3=L2/L4:L6=L5/L7:BOTTOM=L7 |
| TP_GPIOU2 | OTHERS | BUS | 1 | 4.75 | 5 | 10 | 5 | 14 | 6 | 9.5 | 12 | 12 | 12 | 12 |  | 50 Ohms | TOP=L2:L3=L2/L4:L6=L5/L7:BOTTOM=L7 |
| TP_GPIOU2 | OTHERS | BUS | 2 | 5 | 5 | 10 | 5 | 14 | 6 | 10 | 12 | 12 | 12 | 12 |  | 50 Ohms | TOP=L2:L3=L2/L4:L6=L5/L7:BOTTOM=L7 |
| TP_GPIOU2 | OTHERS | BUS | 3 | 5 | 5 | 10 | 5 | 14 | 6 | 10 | 12 | 12 | 12 | 12 |  | 50 Ohms | TOP=L2:L3=L2/L4:L6=L5/L7:BOTTOM=L7 |
| TP_GPIOU2 | OTHERS | BUS | 4 | 5 | 5 | 10 | 5 | 14 | 6 | 10 | 12 | 12 | 12 | 12 |  | 50 Ohms | TOP=L2:L3=L2/L4:L6=L5/L7:BOTTOM=L7 |
| TP_GPIOU2 | OTHERS | BUS | 5 | 5 | 5 | 10 | 5 | 14 | 6 | 10 | 12 | 12 | 12 | 12 |  | 50 Ohms | TOP=L2:L3=L2/L4:L6=L5/L7:BOTTOM=L7 |
| TP_GPIOU2 | OTHERS | BUS | 6 | 5 | 5 | 10 | 5 | 14 | 6 | 10 | 12 | 12 | 12 | 12 |  | 50 Ohms | TOP=L2:L3=L2/L4:L6=L5/L7:BOTTOM=L7 |
| TP_GPIOU2 | OTHERS | BUS | 7 | 5 | 5 | 10 | 5 | 14 | 6 | 10 | 12 | 12 | 12 | 12 |  | 50 Ohms | TOP=L2:L3=L2/L4:L6=L5/L7:BOTTOM=L7 |
| TP_GPIOU2 | OTHERS | BUS | 8 | 4.75 | 5 | 10 | 5 | 14 | 6 | 9.5 | 12 | 12 | 12 | 12 |  | 50 Ohms | TOP=L2:L3=L2/L4:L6=L5/L7:BOTTOM=L7 |
| TP_GPIOU3 | OTHERS | BUS | 1 | 4.75 | 5 | 10 | 5 | 14 | 6 | 9.5 | 12 | 12 | 12 | 12 |  | 50 Ohms | TOP=L2:L3=L2/L4:L6=L5/L7:BOTTOM=L7 |
| TP_GPIOU3 | OTHERS | BUS | 2 | 5 | 5 | 10 | 5 | 14 | 6 | 10 | 12 | 12 | 12 | 12 |  | 50 Ohms | TOP=L2:L3=L2/L4:L6=L5/L7:BOTTOM=L7 |
| TP_GPIOU3 | OTHERS | BUS | 3 | 5 | 5 | 10 | 5 | 14 | 6 | 10 | 12 | 12 | 12 | 12 |  | 50 Ohms | TOP=L2:L3=L2/L4:L6=L5/L7:BOTTOM=L7 |
| TP_GPIOU3 | OTHERS | BUS | 4 | 5 | 5 | 10 | 5 | 14 | 6 | 10 | 12 | 12 | 12 | 12 |  | 50 Ohms | TOP=L2:L3=L2/L4:L6=L5/L7:BOTTOM=L7 |
| TP_GPIOU3 | OTHERS | BUS | 5 | 5 | 5 | 10 | 5 | 14 | 6 | 10 | 12 | 12 | 12 | 12 |  | 50 Ohms | TOP=L2:L3=L2/L4:L6=L5/L7:BOTTOM=L7 |
| TP_GPIOU3 | OTHERS | BUS | 6 | 5 | 5 | 10 | 5 | 14 | 6 | 10 | 12 | 12 | 12 | 12 |  | 50 Ohms | TOP=L2:L3=L2/L4:L6=L5/L7:BOTTOM=L7 |
| TP_GPIOU3 | OTHERS | BUS | 7 | 5 | 5 | 10 | 5 | 14 | 6 | 10 | 12 | 12 | 12 | 12 |  | 50 Ohms | TOP=L2:L3=L2/L4:L6=L5/L7:BOTTOM=L7 |
| TP_GPIOU3 | OTHERS | BUS | 8 | 4.75 | 5 | 10 | 5 | 14 | 6 | 9.5 | 12 | 12 | 12 | 12 |  | 50 Ohms | TOP=L2:L3=L2/L4:L6=L5/L7:BOTTOM=L7 |
| TP_GPIOV3 | OTHERS | BUS | 1 | 4.75 | 5 | 10 | 5 | 14 | 6 | 9.5 | 12 | 12 | 12 | 12 |  | 50 Ohms | TOP=L2:L3=L2/L4:L6=L5/L7:BOTTOM=L7 |
| TP_GPIOV3 | OTHERS | BUS | 2 | 5 | 5 | 10 | 5 | 14 | 6 | 10 | 12 | 12 | 12 | 12 |  | 50 Ohms | TOP=L2:L3=L2/L4:L6=L5/L7:BOTTOM=L7 |
| TP_GPIOV3 | OTHERS | BUS | 3 | 5 | 5 | 10 | 5 | 14 | 6 | 10 | 12 | 12 | 12 | 12 |  | 50 Ohms | TOP=L2:L3=L2/L4:L6=L5/L7:BOTTOM=L7 |
| TP_GPIOV3 | OTHERS | BUS | 4 | 5 | 5 | 10 | 5 | 14 | 6 | 10 | 12 | 12 | 12 | 12 |  | 50 Ohms | TOP=L2:L3=L2/L4:L6=L5/L7:BOTTOM=L7 |
| TP_GPIOV3 | OTHERS | BUS | 5 | 5 | 5 | 10 | 5 | 14 | 6 | 10 | 12 | 12 | 12 | 12 |  | 50 Ohms | TOP=L2:L3=L2/L4:L6=L5/L7:BOTTOM=L7 |
| TP_GPIOV3 | OTHERS | BUS | 6 | 5 | 5 | 10 | 5 | 14 | 6 | 10 | 12 | 12 | 12 | 12 |  | 50 Ohms | TOP=L2:L3=L2/L4:L6=L5/L7:BOTTOM=L7 |
| TP_GPIOV3 | OTHERS | BUS | 7 | 5 | 5 | 10 | 5 | 14 | 6 | 10 | 12 | 12 | 12 | 12 |  | 50 Ohms | TOP=L2:L3=L2/L4:L6=L5/L7:BOTTOM=L7 |
| TP_GPIOV3 | OTHERS | BUS | 8 | 4.75 | 5 | 10 | 5 | 14 | 6 | 9.5 | 12 | 12 | 12 | 12 |  | 50 Ohms | TOP=L2:L3=L2/L4:L6=L5/L7:BOTTOM=L7 |
| TP_GPIOV4 | OTHERS | BUS | 1 | 4.75 | 5 | 10 | 5 | 14 | 6 | 9.5 | 12 | 12 | 12 | 12 |  | 50 Ohms | TOP=L2:L3=L2/L4:L6=L5/L7:BOTTOM=L7 |
| TP_GPIOV4 | OTHERS | BUS | 2 | 5 | 5 | 10 | 5 | 14 | 6 | 10 | 12 | 12 | 12 | 12 |  | 50 Ohms | TOP=L2:L3=L2/L4:L6=L5/L7:BOTTOM=L7 |
| TP_GPIOV4 | OTHERS | BUS | 3 | 5 | 5 | 10 | 5 | 14 | 6 | 10 | 12 | 12 | 12 | 12 |  | 50 Ohms | TOP=L2:L3=L2/L4:L6=L5/L7:BOTTOM=L7 |
| TP_GPIOV4 | OTHERS | BUS | 4 | 5 | 5 | 10 | 5 | 14 | 6 | 10 | 12 | 12 | 12 | 12 |  | 50 Ohms | TOP=L2:L3=L2/L4:L6=L5/L7:BOTTOM=L7 |
| TP_GPIOV4 | OTHERS | BUS | 5 | 5 | 5 | 10 | 5 | 14 | 6 | 10 | 12 | 12 | 12 | 12 |  | 50 Ohms | TOP=L2:L3=L2/L4:L6=L5/L7:BOTTOM=L7 |
| TP_GPIOV4 | OTHERS | BUS | 6 | 5 | 5 | 10 | 5 | 14 | 6 | 10 | 12 | 12 | 12 | 12 |  | 50 Ohms | TOP=L2:L3=L2/L4:L6=L5/L7:BOTTOM=L7 |
| TP_GPIOV4 | OTHERS | BUS | 7 | 5 | 5 | 10 | 5 | 14 | 6 | 10 | 12 | 12 | 12 | 12 |  | 50 Ohms | TOP=L2:L3=L2/L4:L6=L5/L7:BOTTOM=L7 |
| TP_GPIOV4 | OTHERS | BUS | 8 | 4.75 | 5 | 10 | 5 | 14 | 6 | 9.5 | 12 | 12 | 12 | 12 |  | 50 Ohms | TOP=L2:L3=L2/L4:L6=L5/L7:BOTTOM=L7 |
| TP_GPIOV5 | OTHERS | BUS | 1 | 4.75 | 5 | 10 | 5 | 14 | 6 | 9.5 | 12 | 12 | 12 | 12 |  | 50 Ohms | TOP=L2:L3=L2/L4:L6=L5/L7:BOTTOM=L7 |
| TP_GPIOV5 | OTHERS | BUS | 2 | 5 | 5 | 10 | 5 | 14 | 6 | 10 | 12 | 12 | 12 | 12 |  | 50 Ohms | TOP=L2:L3=L2/L4:L6=L5/L7:BOTTOM=L7 |
| TP_GPIOV5 | OTHERS | BUS | 3 | 5 | 5 | 10 | 5 | 14 | 6 | 10 | 12 | 12 | 12 | 12 |  | 50 Ohms | TOP=L2:L3=L2/L4:L6=L5/L7:BOTTOM=L7 |
| TP_GPIOV5 | OTHERS | BUS | 4 | 5 | 5 | 10 | 5 | 14 | 6 | 10 | 12 | 12 | 12 | 12 |  | 50 Ohms | TOP=L2:L3=L2/L4:L6=L5/L7:BOTTOM=L7 |
| TP_GPIOV5 | OTHERS | BUS | 5 | 5 | 5 | 10 | 5 | 14 | 6 | 10 | 12 | 12 | 12 | 12 |  | 50 Ohms | TOP=L2:L3=L2/L4:L6=L5/L7:BOTTOM=L7 |
| TP_GPIOV5 | OTHERS | BUS | 6 | 5 | 5 | 10 | 5 | 14 | 6 | 10 | 12 | 12 | 12 | 12 |  | 50 Ohms | TOP=L2:L3=L2/L4:L6=L5/L7:BOTTOM=L7 |
| TP_GPIOV5 | OTHERS | BUS | 7 | 5 | 5 | 10 | 5 | 14 | 6 | 10 | 12 | 12 | 12 | 12 |  | 50 Ohms | TOP=L2:L3=L2/L4:L6=L5/L7:BOTTOM=L7 |
| TP_GPIOV5 | OTHERS | BUS | 8 | 4.75 | 5 | 10 | 5 | 14 | 6 | 9.5 | 12 | 12 | 12 | 12 |  | 50 Ohms | TOP=L2:L3=L2/L4:L6=L5/L7:BOTTOM=L7 |
| TP_GPIOV6 | OTHERS | BUS | 1 | 4.75 | 5 | 10 | 5 | 14 | 6 | 9.5 | 12 | 12 | 12 | 12 |  | 50 Ohms | TOP=L2:L3=L2/L4:L6=L5/L7:BOTTOM=L7 |
| TP_GPIOV6 | OTHERS | BUS | 2 | 5 | 5 | 10 | 5 | 14 | 6 | 10 | 12 | 12 | 12 | 12 |  | 50 Ohms | TOP=L2:L3=L2/L4:L6=L5/L7:BOTTOM=L7 |
| TP_GPIOV6 | OTHERS | BUS | 3 | 5 | 5 | 10 | 5 | 14 | 6 | 10 | 12 | 12 | 12 | 12 |  | 50 Ohms | TOP=L2:L3=L2/L4:L6=L5/L7:BOTTOM=L7 |
| TP_GPIOV6 | OTHERS | BUS | 4 | 5 | 5 | 10 | 5 | 14 | 6 | 10 | 12 | 12 | 12 | 12 |  | 50 Ohms | TOP=L2:L3=L2/L4:L6=L5/L7:BOTTOM=L7 |
| TP_GPIOV6 | OTHERS | BUS | 5 | 5 | 5 | 10 | 5 | 14 | 6 | 10 | 12 | 12 | 12 | 12 |  | 50 Ohms | TOP=L2:L3=L2/L4:L6=L5/L7:BOTTOM=L7 |
| TP_GPIOV6 | OTHERS | BUS | 6 | 5 | 5 | 10 | 5 | 14 | 6 | 10 | 12 | 12 | 12 | 12 |  | 50 Ohms | TOP=L2:L3=L2/L4:L6=L5/L7:BOTTOM=L7 |
| TP_GPIOV6 | OTHERS | BUS | 7 | 5 | 5 | 10 | 5 | 14 | 6 | 10 | 12 | 12 | 12 | 12 |  | 50 Ohms | TOP=L2:L3=L2/L4:L6=L5/L7:BOTTOM=L7 |
| TP_GPIOV6 | OTHERS | BUS | 8 | 4.75 | 5 | 10 | 5 | 14 | 6 | 9.5 | 12 | 12 | 12 | 12 |  | 50 Ohms | TOP=L2:L3=L2/L4:L6=L5/L7:BOTTOM=L7 |
| TP_GPIOV7 | OTHERS | BUS | 1 | 4.75 | 5 | 10 | 5 | 14 | 6 | 9.5 | 12 | 12 | 12 | 12 |  | 50 Ohms | TOP=L2:L3=L2/L4:L6=L5/L7:BOTTOM=L7 |
| TP_GPIOV7 | OTHERS | BUS | 2 | 5 | 5 | 10 | 5 | 14 | 6 | 10 | 12 | 12 | 12 | 12 |  | 50 Ohms | TOP=L2:L3=L2/L4:L6=L5/L7:BOTTOM=L7 |
| TP_GPIOV7 | OTHERS | BUS | 3 | 5 | 5 | 10 | 5 | 14 | 6 | 10 | 12 | 12 | 12 | 12 |  | 50 Ohms | TOP=L2:L3=L2/L4:L6=L5/L7:BOTTOM=L7 |
| TP_GPIOV7 | OTHERS | BUS | 4 | 5 | 5 | 10 | 5 | 14 | 6 | 10 | 12 | 12 | 12 | 12 |  | 50 Ohms | TOP=L2:L3=L2/L4:L6=L5/L7:BOTTOM=L7 |
| TP_GPIOV7 | OTHERS | BUS | 5 | 5 | 5 | 10 | 5 | 14 | 6 | 10 | 12 | 12 | 12 | 12 |  | 50 Ohms | TOP=L2:L3=L2/L4:L6=L5/L7:BOTTOM=L7 |
| TP_GPIOV7 | OTHERS | BUS | 6 | 5 | 5 | 10 | 5 | 14 | 6 | 10 | 12 | 12 | 12 | 12 |  | 50 Ohms | TOP=L2:L3=L2/L4:L6=L5/L7:BOTTOM=L7 |
| TP_GPIOV7 | OTHERS | BUS | 7 | 5 | 5 | 10 | 5 | 14 | 6 | 10 | 12 | 12 | 12 | 12 |  | 50 Ohms | TOP=L2:L3=L2/L4:L6=L5/L7:BOTTOM=L7 |
| TP_GPIOV7 | OTHERS | BUS | 8 | 4.75 | 5 | 10 | 5 | 14 | 6 | 9.5 | 12 | 12 | 12 | 12 |  | 50 Ohms | TOP=L2:L3=L2/L4:L6=L5/L7:BOTTOM=L7 |
| TP_GPIOY3 | OTHERS | BUS | 1 | 4.75 | 5 | 10 | 5 | 14 | 6 | 9.5 | 12 | 12 | 12 | 12 |  | 50 Ohms | TOP=L2:L3=L2/L4:L6=L5/L7:BOTTOM=L7 |
| TP_GPIOY3 | OTHERS | BUS | 2 | 5 | 5 | 10 | 5 | 14 | 6 | 10 | 12 | 12 | 12 | 12 |  | 50 Ohms | TOP=L2:L3=L2/L4:L6=L5/L7:BOTTOM=L7 |
| TP_GPIOY3 | OTHERS | BUS | 3 | 5 | 5 | 10 | 5 | 14 | 6 | 10 | 12 | 12 | 12 | 12 |  | 50 Ohms | TOP=L2:L3=L2/L4:L6=L5/L7:BOTTOM=L7 |
| TP_GPIOY3 | OTHERS | BUS | 4 | 5 | 5 | 10 | 5 | 14 | 6 | 10 | 12 | 12 | 12 | 12 |  | 50 Ohms | TOP=L2:L3=L2/L4:L6=L5/L7:BOTTOM=L7 |
| TP_GPIOY3 | OTHERS | BUS | 5 | 5 | 5 | 10 | 5 | 14 | 6 | 10 | 12 | 12 | 12 | 12 |  | 50 Ohms | TOP=L2:L3=L2/L4:L6=L5/L7:BOTTOM=L7 |
| TP_GPIOY3 | OTHERS | BUS | 6 | 5 | 5 | 10 | 5 | 14 | 6 | 10 | 12 | 12 | 12 | 12 |  | 50 Ohms | TOP=L2:L3=L2/L4:L6=L5/L7:BOTTOM=L7 |
| TP_GPIOY3 | OTHERS | BUS | 7 | 5 | 5 | 10 | 5 | 14 | 6 | 10 | 12 | 12 | 12 | 12 |  | 50 Ohms | TOP=L2:L3=L2/L4:L6=L5/L7:BOTTOM=L7 |
| TP_GPIOY3 | OTHERS | BUS | 8 | 4.75 | 5 | 10 | 5 | 14 | 6 | 9.5 | 12 | 12 | 12 | 12 |  | 50 Ohms | TOP=L2:L3=L2/L4:L6=L5/L7:BOTTOM=L7 |
| TP_IRQ_CPU_SERIAL | OTHERS | BUS | 1 | 4.75 | 5 | 10 | 5 | 14 | 6 | 9.5 | 12 | 12 | 12 | 12 |  | 50 Ohms | TOP=L2:L3=L2/L4:L6=L5/L7:BOTTOM=L7 |
| TP_IRQ_CPU_SERIAL | OTHERS | BUS | 2 | 5 | 5 | 10 | 5 | 14 | 6 | 10 | 12 | 12 | 12 | 12 |  | 50 Ohms | TOP=L2:L3=L2/L4:L6=L5/L7:BOTTOM=L7 |
| TP_IRQ_CPU_SERIAL | OTHERS | BUS | 3 | 5 | 5 | 10 | 5 | 14 | 6 | 10 | 12 | 12 | 12 | 12 |  | 50 Ohms | TOP=L2:L3=L2/L4:L6=L5/L7:BOTTOM=L7 |
| TP_IRQ_CPU_SERIAL | OTHERS | BUS | 4 | 5 | 5 | 10 | 5 | 14 | 6 | 10 | 12 | 12 | 12 | 12 |  | 50 Ohms | TOP=L2:L3=L2/L4:L6=L5/L7:BOTTOM=L7 |
| TP_IRQ_CPU_SERIAL | OTHERS | BUS | 5 | 5 | 5 | 10 | 5 | 14 | 6 | 10 | 12 | 12 | 12 | 12 |  | 50 Ohms | TOP=L2:L3=L2/L4:L6=L5/L7:BOTTOM=L7 |
| TP_IRQ_CPU_SERIAL | OTHERS | BUS | 6 | 5 | 5 | 10 | 5 | 14 | 6 | 10 | 12 | 12 | 12 | 12 |  | 50 Ohms | TOP=L2:L3=L2/L4:L6=L5/L7:BOTTOM=L7 |
| TP_IRQ_CPU_SERIAL | OTHERS | BUS | 7 | 5 | 5 | 10 | 5 | 14 | 6 | 10 | 12 | 12 | 12 | 12 |  | 50 Ohms | TOP=L2:L3=L2/L4:L6=L5/L7:BOTTOM=L7 |
| TP_IRQ_CPU_SERIAL | OTHERS | BUS | 8 | 4.75 | 5 | 10 | 5 | 14 | 6 | 9.5 | 12 | 12 | 12 | 12 |  | 50 Ohms | TOP=L2:L3=L2/L4:L6=L5/L7:BOTTOM=L7 |
| TP_LPC_CPU_CLKOUT0 | OTHERS | BUS | 1 | 4.75 | 5 | 10 | 5 | 14 | 6 | 9.5 | 12 | 12 | 12 | 12 |  | 50 Ohms | TOP=L2:L3=L2/L4:L6=L5/L7:BOTTOM=L7 |
| TP_LPC_CPU_CLKOUT0 | OTHERS | BUS | 2 | 5 | 5 | 10 | 5 | 14 | 6 | 10 | 12 | 12 | 12 | 12 |  | 50 Ohms | TOP=L2:L3=L2/L4:L6=L5/L7:BOTTOM=L7 |
| TP_LPC_CPU_CLKOUT0 | OTHERS | BUS | 3 | 5 | 5 | 10 | 5 | 14 | 6 | 10 | 12 | 12 | 12 | 12 |  | 50 Ohms | TOP=L2:L3=L2/L4:L6=L5/L7:BOTTOM=L7 |
| TP_LPC_CPU_CLKOUT0 | OTHERS | BUS | 4 | 5 | 5 | 10 | 5 | 14 | 6 | 10 | 12 | 12 | 12 | 12 |  | 50 Ohms | TOP=L2:L3=L2/L4:L6=L5/L7:BOTTOM=L7 |
| TP_LPC_CPU_CLKOUT0 | OTHERS | BUS | 5 | 5 | 5 | 10 | 5 | 14 | 6 | 10 | 12 | 12 | 12 | 12 |  | 50 Ohms | TOP=L2:L3=L2/L4:L6=L5/L7:BOTTOM=L7 |
| TP_LPC_CPU_CLKOUT0 | OTHERS | BUS | 6 | 5 | 5 | 10 | 5 | 14 | 6 | 10 | 12 | 12 | 12 | 12 |  | 50 Ohms | TOP=L2:L3=L2/L4:L6=L5/L7:BOTTOM=L7 |
| TP_LPC_CPU_CLKOUT0 | OTHERS | BUS | 7 | 5 | 5 | 10 | 5 | 14 | 6 | 10 | 12 | 12 | 12 | 12 |  | 50 Ohms | TOP=L2:L3=L2/L4:L6=L5/L7:BOTTOM=L7 |
| TP_LPC_CPU_CLKOUT0 | OTHERS | BUS | 8 | 4.75 | 5 | 10 | 5 | 14 | 6 | 9.5 | 12 | 12 | 12 | 12 |  | 50 Ohms | TOP=L2:L3=L2/L4:L6=L5/L7:BOTTOM=L7 |
| TP_LPC_CPU_FRAME_N | OTHERS | BUS | 1 | 4.75 | 5 | 10 | 5 | 14 | 6 | 9.5 | 12 | 12 | 12 | 12 |  | 50 Ohms | TOP=L2:L3=L2/L4:L6=L5/L7:BOTTOM=L7 |
| TP_LPC_CPU_FRAME_N | OTHERS | BUS | 2 | 5 | 5 | 10 | 5 | 14 | 6 | 10 | 12 | 12 | 12 | 12 |  | 50 Ohms | TOP=L2:L3=L2/L4:L6=L5/L7:BOTTOM=L7 |
| TP_LPC_CPU_FRAME_N | OTHERS | BUS | 3 | 5 | 5 | 10 | 5 | 14 | 6 | 10 | 12 | 12 | 12 | 12 |  | 50 Ohms | TOP=L2:L3=L2/L4:L6=L5/L7:BOTTOM=L7 |
| TP_LPC_CPU_FRAME_N | OTHERS | BUS | 4 | 5 | 5 | 10 | 5 | 14 | 6 | 10 | 12 | 12 | 12 | 12 |  | 50 Ohms | TOP=L2:L3=L2/L4:L6=L5/L7:BOTTOM=L7 |
| TP_LPC_CPU_FRAME_N | OTHERS | BUS | 5 | 5 | 5 | 10 | 5 | 14 | 6 | 10 | 12 | 12 | 12 | 12 |  | 50 Ohms | TOP=L2:L3=L2/L4:L6=L5/L7:BOTTOM=L7 |
| TP_LPC_CPU_FRAME_N | OTHERS | BUS | 6 | 5 | 5 | 10 | 5 | 14 | 6 | 10 | 12 | 12 | 12 | 12 |  | 50 Ohms | TOP=L2:L3=L2/L4:L6=L5/L7:BOTTOM=L7 |
| TP_LPC_CPU_FRAME_N | OTHERS | BUS | 7 | 5 | 5 | 10 | 5 | 14 | 6 | 10 | 12 | 12 | 12 | 12 |  | 50 Ohms | TOP=L2:L3=L2/L4:L6=L5/L7:BOTTOM=L7 |
| TP_LPC_CPU_FRAME_N | OTHERS | BUS | 8 | 4.75 | 5 | 10 | 5 | 14 | 6 | 9.5 | 12 | 12 | 12 | 12 |  | 50 Ohms | TOP=L2:L3=L2/L4:L6=L5/L7:BOTTOM=L7 |
| TP_RGMIICK | OTHERS | BUS | 1 | 4.75 | 5 | 10 | 5 | 14 | 6 | 9.5 | 12 | 12 | 12 | 12 |  | 50 Ohms | TOP=L2:L3=L2/L4:L6=L5/L7:BOTTOM=L7 |
| TP_RGMIICK | OTHERS | BUS | 2 | 5 | 5 | 10 | 5 | 14 | 6 | 10 | 12 | 12 | 12 | 12 |  | 50 Ohms | TOP=L2:L3=L2/L4:L6=L5/L7:BOTTOM=L7 |
| TP_RGMIICK | OTHERS | BUS | 3 | 5 | 5 | 10 | 5 | 14 | 6 | 10 | 12 | 12 | 12 | 12 |  | 50 Ohms | TOP=L2:L3=L2/L4:L6=L5/L7:BOTTOM=L7 |
| TP_RGMIICK | OTHERS | BUS | 4 | 5 | 5 | 10 | 5 | 14 | 6 | 10 | 12 | 12 | 12 | 12 |  | 50 Ohms | TOP=L2:L3=L2/L4:L6=L5/L7:BOTTOM=L7 |
| TP_RGMIICK | OTHERS | BUS | 5 | 5 | 5 | 10 | 5 | 14 | 6 | 10 | 12 | 12 | 12 | 12 |  | 50 Ohms | TOP=L2:L3=L2/L4:L6=L5/L7:BOTTOM=L7 |
| TP_RGMIICK | OTHERS | BUS | 6 | 5 | 5 | 10 | 5 | 14 | 6 | 10 | 12 | 12 | 12 | 12 |  | 50 Ohms | TOP=L2:L3=L2/L4:L6=L5/L7:BOTTOM=L7 |
| TP_RGMIICK | OTHERS | BUS | 7 | 5 | 5 | 10 | 5 | 14 | 6 | 10 | 12 | 12 | 12 | 12 |  | 50 Ohms | TOP=L2:L3=L2/L4:L6=L5/L7:BOTTOM=L7 |
| TP_RGMIICK | OTHERS | BUS | 8 | 4.75 | 5 | 10 | 5 | 14 | 6 | 9.5 | 12 | 12 | 12 | 12 |  | 50 Ohms | TOP=L2:L3=L2/L4:L6=L5/L7:BOTTOM=L7 |
| TP_SDP0 | OTHERS | BUS | 1 | 4.75 | 5 | 10 | 5 | 14 | 6 | 9.5 | 12 | 12 | 12 | 12 |  | 50 Ohms | TOP=L2:L3=L2/L4:L6=L5/L7:BOTTOM=L7 |
| TP_SDP0 | OTHERS | BUS | 2 | 5 | 5 | 10 | 5 | 14 | 6 | 10 | 12 | 12 | 12 | 12 |  | 50 Ohms | TOP=L2:L3=L2/L4:L6=L5/L7:BOTTOM=L7 |
| TP_SDP0 | OTHERS | BUS | 3 | 5 | 5 | 10 | 5 | 14 | 6 | 10 | 12 | 12 | 12 | 12 |  | 50 Ohms | TOP=L2:L3=L2/L4:L6=L5/L7:BOTTOM=L7 |
| TP_SDP0 | OTHERS | BUS | 4 | 5 | 5 | 10 | 5 | 14 | 6 | 10 | 12 | 12 | 12 | 12 |  | 50 Ohms | TOP=L2:L3=L2/L4:L6=L5/L7:BOTTOM=L7 |
| TP_SDP0 | OTHERS | BUS | 5 | 5 | 5 | 10 | 5 | 14 | 6 | 10 | 12 | 12 | 12 | 12 |  | 50 Ohms | TOP=L2:L3=L2/L4:L6=L5/L7:BOTTOM=L7 |
| TP_SDP0 | OTHERS | BUS | 6 | 5 | 5 | 10 | 5 | 14 | 6 | 10 | 12 | 12 | 12 | 12 |  | 50 Ohms | TOP=L2:L3=L2/L4:L6=L5/L7:BOTTOM=L7 |
| TP_SDP0 | OTHERS | BUS | 7 | 5 | 5 | 10 | 5 | 14 | 6 | 10 | 12 | 12 | 12 | 12 |  | 50 Ohms | TOP=L2:L3=L2/L4:L6=L5/L7:BOTTOM=L7 |
| TP_SDP0 | OTHERS | BUS | 8 | 4.75 | 5 | 10 | 5 | 14 | 6 | 9.5 | 12 | 12 | 12 | 12 |  | 50 Ohms | TOP=L2:L3=L2/L4:L6=L5/L7:BOTTOM=L7 |
| TP_SDP2 | OTHERS | BUS | 1 | 4.75 | 5 | 10 | 5 | 14 | 6 | 9.5 | 12 | 12 | 12 | 12 |  | 50 Ohms | TOP=L2:L3=L2/L4:L6=L5/L7:BOTTOM=L7 |
| TP_SDP2 | OTHERS | BUS | 2 | 5 | 5 | 10 | 5 | 14 | 6 | 10 | 12 | 12 | 12 | 12 |  | 50 Ohms | TOP=L2:L3=L2/L4:L6=L5/L7:BOTTOM=L7 |
| TP_SDP2 | OTHERS | BUS | 3 | 5 | 5 | 10 | 5 | 14 | 6 | 10 | 12 | 12 | 12 | 12 |  | 50 Ohms | TOP=L2:L3=L2/L4:L6=L5/L7:BOTTOM=L7 |
| TP_SDP2 | OTHERS | BUS | 4 | 5 | 5 | 10 | 5 | 14 | 6 | 10 | 12 | 12 | 12 | 12 |  | 50 Ohms | TOP=L2:L3=L2/L4:L6=L5/L7:BOTTOM=L7 |
| TP_SDP2 | OTHERS | BUS | 5 | 5 | 5 | 10 | 5 | 14 | 6 | 10 | 12 | 12 | 12 | 12 |  | 50 Ohms | TOP=L2:L3=L2/L4:L6=L5/L7:BOTTOM=L7 |
| TP_SDP2 | OTHERS | BUS | 6 | 5 | 5 | 10 | 5 | 14 | 6 | 10 | 12 | 12 | 12 | 12 |  | 50 Ohms | TOP=L2:L3=L2/L4:L6=L5/L7:BOTTOM=L7 |
| TP_SDP2 | OTHERS | BUS | 7 | 5 | 5 | 10 | 5 | 14 | 6 | 10 | 12 | 12 | 12 | 12 |  | 50 Ohms | TOP=L2:L3=L2/L4:L6=L5/L7:BOTTOM=L7 |
| TP_SDP2 | OTHERS | BUS | 8 | 4.75 | 5 | 10 | 5 | 14 | 6 | 9.5 | 12 | 12 | 12 | 12 |  | 50 Ohms | TOP=L2:L3=L2/L4:L6=L5/L7:BOTTOM=L7 |
| TP_SDP3 | OTHERS | BUS | 1 | 4.75 | 5 | 10 | 5 | 14 | 6 | 9.5 | 12 | 12 | 12 | 12 |  | 50 Ohms | TOP=L2:L3=L2/L4:L6=L5/L7:BOTTOM=L7 |
| TP_SDP3 | OTHERS | BUS | 2 | 5 | 5 | 10 | 5 | 14 | 6 | 10 | 12 | 12 | 12 | 12 |  | 50 Ohms | TOP=L2:L3=L2/L4:L6=L5/L7:BOTTOM=L7 |
| TP_SDP3 | OTHERS | BUS | 3 | 5 | 5 | 10 | 5 | 14 | 6 | 10 | 12 | 12 | 12 | 12 |  | 50 Ohms | TOP=L2:L3=L2/L4:L6=L5/L7:BOTTOM=L7 |
| TP_SDP3 | OTHERS | BUS | 4 | 5 | 5 | 10 | 5 | 14 | 6 | 10 | 12 | 12 | 12 | 12 |  | 50 Ohms | TOP=L2:L3=L2/L4:L6=L5/L7:BOTTOM=L7 |
| TP_SDP3 | OTHERS | BUS | 5 | 5 | 5 | 10 | 5 | 14 | 6 | 10 | 12 | 12 | 12 | 12 |  | 50 Ohms | TOP=L2:L3=L2/L4:L6=L5/L7:BOTTOM=L7 |
| TP_SDP3 | OTHERS | BUS | 6 | 5 | 5 | 10 | 5 | 14 | 6 | 10 | 12 | 12 | 12 | 12 |  | 50 Ohms | TOP=L2:L3=L2/L4:L6=L5/L7:BOTTOM=L7 |
| TP_SDP3 | OTHERS | BUS | 7 | 5 | 5 | 10 | 5 | 14 | 6 | 10 | 12 | 12 | 12 | 12 |  | 50 Ohms | TOP=L2:L3=L2/L4:L6=L5/L7:BOTTOM=L7 |
| TP_SDP3 | OTHERS | BUS | 8 | 4.75 | 5 | 10 | 5 | 14 | 6 | 9.5 | 12 | 12 | 12 | 12 |  | 50 Ohms | TOP=L2:L3=L2/L4:L6=L5/L7:BOTTOM=L7 |
| TPIN | OTHERS | BUS | 1 | 4.75 | 5 | 10 | 5 | 14 | 6 | 9.5 | 12 | 12 | 12 | 12 |  | 50 Ohms | TOP=L2:L3=L2/L4:L6=L5/L7:BOTTOM=L7 |
| TPIN | OTHERS | BUS | 2 | 5 | 5 | 10 | 5 | 14 | 6 | 10 | 12 | 12 | 12 | 12 |  | 50 Ohms | TOP=L2:L3=L2/L4:L6=L5/L7:BOTTOM=L7 |
| TPIN | OTHERS | BUS | 3 | 5 | 5 | 10 | 5 | 14 | 6 | 10 | 12 | 12 | 12 | 12 |  | 50 Ohms | TOP=L2:L3=L2/L4:L6=L5/L7:BOTTOM=L7 |
| TPIN | OTHERS | BUS | 4 | 5 | 5 | 10 | 5 | 14 | 6 | 10 | 12 | 12 | 12 | 12 |  | 50 Ohms | TOP=L2:L3=L2/L4:L6=L5/L7:BOTTOM=L7 |
| TPIN | OTHERS | BUS | 5 | 5 | 5 | 10 | 5 | 14 | 6 | 10 | 12 | 12 | 12 | 12 |  | 50 Ohms | TOP=L2:L3=L2/L4:L6=L5/L7:BOTTOM=L7 |
| TPIN | OTHERS | BUS | 6 | 5 | 5 | 10 | 5 | 14 | 6 | 10 | 12 | 12 | 12 | 12 |  | 50 Ohms | TOP=L2:L3=L2/L4:L6=L5/L7:BOTTOM=L7 |
| TPIN | OTHERS | BUS | 7 | 5 | 5 | 10 | 5 | 14 | 6 | 10 | 12 | 12 | 12 | 12 |  | 50 Ohms | TOP=L2:L3=L2/L4:L6=L5/L7:BOTTOM=L7 |
| TPIN | OTHERS | BUS | 8 | 4.75 | 5 | 10 | 5 | 14 | 6 | 9.5 | 12 | 12 | 12 | 12 |  | 50 Ohms | TOP=L2:L3=L2/L4:L6=L5/L7:BOTTOM=L7 |
| TRAY_ID0 | OTHERS | BUS | 1 | 4.75 | 5 | 10 | 5 | 14 | 6 | 9.5 | 12 | 12 | 12 | 12 |  | 50 Ohms | TOP=L2:L3=L2/L4:L6=L5/L7:BOTTOM=L7 |
| TRAY_ID0 | OTHERS | BUS | 2 | 5 | 5 | 10 | 5 | 14 | 6 | 10 | 12 | 12 | 12 | 12 |  | 50 Ohms | TOP=L2:L3=L2/L4:L6=L5/L7:BOTTOM=L7 |
| TRAY_ID0 | OTHERS | BUS | 3 | 5 | 5 | 10 | 5 | 14 | 6 | 10 | 12 | 12 | 12 | 12 |  | 50 Ohms | TOP=L2:L3=L2/L4:L6=L5/L7:BOTTOM=L7 |
| TRAY_ID0 | OTHERS | BUS | 4 | 5 | 5 | 10 | 5 | 14 | 6 | 10 | 12 | 12 | 12 | 12 |  | 50 Ohms | TOP=L2:L3=L2/L4:L6=L5/L7:BOTTOM=L7 |
| TRAY_ID0 | OTHERS | BUS | 5 | 5 | 5 | 10 | 5 | 14 | 6 | 10 | 12 | 12 | 12 | 12 |  | 50 Ohms | TOP=L2:L3=L2/L4:L6=L5/L7:BOTTOM=L7 |
| TRAY_ID0 | OTHERS | BUS | 6 | 5 | 5 | 10 | 5 | 14 | 6 | 10 | 12 | 12 | 12 | 12 |  | 50 Ohms | TOP=L2:L3=L2/L4:L6=L5/L7:BOTTOM=L7 |
| TRAY_ID0 | OTHERS | BUS | 7 | 5 | 5 | 10 | 5 | 14 | 6 | 10 | 12 | 12 | 12 | 12 |  | 50 Ohms | TOP=L2:L3=L2/L4:L6=L5/L7:BOTTOM=L7 |
| TRAY_ID0 | OTHERS | BUS | 8 | 4.75 | 5 | 10 | 5 | 14 | 6 | 9.5 | 12 | 12 | 12 | 12 |  | 50 Ohms | TOP=L2:L3=L2/L4:L6=L5/L7:BOTTOM=L7 |
| TRAY_ID1 | OTHERS | BUS | 1 | 4.75 | 5 | 10 | 5 | 14 | 6 | 9.5 | 12 | 12 | 12 | 12 |  | 50 Ohms | TOP=L2:L3=L2/L4:L6=L5/L7:BOTTOM=L7 |
| TRAY_ID1 | OTHERS | BUS | 2 | 5 | 5 | 10 | 5 | 14 | 6 | 10 | 12 | 12 | 12 | 12 |  | 50 Ohms | TOP=L2:L3=L2/L4:L6=L5/L7:BOTTOM=L7 |
| TRAY_ID1 | OTHERS | BUS | 3 | 5 | 5 | 10 | 5 | 14 | 6 | 10 | 12 | 12 | 12 | 12 |  | 50 Ohms | TOP=L2:L3=L2/L4:L6=L5/L7:BOTTOM=L7 |
| TRAY_ID1 | OTHERS | BUS | 4 | 5 | 5 | 10 | 5 | 14 | 6 | 10 | 12 | 12 | 12 | 12 |  | 50 Ohms | TOP=L2:L3=L2/L4:L6=L5/L7:BOTTOM=L7 |
| TRAY_ID1 | OTHERS | BUS | 5 | 5 | 5 | 10 | 5 | 14 | 6 | 10 | 12 | 12 | 12 | 12 |  | 50 Ohms | TOP=L2:L3=L2/L4:L6=L5/L7:BOTTOM=L7 |
| TRAY_ID1 | OTHERS | BUS | 6 | 5 | 5 | 10 | 5 | 14 | 6 | 10 | 12 | 12 | 12 | 12 |  | 50 Ohms | TOP=L2:L3=L2/L4:L6=L5/L7:BOTTOM=L7 |
| TRAY_ID1 | OTHERS | BUS | 7 | 5 | 5 | 10 | 5 | 14 | 6 | 10 | 12 | 12 | 12 | 12 |  | 50 Ohms | TOP=L2:L3=L2/L4:L6=L5/L7:BOTTOM=L7 |
| TRAY_ID1 | OTHERS | BUS | 8 | 4.75 | 5 | 10 | 5 | 14 | 6 | 9.5 | 12 | 12 | 12 | 12 |  | 50 Ohms | TOP=L2:L3=L2/L4:L6=L5/L7:BOTTOM=L7 |
| TRAY_ID2 | OTHERS | BUS | 1 | 4.75 | 5 | 10 | 5 | 14 | 6 | 9.5 | 12 | 12 | 12 | 12 |  | 50 Ohms | TOP=L2:L3=L2/L4:L6=L5/L7:BOTTOM=L7 |
| TRAY_ID2 | OTHERS | BUS | 2 | 5 | 5 | 10 | 5 | 14 | 6 | 10 | 12 | 12 | 12 | 12 |  | 50 Ohms | TOP=L2:L3=L2/L4:L6=L5/L7:BOTTOM=L7 |
| TRAY_ID2 | OTHERS | BUS | 3 | 5 | 5 | 10 | 5 | 14 | 6 | 10 | 12 | 12 | 12 | 12 |  | 50 Ohms | TOP=L2:L3=L2/L4:L6=L5/L7:BOTTOM=L7 |
| TRAY_ID2 | OTHERS | BUS | 4 | 5 | 5 | 10 | 5 | 14 | 6 | 10 | 12 | 12 | 12 | 12 |  | 50 Ohms | TOP=L2:L3=L2/L4:L6=L5/L7:BOTTOM=L7 |
| TRAY_ID2 | OTHERS | BUS | 5 | 5 | 5 | 10 | 5 | 14 | 6 | 10 | 12 | 12 | 12 | 12 |  | 50 Ohms | TOP=L2:L3=L2/L4:L6=L5/L7:BOTTOM=L7 |
| TRAY_ID2 | OTHERS | BUS | 6 | 5 | 5 | 10 | 5 | 14 | 6 | 10 | 12 | 12 | 12 | 12 |  | 50 Ohms | TOP=L2:L3=L2/L4:L6=L5/L7:BOTTOM=L7 |
| TRAY_ID2 | OTHERS | BUS | 7 | 5 | 5 | 10 | 5 | 14 | 6 | 10 | 12 | 12 | 12 | 12 |  | 50 Ohms | TOP=L2:L3=L2/L4:L6=L5/L7:BOTTOM=L7 |
| TRAY_ID2 | OTHERS | BUS | 8 | 4.75 | 5 | 10 | 5 | 14 | 6 | 9.5 | 12 | 12 | 12 | 12 |  | 50 Ohms | TOP=L2:L3=L2/L4:L6=L5/L7:BOTTOM=L7 |
| TRAY_MBP_CTRL_EN_N | OTHERS | BUS | 1 | 4.75 | 5 | 10 | 5 | 14 | 6 | 9.5 | 12 | 12 | 12 | 12 |  | 50 Ohms | TOP=L2:L3=L2/L4:L6=L5/L7:BOTTOM=L7 |
| TRAY_MBP_CTRL_EN_N | OTHERS | BUS | 2 | 5 | 5 | 10 | 5 | 14 | 6 | 10 | 12 | 12 | 12 | 12 |  | 50 Ohms | TOP=L2:L3=L2/L4:L6=L5/L7:BOTTOM=L7 |
| TRAY_MBP_CTRL_EN_N | OTHERS | BUS | 3 | 5 | 5 | 10 | 5 | 14 | 6 | 10 | 12 | 12 | 12 | 12 |  | 50 Ohms | TOP=L2:L3=L2/L4:L6=L5/L7:BOTTOM=L7 |
| TRAY_MBP_CTRL_EN_N | OTHERS | BUS | 4 | 5 | 5 | 10 | 5 | 14 | 6 | 10 | 12 | 12 | 12 | 12 |  | 50 Ohms | TOP=L2:L3=L2/L4:L6=L5/L7:BOTTOM=L7 |
| TRAY_MBP_CTRL_EN_N | OTHERS | BUS | 5 | 5 | 5 | 10 | 5 | 14 | 6 | 10 | 12 | 12 | 12 | 12 |  | 50 Ohms | TOP=L2:L3=L2/L4:L6=L5/L7:BOTTOM=L7 |
| TRAY_MBP_CTRL_EN_N | OTHERS | BUS | 6 | 5 | 5 | 10 | 5 | 14 | 6 | 10 | 12 | 12 | 12 | 12 |  | 50 Ohms | TOP=L2:L3=L2/L4:L6=L5/L7:BOTTOM=L7 |
| TRAY_MBP_CTRL_EN_N | OTHERS | BUS | 7 | 5 | 5 | 10 | 5 | 14 | 6 | 10 | 12 | 12 | 12 | 12 |  | 50 Ohms | TOP=L2:L3=L2/L4:L6=L5/L7:BOTTOM=L7 |
| TRAY_MBP_CTRL_EN_N | OTHERS | BUS | 8 | 4.75 | 5 | 10 | 5 | 14 | 6 | 9.5 | 12 | 12 | 12 | 12 |  | 50 Ohms | TOP=L2:L3=L2/L4:L6=L5/L7:BOTTOM=L7 |
| TRAY_POWER_CRIT_N | OTHERS | BUS | 1 | 4.75 | 5 | 10 | 5 | 14 | 6 | 9.5 | 12 | 12 | 12 | 12 |  | 50 Ohms | TOP=L2:L3=L2/L4:L6=L5/L7:BOTTOM=L7 |
| TRAY_POWER_CRIT_N | OTHERS | BUS | 2 | 5 | 5 | 10 | 5 | 14 | 6 | 10 | 12 | 12 | 12 | 12 |  | 50 Ohms | TOP=L2:L3=L2/L4:L6=L5/L7:BOTTOM=L7 |
| TRAY_POWER_CRIT_N | OTHERS | BUS | 3 | 5 | 5 | 10 | 5 | 14 | 6 | 10 | 12 | 12 | 12 | 12 |  | 50 Ohms | TOP=L2:L3=L2/L4:L6=L5/L7:BOTTOM=L7 |
| TRAY_POWER_CRIT_N | OTHERS | BUS | 4 | 5 | 5 | 10 | 5 | 14 | 6 | 10 | 12 | 12 | 12 | 12 |  | 50 Ohms | TOP=L2:L3=L2/L4:L6=L5/L7:BOTTOM=L7 |
| TRAY_POWER_CRIT_N | OTHERS | BUS | 5 | 5 | 5 | 10 | 5 | 14 | 6 | 10 | 12 | 12 | 12 | 12 |  | 50 Ohms | TOP=L2:L3=L2/L4:L6=L5/L7:BOTTOM=L7 |
| TRAY_POWER_CRIT_N | OTHERS | BUS | 6 | 5 | 5 | 10 | 5 | 14 | 6 | 10 | 12 | 12 | 12 | 12 |  | 50 Ohms | TOP=L2:L3=L2/L4:L6=L5/L7:BOTTOM=L7 |
| TRAY_POWER_CRIT_N | OTHERS | BUS | 7 | 5 | 5 | 10 | 5 | 14 | 6 | 10 | 12 | 12 | 12 | 12 |  | 50 Ohms | TOP=L2:L3=L2/L4:L6=L5/L7:BOTTOM=L7 |
| TRAY_POWER_CRIT_N | OTHERS | BUS | 8 | 4.75 | 5 | 10 | 5 | 14 | 6 | 9.5 | 12 | 12 | 12 | 12 |  | 50 Ohms | TOP=L2:L3=L2/L4:L6=L5/L7:BOTTOM=L7 |
| TRAY_RESET_N | OTHERS | BUS | 1 | 4.75 | 5 | 10 | 5 | 14 | 6 | 9.5 | 12 | 12 | 12 | 12 |  | 50 Ohms | TOP=L2:L3=L2/L4:L6=L5/L7:BOTTOM=L7 |
| TRAY_RESET_N | OTHERS | BUS | 2 | 5 | 5 | 10 | 5 | 14 | 6 | 10 | 12 | 12 | 12 | 12 |  | 50 Ohms | TOP=L2:L3=L2/L4:L6=L5/L7:BOTTOM=L7 |
| TRAY_RESET_N | OTHERS | BUS | 3 | 5 | 5 | 10 | 5 | 14 | 6 | 10 | 12 | 12 | 12 | 12 |  | 50 Ohms | TOP=L2:L3=L2/L4:L6=L5/L7:BOTTOM=L7 |
| TRAY_RESET_N | OTHERS | BUS | 4 | 5 | 5 | 10 | 5 | 14 | 6 | 10 | 12 | 12 | 12 | 12 |  | 50 Ohms | TOP=L2:L3=L2/L4:L6=L5/L7:BOTTOM=L7 |
| TRAY_RESET_N | OTHERS | BUS | 5 | 5 | 5 | 10 | 5 | 14 | 6 | 10 | 12 | 12 | 12 | 12 |  | 50 Ohms | TOP=L2:L3=L2/L4:L6=L5/L7:BOTTOM=L7 |
| TRAY_RESET_N | OTHERS | BUS | 6 | 5 | 5 | 10 | 5 | 14 | 6 | 10 | 12 | 12 | 12 | 12 |  | 50 Ohms | TOP=L2:L3=L2/L4:L6=L5/L7:BOTTOM=L7 |
| TRAY_RESET_N | OTHERS | BUS | 7 | 5 | 5 | 10 | 5 | 14 | 6 | 10 | 12 | 12 | 12 | 12 |  | 50 Ohms | TOP=L2:L3=L2/L4:L6=L5/L7:BOTTOM=L7 |
| TRAY_RESET_N | OTHERS | BUS | 8 | 4.75 | 5 | 10 | 5 | 14 | 6 | 9.5 | 12 | 12 | 12 | 12 |  | 50 Ohms | TOP=L2:L3=L2/L4:L6=L5/L7:BOTTOM=L7 |
| TRAY_RESET_N_R | OTHERS | BUS | 1 | 4.75 | 5 | 10 | 5 | 14 | 6 | 9.5 | 12 | 12 | 12 | 12 |  | 50 Ohms | TOP=L2:L3=L2/L4:L6=L5/L7:BOTTOM=L7 |
| TRAY_RESET_N_R | OTHERS | BUS | 2 | 5 | 5 | 10 | 5 | 14 | 6 | 10 | 12 | 12 | 12 | 12 |  | 50 Ohms | TOP=L2:L3=L2/L4:L6=L5/L7:BOTTOM=L7 |
| TRAY_RESET_N_R | OTHERS | BUS | 3 | 5 | 5 | 10 | 5 | 14 | 6 | 10 | 12 | 12 | 12 | 12 |  | 50 Ohms | TOP=L2:L3=L2/L4:L6=L5/L7:BOTTOM=L7 |
| TRAY_RESET_N_R | OTHERS | BUS | 4 | 5 | 5 | 10 | 5 | 14 | 6 | 10 | 12 | 12 | 12 | 12 |  | 50 Ohms | TOP=L2:L3=L2/L4:L6=L5/L7:BOTTOM=L7 |
| TRAY_RESET_N_R | OTHERS | BUS | 5 | 5 | 5 | 10 | 5 | 14 | 6 | 10 | 12 | 12 | 12 | 12 |  | 50 Ohms | TOP=L2:L3=L2/L4:L6=L5/L7:BOTTOM=L7 |
| TRAY_RESET_N_R | OTHERS | BUS | 6 | 5 | 5 | 10 | 5 | 14 | 6 | 10 | 12 | 12 | 12 | 12 |  | 50 Ohms | TOP=L2:L3=L2/L4:L6=L5/L7:BOTTOM=L7 |
| TRAY_RESET_N_R | OTHERS | BUS | 7 | 5 | 5 | 10 | 5 | 14 | 6 | 10 | 12 | 12 | 12 | 12 |  | 50 Ohms | TOP=L2:L3=L2/L4:L6=L5/L7:BOTTOM=L7 |
| TRAY_RESET_N_R | OTHERS | BUS | 8 | 4.75 | 5 | 10 | 5 | 14 | 6 | 9.5 | 12 | 12 | 12 | 12 |  | 50 Ohms | TOP=L2:L3=L2/L4:L6=L5/L7:BOTTOM=L7 |
| TWI_SDA9 | OTHERS | BUS | 1 | 4.75 | 5 | 10 | 5 | 14 | 6 | 9.5 | 12 | 12 | 12 | 12 |  | 50 Ohms | TOP=L2:L3=L2/L4:L6=L5/L7:BOTTOM=L7 |
| TWI_SDA9 | OTHERS | BUS | 2 | 5 | 5 | 10 | 5 | 14 | 6 | 10 | 12 | 12 | 12 | 12 |  | 50 Ohms | TOP=L2:L3=L2/L4:L6=L5/L7:BOTTOM=L7 |
| TWI_SDA9 | OTHERS | BUS | 3 | 5 | 5 | 10 | 5 | 14 | 6 | 10 | 12 | 12 | 12 | 12 |  | 50 Ohms | TOP=L2:L3=L2/L4:L6=L5/L7:BOTTOM=L7 |
| TWI_SDA9 | OTHERS | BUS | 4 | 5 | 5 | 10 | 5 | 14 | 6 | 10 | 12 | 12 | 12 | 12 |  | 50 Ohms | TOP=L2:L3=L2/L4:L6=L5/L7:BOTTOM=L7 |
| TWI_SDA9 | OTHERS | BUS | 5 | 5 | 5 | 10 | 5 | 14 | 6 | 10 | 12 | 12 | 12 | 12 |  | 50 Ohms | TOP=L2:L3=L2/L4:L6=L5/L7:BOTTOM=L7 |
| TWI_SDA9 | OTHERS | BUS | 6 | 5 | 5 | 10 | 5 | 14 | 6 | 10 | 12 | 12 | 12 | 12 |  | 50 Ohms | TOP=L2:L3=L2/L4:L6=L5/L7:BOTTOM=L7 |
| TWI_SDA9 | OTHERS | BUS | 7 | 5 | 5 | 10 | 5 | 14 | 6 | 10 | 12 | 12 | 12 | 12 |  | 50 Ohms | TOP=L2:L3=L2/L4:L6=L5/L7:BOTTOM=L7 |
| TWI_SDA9 | OTHERS | BUS | 8 | 4.75 | 5 | 10 | 5 | 14 | 6 | 9.5 | 12 | 12 | 12 | 12 |  | 50 Ohms | TOP=L2:L3=L2/L4:L6=L5/L7:BOTTOM=L7 |
| TWI_SRST#0 | OTHERS | BUS | 1 | 4.75 | 5 | 10 | 5 | 14 | 6 | 9.5 | 12 | 12 | 12 | 12 |  | 50 Ohms | TOP=L2:L3=L2/L4:L6=L5/L7:BOTTOM=L7 |
| TWI_SRST#0 | OTHERS | BUS | 2 | 5 | 5 | 10 | 5 | 14 | 6 | 10 | 12 | 12 | 12 | 12 |  | 50 Ohms | TOP=L2:L3=L2/L4:L6=L5/L7:BOTTOM=L7 |
| TWI_SRST#0 | OTHERS | BUS | 3 | 5 | 5 | 10 | 5 | 14 | 6 | 10 | 12 | 12 | 12 | 12 |  | 50 Ohms | TOP=L2:L3=L2/L4:L6=L5/L7:BOTTOM=L7 |
| TWI_SRST#0 | OTHERS | BUS | 4 | 5 | 5 | 10 | 5 | 14 | 6 | 10 | 12 | 12 | 12 | 12 |  | 50 Ohms | TOP=L2:L3=L2/L4:L6=L5/L7:BOTTOM=L7 |
| TWI_SRST#0 | OTHERS | BUS | 5 | 5 | 5 | 10 | 5 | 14 | 6 | 10 | 12 | 12 | 12 | 12 |  | 50 Ohms | TOP=L2:L3=L2/L4:L6=L5/L7:BOTTOM=L7 |
| TWI_SRST#0 | OTHERS | BUS | 6 | 5 | 5 | 10 | 5 | 14 | 6 | 10 | 12 | 12 | 12 | 12 |  | 50 Ohms | TOP=L2:L3=L2/L4:L6=L5/L7:BOTTOM=L7 |
| TWI_SRST#0 | OTHERS | BUS | 7 | 5 | 5 | 10 | 5 | 14 | 6 | 10 | 12 | 12 | 12 | 12 |  | 50 Ohms | TOP=L2:L3=L2/L4:L6=L5/L7:BOTTOM=L7 |
| TWI_SRST#0 | OTHERS | BUS | 8 | 4.75 | 5 | 10 | 5 | 14 | 6 | 9.5 | 12 | 12 | 12 | 12 |  | 50 Ohms | TOP=L2:L3=L2/L4:L6=L5/L7:BOTTOM=L7 |
| TWI_SRST#1 | OTHERS | BUS | 1 | 4.75 | 5 | 10 | 5 | 14 | 6 | 9.5 | 12 | 12 | 12 | 12 |  | 50 Ohms | TOP=L2:L3=L2/L4:L6=L5/L7:BOTTOM=L7 |
| TWI_SRST#1 | OTHERS | BUS | 2 | 5 | 5 | 10 | 5 | 14 | 6 | 10 | 12 | 12 | 12 | 12 |  | 50 Ohms | TOP=L2:L3=L2/L4:L6=L5/L7:BOTTOM=L7 |
| TWI_SRST#1 | OTHERS | BUS | 3 | 5 | 5 | 10 | 5 | 14 | 6 | 10 | 12 | 12 | 12 | 12 |  | 50 Ohms | TOP=L2:L3=L2/L4:L6=L5/L7:BOTTOM=L7 |
| TWI_SRST#1 | OTHERS | BUS | 4 | 5 | 5 | 10 | 5 | 14 | 6 | 10 | 12 | 12 | 12 | 12 |  | 50 Ohms | TOP=L2:L3=L2/L4:L6=L5/L7:BOTTOM=L7 |
| TWI_SRST#1 | OTHERS | BUS | 5 | 5 | 5 | 10 | 5 | 14 | 6 | 10 | 12 | 12 | 12 | 12 |  | 50 Ohms | TOP=L2:L3=L2/L4:L6=L5/L7:BOTTOM=L7 |
| TWI_SRST#1 | OTHERS | BUS | 6 | 5 | 5 | 10 | 5 | 14 | 6 | 10 | 12 | 12 | 12 | 12 |  | 50 Ohms | TOP=L2:L3=L2/L4:L6=L5/L7:BOTTOM=L7 |
| TWI_SRST#1 | OTHERS | BUS | 7 | 5 | 5 | 10 | 5 | 14 | 6 | 10 | 12 | 12 | 12 | 12 |  | 50 Ohms | TOP=L2:L3=L2/L4:L6=L5/L7:BOTTOM=L7 |
| TWI_SRST#1 | OTHERS | BUS | 8 | 4.75 | 5 | 10 | 5 | 14 | 6 | 9.5 | 12 | 12 | 12 | 12 |  | 50 Ohms | TOP=L2:L3=L2/L4:L6=L5/L7:BOTTOM=L7 |
| TWI_SRST#2 | OTHERS | BUS | 1 | 4.75 | 5 | 10 | 5 | 14 | 6 | 9.5 | 12 | 12 | 12 | 12 |  | 50 Ohms | TOP=L2:L3=L2/L4:L6=L5/L7:BOTTOM=L7 |
| TWI_SRST#2 | OTHERS | BUS | 2 | 5 | 5 | 10 | 5 | 14 | 6 | 10 | 12 | 12 | 12 | 12 |  | 50 Ohms | TOP=L2:L3=L2/L4:L6=L5/L7:BOTTOM=L7 |
| TWI_SRST#2 | OTHERS | BUS | 3 | 5 | 5 | 10 | 5 | 14 | 6 | 10 | 12 | 12 | 12 | 12 |  | 50 Ohms | TOP=L2:L3=L2/L4:L6=L5/L7:BOTTOM=L7 |
| TWI_SRST#2 | OTHERS | BUS | 4 | 5 | 5 | 10 | 5 | 14 | 6 | 10 | 12 | 12 | 12 | 12 |  | 50 Ohms | TOP=L2:L3=L2/L4:L6=L5/L7:BOTTOM=L7 |
| TWI_SRST#2 | OTHERS | BUS | 5 | 5 | 5 | 10 | 5 | 14 | 6 | 10 | 12 | 12 | 12 | 12 |  | 50 Ohms | TOP=L2:L3=L2/L4:L6=L5/L7:BOTTOM=L7 |
| TWI_SRST#2 | OTHERS | BUS | 6 | 5 | 5 | 10 | 5 | 14 | 6 | 10 | 12 | 12 | 12 | 12 |  | 50 Ohms | TOP=L2:L3=L2/L4:L6=L5/L7:BOTTOM=L7 |
| TWI_SRST#2 | OTHERS | BUS | 7 | 5 | 5 | 10 | 5 | 14 | 6 | 10 | 12 | 12 | 12 | 12 |  | 50 Ohms | TOP=L2:L3=L2/L4:L6=L5/L7:BOTTOM=L7 |
| TWI_SRST#2 | OTHERS | BUS | 8 | 4.75 | 5 | 10 | 5 | 14 | 6 | 9.5 | 12 | 12 | 12 | 12 |  | 50 Ohms | TOP=L2:L3=L2/L4:L6=L5/L7:BOTTOM=L7 |
| TWI_SRST#3 | OTHERS | BUS | 1 | 4.75 | 5 | 10 | 5 | 14 | 6 | 9.5 | 12 | 12 | 12 | 12 |  | 50 Ohms | TOP=L2:L3=L2/L4:L6=L5/L7:BOTTOM=L7 |
| TWI_SRST#3 | OTHERS | BUS | 2 | 5 | 5 | 10 | 5 | 14 | 6 | 10 | 12 | 12 | 12 | 12 |  | 50 Ohms | TOP=L2:L3=L2/L4:L6=L5/L7:BOTTOM=L7 |
| TWI_SRST#3 | OTHERS | BUS | 3 | 5 | 5 | 10 | 5 | 14 | 6 | 10 | 12 | 12 | 12 | 12 |  | 50 Ohms | TOP=L2:L3=L2/L4:L6=L5/L7:BOTTOM=L7 |
| TWI_SRST#3 | OTHERS | BUS | 4 | 5 | 5 | 10 | 5 | 14 | 6 | 10 | 12 | 12 | 12 | 12 |  | 50 Ohms | TOP=L2:L3=L2/L4:L6=L5/L7:BOTTOM=L7 |
| TWI_SRST#3 | OTHERS | BUS | 5 | 5 | 5 | 10 | 5 | 14 | 6 | 10 | 12 | 12 | 12 | 12 |  | 50 Ohms | TOP=L2:L3=L2/L4:L6=L5/L7:BOTTOM=L7 |
| TWI_SRST#3 | OTHERS | BUS | 6 | 5 | 5 | 10 | 5 | 14 | 6 | 10 | 12 | 12 | 12 | 12 |  | 50 Ohms | TOP=L2:L3=L2/L4:L6=L5/L7:BOTTOM=L7 |
| TWI_SRST#3 | OTHERS | BUS | 7 | 5 | 5 | 10 | 5 | 14 | 6 | 10 | 12 | 12 | 12 | 12 |  | 50 Ohms | TOP=L2:L3=L2/L4:L6=L5/L7:BOTTOM=L7 |
| TWI_SRST#3 | OTHERS | BUS | 8 | 4.75 | 5 | 10 | 5 | 14 | 6 | 9.5 | 12 | 12 | 12 | 12 |  | 50 Ohms | TOP=L2:L3=L2/L4:L6=L5/L7:BOTTOM=L7 |
| TWI_SRST#4 | OTHERS | BUS | 1 | 4.75 | 5 | 10 | 5 | 14 | 6 | 9.5 | 12 | 12 | 12 | 12 |  | 50 Ohms | TOP=L2:L3=L2/L4:L6=L5/L7:BOTTOM=L7 |
| TWI_SRST#4 | OTHERS | BUS | 2 | 5 | 5 | 10 | 5 | 14 | 6 | 10 | 12 | 12 | 12 | 12 |  | 50 Ohms | TOP=L2:L3=L2/L4:L6=L5/L7:BOTTOM=L7 |
| TWI_SRST#4 | OTHERS | BUS | 3 | 5 | 5 | 10 | 5 | 14 | 6 | 10 | 12 | 12 | 12 | 12 |  | 50 Ohms | TOP=L2:L3=L2/L4:L6=L5/L7:BOTTOM=L7 |
| TWI_SRST#4 | OTHERS | BUS | 4 | 5 | 5 | 10 | 5 | 14 | 6 | 10 | 12 | 12 | 12 | 12 |  | 50 Ohms | TOP=L2:L3=L2/L4:L6=L5/L7:BOTTOM=L7 |
| TWI_SRST#4 | OTHERS | BUS | 5 | 5 | 5 | 10 | 5 | 14 | 6 | 10 | 12 | 12 | 12 | 12 |  | 50 Ohms | TOP=L2:L3=L2/L4:L6=L5/L7:BOTTOM=L7 |
| TWI_SRST#4 | OTHERS | BUS | 6 | 5 | 5 | 10 | 5 | 14 | 6 | 10 | 12 | 12 | 12 | 12 |  | 50 Ohms | TOP=L2:L3=L2/L4:L6=L5/L7:BOTTOM=L7 |
| TWI_SRST#4 | OTHERS | BUS | 7 | 5 | 5 | 10 | 5 | 14 | 6 | 10 | 12 | 12 | 12 | 12 |  | 50 Ohms | TOP=L2:L3=L2/L4:L6=L5/L7:BOTTOM=L7 |
| TWI_SRST#4 | OTHERS | BUS | 8 | 4.75 | 5 | 10 | 5 | 14 | 6 | 9.5 | 12 | 12 | 12 | 12 |  | 50 Ohms | TOP=L2:L3=L2/L4:L6=L5/L7:BOTTOM=L7 |
| TWI_SRST#5 | OTHERS | BUS | 1 | 4.75 | 5 | 10 | 5 | 14 | 6 | 9.5 | 12 | 12 | 12 | 12 |  | 50 Ohms | TOP=L2:L3=L2/L4:L6=L5/L7:BOTTOM=L7 |
| TWI_SRST#5 | OTHERS | BUS | 2 | 5 | 5 | 10 | 5 | 14 | 6 | 10 | 12 | 12 | 12 | 12 |  | 50 Ohms | TOP=L2:L3=L2/L4:L6=L5/L7:BOTTOM=L7 |
| TWI_SRST#5 | OTHERS | BUS | 3 | 5 | 5 | 10 | 5 | 14 | 6 | 10 | 12 | 12 | 12 | 12 |  | 50 Ohms | TOP=L2:L3=L2/L4:L6=L5/L7:BOTTOM=L7 |
| TWI_SRST#5 | OTHERS | BUS | 4 | 5 | 5 | 10 | 5 | 14 | 6 | 10 | 12 | 12 | 12 | 12 |  | 50 Ohms | TOP=L2:L3=L2/L4:L6=L5/L7:BOTTOM=L7 |
| TWI_SRST#5 | OTHERS | BUS | 5 | 5 | 5 | 10 | 5 | 14 | 6 | 10 | 12 | 12 | 12 | 12 |  | 50 Ohms | TOP=L2:L3=L2/L4:L6=L5/L7:BOTTOM=L7 |
| TWI_SRST#5 | OTHERS | BUS | 6 | 5 | 5 | 10 | 5 | 14 | 6 | 10 | 12 | 12 | 12 | 12 |  | 50 Ohms | TOP=L2:L3=L2/L4:L6=L5/L7:BOTTOM=L7 |
| TWI_SRST#5 | OTHERS | BUS | 7 | 5 | 5 | 10 | 5 | 14 | 6 | 10 | 12 | 12 | 12 | 12 |  | 50 Ohms | TOP=L2:L3=L2/L4:L6=L5/L7:BOTTOM=L7 |
| TWI_SRST#5 | OTHERS | BUS | 8 | 4.75 | 5 | 10 | 5 | 14 | 6 | 9.5 | 12 | 12 | 12 | 12 |  | 50 Ohms | TOP=L2:L3=L2/L4:L6=L5/L7:BOTTOM=L7 |
| TWI_SRST#6 | OTHERS | BUS | 1 | 4.75 | 5 | 10 | 5 | 14 | 6 | 9.5 | 12 | 12 | 12 | 12 |  | 50 Ohms | TOP=L2:L3=L2/L4:L6=L5/L7:BOTTOM=L7 |
| TWI_SRST#6 | OTHERS | BUS | 2 | 5 | 5 | 10 | 5 | 14 | 6 | 10 | 12 | 12 | 12 | 12 |  | 50 Ohms | TOP=L2:L3=L2/L4:L6=L5/L7:BOTTOM=L7 |
| TWI_SRST#6 | OTHERS | BUS | 3 | 5 | 5 | 10 | 5 | 14 | 6 | 10 | 12 | 12 | 12 | 12 |  | 50 Ohms | TOP=L2:L3=L2/L4:L6=L5/L7:BOTTOM=L7 |
| TWI_SRST#6 | OTHERS | BUS | 4 | 5 | 5 | 10 | 5 | 14 | 6 | 10 | 12 | 12 | 12 | 12 |  | 50 Ohms | TOP=L2:L3=L2/L4:L6=L5/L7:BOTTOM=L7 |
| TWI_SRST#6 | OTHERS | BUS | 5 | 5 | 5 | 10 | 5 | 14 | 6 | 10 | 12 | 12 | 12 | 12 |  | 50 Ohms | TOP=L2:L3=L2/L4:L6=L5/L7:BOTTOM=L7 |
| TWI_SRST#6 | OTHERS | BUS | 6 | 5 | 5 | 10 | 5 | 14 | 6 | 10 | 12 | 12 | 12 | 12 |  | 50 Ohms | TOP=L2:L3=L2/L4:L6=L5/L7:BOTTOM=L7 |
| TWI_SRST#6 | OTHERS | BUS | 7 | 5 | 5 | 10 | 5 | 14 | 6 | 10 | 12 | 12 | 12 | 12 |  | 50 Ohms | TOP=L2:L3=L2/L4:L6=L5/L7:BOTTOM=L7 |
| TWI_SRST#6 | OTHERS | BUS | 8 | 4.75 | 5 | 10 | 5 | 14 | 6 | 9.5 | 12 | 12 | 12 | 12 |  | 50 Ohms | TOP=L2:L3=L2/L4:L6=L5/L7:BOTTOM=L7 |
| TWI_SRST#7 | OTHERS | BUS | 1 | 4.75 | 5 | 10 | 5 | 14 | 6 | 9.5 | 12 | 12 | 12 | 12 |  | 50 Ohms | TOP=L2:L3=L2/L4:L6=L5/L7:BOTTOM=L7 |
| TWI_SRST#7 | OTHERS | BUS | 2 | 5 | 5 | 10 | 5 | 14 | 6 | 10 | 12 | 12 | 12 | 12 |  | 50 Ohms | TOP=L2:L3=L2/L4:L6=L5/L7:BOTTOM=L7 |
| TWI_SRST#7 | OTHERS | BUS | 3 | 5 | 5 | 10 | 5 | 14 | 6 | 10 | 12 | 12 | 12 | 12 |  | 50 Ohms | TOP=L2:L3=L2/L4:L6=L5/L7:BOTTOM=L7 |
| TWI_SRST#7 | OTHERS | BUS | 4 | 5 | 5 | 10 | 5 | 14 | 6 | 10 | 12 | 12 | 12 | 12 |  | 50 Ohms | TOP=L2:L3=L2/L4:L6=L5/L7:BOTTOM=L7 |
| TWI_SRST#7 | OTHERS | BUS | 5 | 5 | 5 | 10 | 5 | 14 | 6 | 10 | 12 | 12 | 12 | 12 |  | 50 Ohms | TOP=L2:L3=L2/L4:L6=L5/L7:BOTTOM=L7 |
| TWI_SRST#7 | OTHERS | BUS | 6 | 5 | 5 | 10 | 5 | 14 | 6 | 10 | 12 | 12 | 12 | 12 |  | 50 Ohms | TOP=L2:L3=L2/L4:L6=L5/L7:BOTTOM=L7 |
| TWI_SRST#7 | OTHERS | BUS | 7 | 5 | 5 | 10 | 5 | 14 | 6 | 10 | 12 | 12 | 12 | 12 |  | 50 Ohms | TOP=L2:L3=L2/L4:L6=L5/L7:BOTTOM=L7 |
| TWI_SRST#7 | OTHERS | BUS | 8 | 4.75 | 5 | 10 | 5 | 14 | 6 | 9.5 | 12 | 12 | 12 | 12 |  | 50 Ohms | TOP=L2:L3=L2/L4:L6=L5/L7:BOTTOM=L7 |
| TWI_SRST#8 | OTHERS | BUS | 1 | 4.75 | 5 | 10 | 5 | 14 | 6 | 9.5 | 12 | 12 | 12 | 12 |  | 50 Ohms | TOP=L2:L3=L2/L4:L6=L5/L7:BOTTOM=L7 |
| TWI_SRST#8 | OTHERS | BUS | 2 | 5 | 5 | 10 | 5 | 14 | 6 | 10 | 12 | 12 | 12 | 12 |  | 50 Ohms | TOP=L2:L3=L2/L4:L6=L5/L7:BOTTOM=L7 |
| TWI_SRST#8 | OTHERS | BUS | 3 | 5 | 5 | 10 | 5 | 14 | 6 | 10 | 12 | 12 | 12 | 12 |  | 50 Ohms | TOP=L2:L3=L2/L4:L6=L5/L7:BOTTOM=L7 |
| TWI_SRST#8 | OTHERS | BUS | 4 | 5 | 5 | 10 | 5 | 14 | 6 | 10 | 12 | 12 | 12 | 12 |  | 50 Ohms | TOP=L2:L3=L2/L4:L6=L5/L7:BOTTOM=L7 |
| TWI_SRST#8 | OTHERS | BUS | 5 | 5 | 5 | 10 | 5 | 14 | 6 | 10 | 12 | 12 | 12 | 12 |  | 50 Ohms | TOP=L2:L3=L2/L4:L6=L5/L7:BOTTOM=L7 |
| TWI_SRST#8 | OTHERS | BUS | 6 | 5 | 5 | 10 | 5 | 14 | 6 | 10 | 12 | 12 | 12 | 12 |  | 50 Ohms | TOP=L2:L3=L2/L4:L6=L5/L7:BOTTOM=L7 |
| TWI_SRST#8 | OTHERS | BUS | 7 | 5 | 5 | 10 | 5 | 14 | 6 | 10 | 12 | 12 | 12 | 12 |  | 50 Ohms | TOP=L2:L3=L2/L4:L6=L5/L7:BOTTOM=L7 |
| TWI_SRST#8 | OTHERS | BUS | 8 | 4.75 | 5 | 10 | 5 | 14 | 6 | 9.5 | 12 | 12 | 12 | 12 |  | 50 Ohms | TOP=L2:L3=L2/L4:L6=L5/L7:BOTTOM=L7 |
| TWI_SRST#9 | OTHERS | BUS | 1 | 4.75 | 5 | 10 | 5 | 14 | 6 | 9.5 | 12 | 12 | 12 | 12 |  | 50 Ohms | TOP=L2:L3=L2/L4:L6=L5/L7:BOTTOM=L7 |
| TWI_SRST#9 | OTHERS | BUS | 2 | 5 | 5 | 10 | 5 | 14 | 6 | 10 | 12 | 12 | 12 | 12 |  | 50 Ohms | TOP=L2:L3=L2/L4:L6=L5/L7:BOTTOM=L7 |
| TWI_SRST#9 | OTHERS | BUS | 3 | 5 | 5 | 10 | 5 | 14 | 6 | 10 | 12 | 12 | 12 | 12 |  | 50 Ohms | TOP=L2:L3=L2/L4:L6=L5/L7:BOTTOM=L7 |
| TWI_SRST#9 | OTHERS | BUS | 4 | 5 | 5 | 10 | 5 | 14 | 6 | 10 | 12 | 12 | 12 | 12 |  | 50 Ohms | TOP=L2:L3=L2/L4:L6=L5/L7:BOTTOM=L7 |
| TWI_SRST#9 | OTHERS | BUS | 5 | 5 | 5 | 10 | 5 | 14 | 6 | 10 | 12 | 12 | 12 | 12 |  | 50 Ohms | TOP=L2:L3=L2/L4:L6=L5/L7:BOTTOM=L7 |
| TWI_SRST#9 | OTHERS | BUS | 6 | 5 | 5 | 10 | 5 | 14 | 6 | 10 | 12 | 12 | 12 | 12 |  | 50 Ohms | TOP=L2:L3=L2/L4:L6=L5/L7:BOTTOM=L7 |
| TWI_SRST#9 | OTHERS | BUS | 7 | 5 | 5 | 10 | 5 | 14 | 6 | 10 | 12 | 12 | 12 | 12 |  | 50 Ohms | TOP=L2:L3=L2/L4:L6=L5/L7:BOTTOM=L7 |
| TWI_SRST#9 | OTHERS | BUS | 8 | 4.75 | 5 | 10 | 5 | 14 | 6 | 9.5 | 12 | 12 | 12 | 12 |  | 50 Ohms | TOP=L2:L3=L2/L4:L6=L5/L7:BOTTOM=L7 |
| U19_PERST_N | OTHERS | BUS | 1 | 4.75 | 5 | 10 | 5 | 14 | 6 | 9.5 | 12 | 12 | 12 | 12 |  | 50 Ohms | TOP=L2:L3=L2/L4:L6=L5/L7:BOTTOM=L7 |
| U19_PERST_N | OTHERS | BUS | 2 | 5 | 5 | 10 | 5 | 14 | 6 | 10 | 12 | 12 | 12 | 12 |  | 50 Ohms | TOP=L2:L3=L2/L4:L6=L5/L7:BOTTOM=L7 |
| U19_PERST_N | OTHERS | BUS | 3 | 5 | 5 | 10 | 5 | 14 | 6 | 10 | 12 | 12 | 12 | 12 |  | 50 Ohms | TOP=L2:L3=L2/L4:L6=L5/L7:BOTTOM=L7 |
| U19_PERST_N | OTHERS | BUS | 4 | 5 | 5 | 10 | 5 | 14 | 6 | 10 | 12 | 12 | 12 | 12 |  | 50 Ohms | TOP=L2:L3=L2/L4:L6=L5/L7:BOTTOM=L7 |
| U19_PERST_N | OTHERS | BUS | 5 | 5 | 5 | 10 | 5 | 14 | 6 | 10 | 12 | 12 | 12 | 12 |  | 50 Ohms | TOP=L2:L3=L2/L4:L6=L5/L7:BOTTOM=L7 |
| U19_PERST_N | OTHERS | BUS | 6 | 5 | 5 | 10 | 5 | 14 | 6 | 10 | 12 | 12 | 12 | 12 |  | 50 Ohms | TOP=L2:L3=L2/L4:L6=L5/L7:BOTTOM=L7 |
| U19_PERST_N | OTHERS | BUS | 7 | 5 | 5 | 10 | 5 | 14 | 6 | 10 | 12 | 12 | 12 | 12 |  | 50 Ohms | TOP=L2:L3=L2/L4:L6=L5/L7:BOTTOM=L7 |
| U19_PERST_N | OTHERS | BUS | 8 | 4.75 | 5 | 10 | 5 | 14 | 6 | 9.5 | 12 | 12 | 12 | 12 |  | 50 Ohms | TOP=L2:L3=L2/L4:L6=L5/L7:BOTTOM=L7 |
| U44_HOLD_N | OTHERS | BUS | 1 | 4.75 | 5 | 10 | 5 | 14 | 6 | 9.5 | 12 | 12 | 12 | 12 |  | 50 Ohms | TOP=L2:L3=L2/L4:L6=L5/L7:BOTTOM=L7 |
| U44_HOLD_N | OTHERS | BUS | 2 | 5 | 5 | 10 | 5 | 14 | 6 | 10 | 12 | 12 | 12 | 12 |  | 50 Ohms | TOP=L2:L3=L2/L4:L6=L5/L7:BOTTOM=L7 |
| U44_HOLD_N | OTHERS | BUS | 3 | 5 | 5 | 10 | 5 | 14 | 6 | 10 | 12 | 12 | 12 | 12 |  | 50 Ohms | TOP=L2:L3=L2/L4:L6=L5/L7:BOTTOM=L7 |
| U44_HOLD_N | OTHERS | BUS | 4 | 5 | 5 | 10 | 5 | 14 | 6 | 10 | 12 | 12 | 12 | 12 |  | 50 Ohms | TOP=L2:L3=L2/L4:L6=L5/L7:BOTTOM=L7 |
| U44_HOLD_N | OTHERS | BUS | 5 | 5 | 5 | 10 | 5 | 14 | 6 | 10 | 12 | 12 | 12 | 12 |  | 50 Ohms | TOP=L2:L3=L2/L4:L6=L5/L7:BOTTOM=L7 |
| U44_HOLD_N | OTHERS | BUS | 6 | 5 | 5 | 10 | 5 | 14 | 6 | 10 | 12 | 12 | 12 | 12 |  | 50 Ohms | TOP=L2:L3=L2/L4:L6=L5/L7:BOTTOM=L7 |
| U44_HOLD_N | OTHERS | BUS | 7 | 5 | 5 | 10 | 5 | 14 | 6 | 10 | 12 | 12 | 12 | 12 |  | 50 Ohms | TOP=L2:L3=L2/L4:L6=L5/L7:BOTTOM=L7 |
| U44_HOLD_N | OTHERS | BUS | 8 | 4.75 | 5 | 10 | 5 | 14 | 6 | 9.5 | 12 | 12 | 12 | 12 |  | 50 Ohms | TOP=L2:L3=L2/L4:L6=L5/L7:BOTTOM=L7 |
| U44_WP_N | OTHERS | BUS | 1 | 4.75 | 5 | 10 | 5 | 14 | 6 | 9.5 | 12 | 12 | 12 | 12 |  | 50 Ohms | TOP=L2:L3=L2/L4:L6=L5/L7:BOTTOM=L7 |
| U44_WP_N | OTHERS | BUS | 2 | 5 | 5 | 10 | 5 | 14 | 6 | 10 | 12 | 12 | 12 | 12 |  | 50 Ohms | TOP=L2:L3=L2/L4:L6=L5/L7:BOTTOM=L7 |
| U44_WP_N | OTHERS | BUS | 3 | 5 | 5 | 10 | 5 | 14 | 6 | 10 | 12 | 12 | 12 | 12 |  | 50 Ohms | TOP=L2:L3=L2/L4:L6=L5/L7:BOTTOM=L7 |
| U44_WP_N | OTHERS | BUS | 4 | 5 | 5 | 10 | 5 | 14 | 6 | 10 | 12 | 12 | 12 | 12 |  | 50 Ohms | TOP=L2:L3=L2/L4:L6=L5/L7:BOTTOM=L7 |
| U44_WP_N | OTHERS | BUS | 5 | 5 | 5 | 10 | 5 | 14 | 6 | 10 | 12 | 12 | 12 | 12 |  | 50 Ohms | TOP=L2:L3=L2/L4:L6=L5/L7:BOTTOM=L7 |
| U44_WP_N | OTHERS | BUS | 6 | 5 | 5 | 10 | 5 | 14 | 6 | 10 | 12 | 12 | 12 | 12 |  | 50 Ohms | TOP=L2:L3=L2/L4:L6=L5/L7:BOTTOM=L7 |
| U44_WP_N | OTHERS | BUS | 7 | 5 | 5 | 10 | 5 | 14 | 6 | 10 | 12 | 12 | 12 | 12 |  | 50 Ohms | TOP=L2:L3=L2/L4:L6=L5/L7:BOTTOM=L7 |
| U44_WP_N | OTHERS | BUS | 8 | 4.75 | 5 | 10 | 5 | 14 | 6 | 9.5 | 12 | 12 | 12 | 12 |  | 50 Ohms | TOP=L2:L3=L2/L4:L6=L5/L7:BOTTOM=L7 |
| U54_A0 | OTHERS | BUS | 1 | 4.75 | 5 | 10 | 5 | 14 | 6 | 9.5 | 12 | 12 | 12 | 12 |  | 50 Ohms | TOP=L2:L3=L2/L4:L6=L5/L7:BOTTOM=L7 |
| U54_A0 | OTHERS | BUS | 2 | 5 | 5 | 10 | 5 | 14 | 6 | 10 | 12 | 12 | 12 | 12 |  | 50 Ohms | TOP=L2:L3=L2/L4:L6=L5/L7:BOTTOM=L7 |
| U54_A0 | OTHERS | BUS | 3 | 5 | 5 | 10 | 5 | 14 | 6 | 10 | 12 | 12 | 12 | 12 |  | 50 Ohms | TOP=L2:L3=L2/L4:L6=L5/L7:BOTTOM=L7 |
| U54_A0 | OTHERS | BUS | 4 | 5 | 5 | 10 | 5 | 14 | 6 | 10 | 12 | 12 | 12 | 12 |  | 50 Ohms | TOP=L2:L3=L2/L4:L6=L5/L7:BOTTOM=L7 |
| U54_A0 | OTHERS | BUS | 5 | 5 | 5 | 10 | 5 | 14 | 6 | 10 | 12 | 12 | 12 | 12 |  | 50 Ohms | TOP=L2:L3=L2/L4:L6=L5/L7:BOTTOM=L7 |
| U54_A0 | OTHERS | BUS | 6 | 5 | 5 | 10 | 5 | 14 | 6 | 10 | 12 | 12 | 12 | 12 |  | 50 Ohms | TOP=L2:L3=L2/L4:L6=L5/L7:BOTTOM=L7 |
| U54_A0 | OTHERS | BUS | 7 | 5 | 5 | 10 | 5 | 14 | 6 | 10 | 12 | 12 | 12 | 12 |  | 50 Ohms | TOP=L2:L3=L2/L4:L6=L5/L7:BOTTOM=L7 |
| U54_A0 | OTHERS | BUS | 8 | 4.75 | 5 | 10 | 5 | 14 | 6 | 9.5 | 12 | 12 | 12 | 12 |  | 50 Ohms | TOP=L2:L3=L2/L4:L6=L5/L7:BOTTOM=L7 |
| U54_A1 | OTHERS | BUS | 1 | 4.75 | 5 | 10 | 5 | 14 | 6 | 9.5 | 12 | 12 | 12 | 12 |  | 50 Ohms | TOP=L2:L3=L2/L4:L6=L5/L7:BOTTOM=L7 |
| U54_A1 | OTHERS | BUS | 2 | 5 | 5 | 10 | 5 | 14 | 6 | 10 | 12 | 12 | 12 | 12 |  | 50 Ohms | TOP=L2:L3=L2/L4:L6=L5/L7:BOTTOM=L7 |
| U54_A1 | OTHERS | BUS | 3 | 5 | 5 | 10 | 5 | 14 | 6 | 10 | 12 | 12 | 12 | 12 |  | 50 Ohms | TOP=L2:L3=L2/L4:L6=L5/L7:BOTTOM=L7 |
| U54_A1 | OTHERS | BUS | 4 | 5 | 5 | 10 | 5 | 14 | 6 | 10 | 12 | 12 | 12 | 12 |  | 50 Ohms | TOP=L2:L3=L2/L4:L6=L5/L7:BOTTOM=L7 |
| U54_A1 | OTHERS | BUS | 5 | 5 | 5 | 10 | 5 | 14 | 6 | 10 | 12 | 12 | 12 | 12 |  | 50 Ohms | TOP=L2:L3=L2/L4:L6=L5/L7:BOTTOM=L7 |
| U54_A1 | OTHERS | BUS | 6 | 5 | 5 | 10 | 5 | 14 | 6 | 10 | 12 | 12 | 12 | 12 |  | 50 Ohms | TOP=L2:L3=L2/L4:L6=L5/L7:BOTTOM=L7 |
| U54_A1 | OTHERS | BUS | 7 | 5 | 5 | 10 | 5 | 14 | 6 | 10 | 12 | 12 | 12 | 12 |  | 50 Ohms | TOP=L2:L3=L2/L4:L6=L5/L7:BOTTOM=L7 |
| U54_A1 | OTHERS | BUS | 8 | 4.75 | 5 | 10 | 5 | 14 | 6 | 9.5 | 12 | 12 | 12 | 12 |  | 50 Ohms | TOP=L2:L3=L2/L4:L6=L5/L7:BOTTOM=L7 |
| U54_A2 | OTHERS | BUS | 1 | 4.75 | 5 | 10 | 5 | 14 | 6 | 9.5 | 12 | 12 | 12 | 12 |  | 50 Ohms | TOP=L2:L3=L2/L4:L6=L5/L7:BOTTOM=L7 |
| U54_A2 | OTHERS | BUS | 2 | 5 | 5 | 10 | 5 | 14 | 6 | 10 | 12 | 12 | 12 | 12 |  | 50 Ohms | TOP=L2:L3=L2/L4:L6=L5/L7:BOTTOM=L7 |
| U54_A2 | OTHERS | BUS | 3 | 5 | 5 | 10 | 5 | 14 | 6 | 10 | 12 | 12 | 12 | 12 |  | 50 Ohms | TOP=L2:L3=L2/L4:L6=L5/L7:BOTTOM=L7 |
| U54_A2 | OTHERS | BUS | 4 | 5 | 5 | 10 | 5 | 14 | 6 | 10 | 12 | 12 | 12 | 12 |  | 50 Ohms | TOP=L2:L3=L2/L4:L6=L5/L7:BOTTOM=L7 |
| U54_A2 | OTHERS | BUS | 5 | 5 | 5 | 10 | 5 | 14 | 6 | 10 | 12 | 12 | 12 | 12 |  | 50 Ohms | TOP=L2:L3=L2/L4:L6=L5/L7:BOTTOM=L7 |
| U54_A2 | OTHERS | BUS | 6 | 5 | 5 | 10 | 5 | 14 | 6 | 10 | 12 | 12 | 12 | 12 |  | 50 Ohms | TOP=L2:L3=L2/L4:L6=L5/L7:BOTTOM=L7 |
| U54_A2 | OTHERS | BUS | 7 | 5 | 5 | 10 | 5 | 14 | 6 | 10 | 12 | 12 | 12 | 12 |  | 50 Ohms | TOP=L2:L3=L2/L4:L6=L5/L7:BOTTOM=L7 |
| U54_A2 | OTHERS | BUS | 8 | 4.75 | 5 | 10 | 5 | 14 | 6 | 9.5 | 12 | 12 | 12 | 12 |  | 50 Ohms | TOP=L2:L3=L2/L4:L6=L5/L7:BOTTOM=L7 |
| U54_INT_N | OTHERS | BUS | 1 | 4.75 | 5 | 10 | 5 | 14 | 6 | 9.5 | 12 | 12 | 12 | 12 |  | 50 Ohms | TOP=L2:L3=L2/L4:L6=L5/L7:BOTTOM=L7 |
| U54_INT_N | OTHERS | BUS | 2 | 5 | 5 | 10 | 5 | 14 | 6 | 10 | 12 | 12 | 12 | 12 |  | 50 Ohms | TOP=L2:L3=L2/L4:L6=L5/L7:BOTTOM=L7 |
| U54_INT_N | OTHERS | BUS | 3 | 5 | 5 | 10 | 5 | 14 | 6 | 10 | 12 | 12 | 12 | 12 |  | 50 Ohms | TOP=L2:L3=L2/L4:L6=L5/L7:BOTTOM=L7 |
| U54_INT_N | OTHERS | BUS | 4 | 5 | 5 | 10 | 5 | 14 | 6 | 10 | 12 | 12 | 12 | 12 |  | 50 Ohms | TOP=L2:L3=L2/L4:L6=L5/L7:BOTTOM=L7 |
| U54_INT_N | OTHERS | BUS | 5 | 5 | 5 | 10 | 5 | 14 | 6 | 10 | 12 | 12 | 12 | 12 |  | 50 Ohms | TOP=L2:L3=L2/L4:L6=L5/L7:BOTTOM=L7 |
| U54_INT_N | OTHERS | BUS | 6 | 5 | 5 | 10 | 5 | 14 | 6 | 10 | 12 | 12 | 12 | 12 |  | 50 Ohms | TOP=L2:L3=L2/L4:L6=L5/L7:BOTTOM=L7 |
| U54_INT_N | OTHERS | BUS | 7 | 5 | 5 | 10 | 5 | 14 | 6 | 10 | 12 | 12 | 12 | 12 |  | 50 Ohms | TOP=L2:L3=L2/L4:L6=L5/L7:BOTTOM=L7 |
| U54_INT_N | OTHERS | BUS | 8 | 4.75 | 5 | 10 | 5 | 14 | 6 | 9.5 | 12 | 12 | 12 | 12 |  | 50 Ohms | TOP=L2:L3=L2/L4:L6=L5/L7:BOTTOM=L7 |
| U54_P0 | OTHERS | BUS | 1 | 4.75 | 5 | 10 | 5 | 14 | 6 | 9.5 | 12 | 12 | 12 | 12 |  | 50 Ohms | TOP=L2:L3=L2/L4:L6=L5/L7:BOTTOM=L7 |
| U54_P0 | OTHERS | BUS | 2 | 5 | 5 | 10 | 5 | 14 | 6 | 10 | 12 | 12 | 12 | 12 |  | 50 Ohms | TOP=L2:L3=L2/L4:L6=L5/L7:BOTTOM=L7 |
| U54_P0 | OTHERS | BUS | 3 | 5 | 5 | 10 | 5 | 14 | 6 | 10 | 12 | 12 | 12 | 12 |  | 50 Ohms | TOP=L2:L3=L2/L4:L6=L5/L7:BOTTOM=L7 |
| U54_P0 | OTHERS | BUS | 4 | 5 | 5 | 10 | 5 | 14 | 6 | 10 | 12 | 12 | 12 | 12 |  | 50 Ohms | TOP=L2:L3=L2/L4:L6=L5/L7:BOTTOM=L7 |
| U54_P0 | OTHERS | BUS | 5 | 5 | 5 | 10 | 5 | 14 | 6 | 10 | 12 | 12 | 12 | 12 |  | 50 Ohms | TOP=L2:L3=L2/L4:L6=L5/L7:BOTTOM=L7 |
| U54_P0 | OTHERS | BUS | 6 | 5 | 5 | 10 | 5 | 14 | 6 | 10 | 12 | 12 | 12 | 12 |  | 50 Ohms | TOP=L2:L3=L2/L4:L6=L5/L7:BOTTOM=L7 |
| U54_P0 | OTHERS | BUS | 7 | 5 | 5 | 10 | 5 | 14 | 6 | 10 | 12 | 12 | 12 | 12 |  | 50 Ohms | TOP=L2:L3=L2/L4:L6=L5/L7:BOTTOM=L7 |
| U54_P0 | OTHERS | BUS | 8 | 4.75 | 5 | 10 | 5 | 14 | 6 | 9.5 | 12 | 12 | 12 | 12 |  | 50 Ohms | TOP=L2:L3=L2/L4:L6=L5/L7:BOTTOM=L7 |
| U54_SCL | OTHERS | BUS | 1 | 4.75 | 5 | 10 | 5 | 14 | 6 | 9.5 | 12 | 12 | 12 | 12 |  | 50 Ohms | TOP=L2:L3=L2/L4:L6=L5/L7:BOTTOM=L7 |
| U54_SCL | OTHERS | BUS | 2 | 5 | 5 | 10 | 5 | 14 | 6 | 10 | 12 | 12 | 12 | 12 |  | 50 Ohms | TOP=L2:L3=L2/L4:L6=L5/L7:BOTTOM=L7 |
| U54_SCL | OTHERS | BUS | 3 | 5 | 5 | 10 | 5 | 14 | 6 | 10 | 12 | 12 | 12 | 12 |  | 50 Ohms | TOP=L2:L3=L2/L4:L6=L5/L7:BOTTOM=L7 |
| U54_SCL | OTHERS | BUS | 4 | 5 | 5 | 10 | 5 | 14 | 6 | 10 | 12 | 12 | 12 | 12 |  | 50 Ohms | TOP=L2:L3=L2/L4:L6=L5/L7:BOTTOM=L7 |
| U54_SCL | OTHERS | BUS | 5 | 5 | 5 | 10 | 5 | 14 | 6 | 10 | 12 | 12 | 12 | 12 |  | 50 Ohms | TOP=L2:L3=L2/L4:L6=L5/L7:BOTTOM=L7 |
| U54_SCL | OTHERS | BUS | 6 | 5 | 5 | 10 | 5 | 14 | 6 | 10 | 12 | 12 | 12 | 12 |  | 50 Ohms | TOP=L2:L3=L2/L4:L6=L5/L7:BOTTOM=L7 |
| U54_SCL | OTHERS | BUS | 7 | 5 | 5 | 10 | 5 | 14 | 6 | 10 | 12 | 12 | 12 | 12 |  | 50 Ohms | TOP=L2:L3=L2/L4:L6=L5/L7:BOTTOM=L7 |
| U54_SCL | OTHERS | BUS | 8 | 4.75 | 5 | 10 | 5 | 14 | 6 | 9.5 | 12 | 12 | 12 | 12 |  | 50 Ohms | TOP=L2:L3=L2/L4:L6=L5/L7:BOTTOM=L7 |
| U54_SDA | OTHERS | BUS | 1 | 4.75 | 5 | 10 | 5 | 14 | 6 | 9.5 | 12 | 12 | 12 | 12 |  | 50 Ohms | TOP=L2:L3=L2/L4:L6=L5/L7:BOTTOM=L7 |
| U54_SDA | OTHERS | BUS | 2 | 5 | 5 | 10 | 5 | 14 | 6 | 10 | 12 | 12 | 12 | 12 |  | 50 Ohms | TOP=L2:L3=L2/L4:L6=L5/L7:BOTTOM=L7 |
| U54_SDA | OTHERS | BUS | 3 | 5 | 5 | 10 | 5 | 14 | 6 | 10 | 12 | 12 | 12 | 12 |  | 50 Ohms | TOP=L2:L3=L2/L4:L6=L5/L7:BOTTOM=L7 |
| U54_SDA | OTHERS | BUS | 4 | 5 | 5 | 10 | 5 | 14 | 6 | 10 | 12 | 12 | 12 | 12 |  | 50 Ohms | TOP=L2:L3=L2/L4:L6=L5/L7:BOTTOM=L7 |
| U54_SDA | OTHERS | BUS | 5 | 5 | 5 | 10 | 5 | 14 | 6 | 10 | 12 | 12 | 12 | 12 |  | 50 Ohms | TOP=L2:L3=L2/L4:L6=L5/L7:BOTTOM=L7 |
| U54_SDA | OTHERS | BUS | 6 | 5 | 5 | 10 | 5 | 14 | 6 | 10 | 12 | 12 | 12 | 12 |  | 50 Ohms | TOP=L2:L3=L2/L4:L6=L5/L7:BOTTOM=L7 |
| U54_SDA | OTHERS | BUS | 7 | 5 | 5 | 10 | 5 | 14 | 6 | 10 | 12 | 12 | 12 | 12 |  | 50 Ohms | TOP=L2:L3=L2/L4:L6=L5/L7:BOTTOM=L7 |
| U54_SDA | OTHERS | BUS | 8 | 4.75 | 5 | 10 | 5 | 14 | 6 | 9.5 | 12 | 12 | 12 | 12 |  | 50 Ohms | TOP=L2:L3=L2/L4:L6=L5/L7:BOTTOM=L7 |
| U55_A0 | OTHERS | BUS | 1 | 4.75 | 5 | 10 | 5 | 14 | 6 | 9.5 | 12 | 12 | 12 | 12 |  | 50 Ohms | TOP=L2:L3=L2/L4:L6=L5/L7:BOTTOM=L7 |
| U55_A0 | OTHERS | BUS | 2 | 5 | 5 | 10 | 5 | 14 | 6 | 10 | 12 | 12 | 12 | 12 |  | 50 Ohms | TOP=L2:L3=L2/L4:L6=L5/L7:BOTTOM=L7 |
| U55_A0 | OTHERS | BUS | 3 | 5 | 5 | 10 | 5 | 14 | 6 | 10 | 12 | 12 | 12 | 12 |  | 50 Ohms | TOP=L2:L3=L2/L4:L6=L5/L7:BOTTOM=L7 |
| U55_A0 | OTHERS | BUS | 4 | 5 | 5 | 10 | 5 | 14 | 6 | 10 | 12 | 12 | 12 | 12 |  | 50 Ohms | TOP=L2:L3=L2/L4:L6=L5/L7:BOTTOM=L7 |
| U55_A0 | OTHERS | BUS | 5 | 5 | 5 | 10 | 5 | 14 | 6 | 10 | 12 | 12 | 12 | 12 |  | 50 Ohms | TOP=L2:L3=L2/L4:L6=L5/L7:BOTTOM=L7 |
| U55_A0 | OTHERS | BUS | 6 | 5 | 5 | 10 | 5 | 14 | 6 | 10 | 12 | 12 | 12 | 12 |  | 50 Ohms | TOP=L2:L3=L2/L4:L6=L5/L7:BOTTOM=L7 |
| U55_A0 | OTHERS | BUS | 7 | 5 | 5 | 10 | 5 | 14 | 6 | 10 | 12 | 12 | 12 | 12 |  | 50 Ohms | TOP=L2:L3=L2/L4:L6=L5/L7:BOTTOM=L7 |
| U55_A0 | OTHERS | BUS | 8 | 4.75 | 5 | 10 | 5 | 14 | 6 | 9.5 | 12 | 12 | 12 | 12 |  | 50 Ohms | TOP=L2:L3=L2/L4:L6=L5/L7:BOTTOM=L7 |
| U55_A1 | OTHERS | BUS | 1 | 4.75 | 5 | 10 | 5 | 14 | 6 | 9.5 | 12 | 12 | 12 | 12 |  | 50 Ohms | TOP=L2:L3=L2/L4:L6=L5/L7:BOTTOM=L7 |
| U55_A1 | OTHERS | BUS | 2 | 5 | 5 | 10 | 5 | 14 | 6 | 10 | 12 | 12 | 12 | 12 |  | 50 Ohms | TOP=L2:L3=L2/L4:L6=L5/L7:BOTTOM=L7 |
| U55_A1 | OTHERS | BUS | 3 | 5 | 5 | 10 | 5 | 14 | 6 | 10 | 12 | 12 | 12 | 12 |  | 50 Ohms | TOP=L2:L3=L2/L4:L6=L5/L7:BOTTOM=L7 |
| U55_A1 | OTHERS | BUS | 4 | 5 | 5 | 10 | 5 | 14 | 6 | 10 | 12 | 12 | 12 | 12 |  | 50 Ohms | TOP=L2:L3=L2/L4:L6=L5/L7:BOTTOM=L7 |
| U55_A1 | OTHERS | BUS | 5 | 5 | 5 | 10 | 5 | 14 | 6 | 10 | 12 | 12 | 12 | 12 |  | 50 Ohms | TOP=L2:L3=L2/L4:L6=L5/L7:BOTTOM=L7 |
| U55_A1 | OTHERS | BUS | 6 | 5 | 5 | 10 | 5 | 14 | 6 | 10 | 12 | 12 | 12 | 12 |  | 50 Ohms | TOP=L2:L3=L2/L4:L6=L5/L7:BOTTOM=L7 |
| U55_A1 | OTHERS | BUS | 7 | 5 | 5 | 10 | 5 | 14 | 6 | 10 | 12 | 12 | 12 | 12 |  | 50 Ohms | TOP=L2:L3=L2/L4:L6=L5/L7:BOTTOM=L7 |
| U55_A1 | OTHERS | BUS | 8 | 4.75 | 5 | 10 | 5 | 14 | 6 | 9.5 | 12 | 12 | 12 | 12 |  | 50 Ohms | TOP=L2:L3=L2/L4:L6=L5/L7:BOTTOM=L7 |
| U55_A2 | OTHERS | BUS | 1 | 4.75 | 5 | 10 | 5 | 14 | 6 | 9.5 | 12 | 12 | 12 | 12 |  | 50 Ohms | TOP=L2:L3=L2/L4:L6=L5/L7:BOTTOM=L7 |
| U55_A2 | OTHERS | BUS | 2 | 5 | 5 | 10 | 5 | 14 | 6 | 10 | 12 | 12 | 12 | 12 |  | 50 Ohms | TOP=L2:L3=L2/L4:L6=L5/L7:BOTTOM=L7 |
| U55_A2 | OTHERS | BUS | 3 | 5 | 5 | 10 | 5 | 14 | 6 | 10 | 12 | 12 | 12 | 12 |  | 50 Ohms | TOP=L2:L3=L2/L4:L6=L5/L7:BOTTOM=L7 |
| U55_A2 | OTHERS | BUS | 4 | 5 | 5 | 10 | 5 | 14 | 6 | 10 | 12 | 12 | 12 | 12 |  | 50 Ohms | TOP=L2:L3=L2/L4:L6=L5/L7:BOTTOM=L7 |
| U55_A2 | OTHERS | BUS | 5 | 5 | 5 | 10 | 5 | 14 | 6 | 10 | 12 | 12 | 12 | 12 |  | 50 Ohms | TOP=L2:L3=L2/L4:L6=L5/L7:BOTTOM=L7 |
| U55_A2 | OTHERS | BUS | 6 | 5 | 5 | 10 | 5 | 14 | 6 | 10 | 12 | 12 | 12 | 12 |  | 50 Ohms | TOP=L2:L3=L2/L4:L6=L5/L7:BOTTOM=L7 |
| U55_A2 | OTHERS | BUS | 7 | 5 | 5 | 10 | 5 | 14 | 6 | 10 | 12 | 12 | 12 | 12 |  | 50 Ohms | TOP=L2:L3=L2/L4:L6=L5/L7:BOTTOM=L7 |
| U55_A2 | OTHERS | BUS | 8 | 4.75 | 5 | 10 | 5 | 14 | 6 | 9.5 | 12 | 12 | 12 | 12 |  | 50 Ohms | TOP=L2:L3=L2/L4:L6=L5/L7:BOTTOM=L7 |
| U55_INT_N | OTHERS | BUS | 1 | 4.75 | 5 | 10 | 5 | 14 | 6 | 9.5 | 12 | 12 | 12 | 12 |  | 50 Ohms | TOP=L2:L3=L2/L4:L6=L5/L7:BOTTOM=L7 |
| U55_INT_N | OTHERS | BUS | 2 | 5 | 5 | 10 | 5 | 14 | 6 | 10 | 12 | 12 | 12 | 12 |  | 50 Ohms | TOP=L2:L3=L2/L4:L6=L5/L7:BOTTOM=L7 |
| U55_INT_N | OTHERS | BUS | 3 | 5 | 5 | 10 | 5 | 14 | 6 | 10 | 12 | 12 | 12 | 12 |  | 50 Ohms | TOP=L2:L3=L2/L4:L6=L5/L7:BOTTOM=L7 |
| U55_INT_N | OTHERS | BUS | 4 | 5 | 5 | 10 | 5 | 14 | 6 | 10 | 12 | 12 | 12 | 12 |  | 50 Ohms | TOP=L2:L3=L2/L4:L6=L5/L7:BOTTOM=L7 |
| U55_INT_N | OTHERS | BUS | 5 | 5 | 5 | 10 | 5 | 14 | 6 | 10 | 12 | 12 | 12 | 12 |  | 50 Ohms | TOP=L2:L3=L2/L4:L6=L5/L7:BOTTOM=L7 |
| U55_INT_N | OTHERS | BUS | 6 | 5 | 5 | 10 | 5 | 14 | 6 | 10 | 12 | 12 | 12 | 12 |  | 50 Ohms | TOP=L2:L3=L2/L4:L6=L5/L7:BOTTOM=L7 |
| U55_INT_N | OTHERS | BUS | 7 | 5 | 5 | 10 | 5 | 14 | 6 | 10 | 12 | 12 | 12 | 12 |  | 50 Ohms | TOP=L2:L3=L2/L4:L6=L5/L7:BOTTOM=L7 |
| U55_INT_N | OTHERS | BUS | 8 | 4.75 | 5 | 10 | 5 | 14 | 6 | 9.5 | 12 | 12 | 12 | 12 |  | 50 Ohms | TOP=L2:L3=L2/L4:L6=L5/L7:BOTTOM=L7 |
| U55_P0 | OTHERS | BUS | 1 | 4.75 | 5 | 10 | 5 | 14 | 6 | 9.5 | 12 | 12 | 12 | 12 |  | 50 Ohms | TOP=L2:L3=L2/L4:L6=L5/L7:BOTTOM=L7 |
| U55_P0 | OTHERS | BUS | 2 | 5 | 5 | 10 | 5 | 14 | 6 | 10 | 12 | 12 | 12 | 12 |  | 50 Ohms | TOP=L2:L3=L2/L4:L6=L5/L7:BOTTOM=L7 |
| U55_P0 | OTHERS | BUS | 3 | 5 | 5 | 10 | 5 | 14 | 6 | 10 | 12 | 12 | 12 | 12 |  | 50 Ohms | TOP=L2:L3=L2/L4:L6=L5/L7:BOTTOM=L7 |
| U55_P0 | OTHERS | BUS | 4 | 5 | 5 | 10 | 5 | 14 | 6 | 10 | 12 | 12 | 12 | 12 |  | 50 Ohms | TOP=L2:L3=L2/L4:L6=L5/L7:BOTTOM=L7 |
| U55_P0 | OTHERS | BUS | 5 | 5 | 5 | 10 | 5 | 14 | 6 | 10 | 12 | 12 | 12 | 12 |  | 50 Ohms | TOP=L2:L3=L2/L4:L6=L5/L7:BOTTOM=L7 |
| U55_P0 | OTHERS | BUS | 6 | 5 | 5 | 10 | 5 | 14 | 6 | 10 | 12 | 12 | 12 | 12 |  | 50 Ohms | TOP=L2:L3=L2/L4:L6=L5/L7:BOTTOM=L7 |
| U55_P0 | OTHERS | BUS | 7 | 5 | 5 | 10 | 5 | 14 | 6 | 10 | 12 | 12 | 12 | 12 |  | 50 Ohms | TOP=L2:L3=L2/L4:L6=L5/L7:BOTTOM=L7 |
| U55_P0 | OTHERS | BUS | 8 | 4.75 | 5 | 10 | 5 | 14 | 6 | 9.5 | 12 | 12 | 12 | 12 |  | 50 Ohms | TOP=L2:L3=L2/L4:L6=L5/L7:BOTTOM=L7 |
| U56_A0 | OTHERS | BUS | 1 | 4.75 | 5 | 10 | 5 | 14 | 6 | 9.5 | 12 | 12 | 12 | 12 |  | 50 Ohms | TOP=L2:L3=L2/L4:L6=L5/L7:BOTTOM=L7 |
| U56_A0 | OTHERS | BUS | 2 | 5 | 5 | 10 | 5 | 14 | 6 | 10 | 12 | 12 | 12 | 12 |  | 50 Ohms | TOP=L2:L3=L2/L4:L6=L5/L7:BOTTOM=L7 |
| U56_A0 | OTHERS | BUS | 3 | 5 | 5 | 10 | 5 | 14 | 6 | 10 | 12 | 12 | 12 | 12 |  | 50 Ohms | TOP=L2:L3=L2/L4:L6=L5/L7:BOTTOM=L7 |
| U56_A0 | OTHERS | BUS | 4 | 5 | 5 | 10 | 5 | 14 | 6 | 10 | 12 | 12 | 12 | 12 |  | 50 Ohms | TOP=L2:L3=L2/L4:L6=L5/L7:BOTTOM=L7 |
| U56_A0 | OTHERS | BUS | 5 | 5 | 5 | 10 | 5 | 14 | 6 | 10 | 12 | 12 | 12 | 12 |  | 50 Ohms | TOP=L2:L3=L2/L4:L6=L5/L7:BOTTOM=L7 |
| U56_A0 | OTHERS | BUS | 6 | 5 | 5 | 10 | 5 | 14 | 6 | 10 | 12 | 12 | 12 | 12 |  | 50 Ohms | TOP=L2:L3=L2/L4:L6=L5/L7:BOTTOM=L7 |
| U56_A0 | OTHERS | BUS | 7 | 5 | 5 | 10 | 5 | 14 | 6 | 10 | 12 | 12 | 12 | 12 |  | 50 Ohms | TOP=L2:L3=L2/L4:L6=L5/L7:BOTTOM=L7 |
| U56_A0 | OTHERS | BUS | 8 | 4.75 | 5 | 10 | 5 | 14 | 6 | 9.5 | 12 | 12 | 12 | 12 |  | 50 Ohms | TOP=L2:L3=L2/L4:L6=L5/L7:BOTTOM=L7 |
| U56_A1 | OTHERS | BUS | 1 | 4.75 | 5 | 10 | 5 | 14 | 6 | 9.5 | 12 | 12 | 12 | 12 |  | 50 Ohms | TOP=L2:L3=L2/L4:L6=L5/L7:BOTTOM=L7 |
| U56_A1 | OTHERS | BUS | 2 | 5 | 5 | 10 | 5 | 14 | 6 | 10 | 12 | 12 | 12 | 12 |  | 50 Ohms | TOP=L2:L3=L2/L4:L6=L5/L7:BOTTOM=L7 |
| U56_A1 | OTHERS | BUS | 3 | 5 | 5 | 10 | 5 | 14 | 6 | 10 | 12 | 12 | 12 | 12 |  | 50 Ohms | TOP=L2:L3=L2/L4:L6=L5/L7:BOTTOM=L7 |
| U56_A1 | OTHERS | BUS | 4 | 5 | 5 | 10 | 5 | 14 | 6 | 10 | 12 | 12 | 12 | 12 |  | 50 Ohms | TOP=L2:L3=L2/L4:L6=L5/L7:BOTTOM=L7 |
| U56_A1 | OTHERS | BUS | 5 | 5 | 5 | 10 | 5 | 14 | 6 | 10 | 12 | 12 | 12 | 12 |  | 50 Ohms | TOP=L2:L3=L2/L4:L6=L5/L7:BOTTOM=L7 |
| U56_A1 | OTHERS | BUS | 6 | 5 | 5 | 10 | 5 | 14 | 6 | 10 | 12 | 12 | 12 | 12 |  | 50 Ohms | TOP=L2:L3=L2/L4:L6=L5/L7:BOTTOM=L7 |
| U56_A1 | OTHERS | BUS | 7 | 5 | 5 | 10 | 5 | 14 | 6 | 10 | 12 | 12 | 12 | 12 |  | 50 Ohms | TOP=L2:L3=L2/L4:L6=L5/L7:BOTTOM=L7 |
| U56_A1 | OTHERS | BUS | 8 | 4.75 | 5 | 10 | 5 | 14 | 6 | 9.5 | 12 | 12 | 12 | 12 |  | 50 Ohms | TOP=L2:L3=L2/L4:L6=L5/L7:BOTTOM=L7 |
| U56_A2 | OTHERS | BUS | 1 | 4.75 | 5 | 10 | 5 | 14 | 6 | 9.5 | 12 | 12 | 12 | 12 |  | 50 Ohms | TOP=L2:L3=L2/L4:L6=L5/L7:BOTTOM=L7 |
| U56_A2 | OTHERS | BUS | 2 | 5 | 5 | 10 | 5 | 14 | 6 | 10 | 12 | 12 | 12 | 12 |  | 50 Ohms | TOP=L2:L3=L2/L4:L6=L5/L7:BOTTOM=L7 |
| U56_A2 | OTHERS | BUS | 3 | 5 | 5 | 10 | 5 | 14 | 6 | 10 | 12 | 12 | 12 | 12 |  | 50 Ohms | TOP=L2:L3=L2/L4:L6=L5/L7:BOTTOM=L7 |
| U56_A2 | OTHERS | BUS | 4 | 5 | 5 | 10 | 5 | 14 | 6 | 10 | 12 | 12 | 12 | 12 |  | 50 Ohms | TOP=L2:L3=L2/L4:L6=L5/L7:BOTTOM=L7 |
| U56_A2 | OTHERS | BUS | 5 | 5 | 5 | 10 | 5 | 14 | 6 | 10 | 12 | 12 | 12 | 12 |  | 50 Ohms | TOP=L2:L3=L2/L4:L6=L5/L7:BOTTOM=L7 |
| U56_A2 | OTHERS | BUS | 6 | 5 | 5 | 10 | 5 | 14 | 6 | 10 | 12 | 12 | 12 | 12 |  | 50 Ohms | TOP=L2:L3=L2/L4:L6=L5/L7:BOTTOM=L7 |
| U56_A2 | OTHERS | BUS | 7 | 5 | 5 | 10 | 5 | 14 | 6 | 10 | 12 | 12 | 12 | 12 |  | 50 Ohms | TOP=L2:L3=L2/L4:L6=L5/L7:BOTTOM=L7 |
| U56_A2 | OTHERS | BUS | 8 | 4.75 | 5 | 10 | 5 | 14 | 6 | 9.5 | 12 | 12 | 12 | 12 |  | 50 Ohms | TOP=L2:L3=L2/L4:L6=L5/L7:BOTTOM=L7 |
| U56_INT_N | OTHERS | BUS | 1 | 4.75 | 5 | 10 | 5 | 14 | 6 | 9.5 | 12 | 12 | 12 | 12 |  | 50 Ohms | TOP=L2:L3=L2/L4:L6=L5/L7:BOTTOM=L7 |
| U56_INT_N | OTHERS | BUS | 2 | 5 | 5 | 10 | 5 | 14 | 6 | 10 | 12 | 12 | 12 | 12 |  | 50 Ohms | TOP=L2:L3=L2/L4:L6=L5/L7:BOTTOM=L7 |
| U56_INT_N | OTHERS | BUS | 3 | 5 | 5 | 10 | 5 | 14 | 6 | 10 | 12 | 12 | 12 | 12 |  | 50 Ohms | TOP=L2:L3=L2/L4:L6=L5/L7:BOTTOM=L7 |
| U56_INT_N | OTHERS | BUS | 4 | 5 | 5 | 10 | 5 | 14 | 6 | 10 | 12 | 12 | 12 | 12 |  | 50 Ohms | TOP=L2:L3=L2/L4:L6=L5/L7:BOTTOM=L7 |
| U56_INT_N | OTHERS | BUS | 5 | 5 | 5 | 10 | 5 | 14 | 6 | 10 | 12 | 12 | 12 | 12 |  | 50 Ohms | TOP=L2:L3=L2/L4:L6=L5/L7:BOTTOM=L7 |
| U56_INT_N | OTHERS | BUS | 6 | 5 | 5 | 10 | 5 | 14 | 6 | 10 | 12 | 12 | 12 | 12 |  | 50 Ohms | TOP=L2:L3=L2/L4:L6=L5/L7:BOTTOM=L7 |
| U56_INT_N | OTHERS | BUS | 7 | 5 | 5 | 10 | 5 | 14 | 6 | 10 | 12 | 12 | 12 | 12 |  | 50 Ohms | TOP=L2:L3=L2/L4:L6=L5/L7:BOTTOM=L7 |
| U56_INT_N | OTHERS | BUS | 8 | 4.75 | 5 | 10 | 5 | 14 | 6 | 9.5 | 12 | 12 | 12 | 12 |  | 50 Ohms | TOP=L2:L3=L2/L4:L6=L5/L7:BOTTOM=L7 |
| U80_B | OTHERS | BUS | 1 | 4.75 | 5 | 10 | 5 | 14 | 6 | 9.5 | 12 | 12 | 12 | 12 |  | 50 Ohms | TOP=L2:L3=L2/L4:L6=L5/L7:BOTTOM=L7 |
| U80_B | OTHERS | BUS | 2 | 5 | 5 | 10 | 5 | 14 | 6 | 10 | 12 | 12 | 12 | 12 |  | 50 Ohms | TOP=L2:L3=L2/L4:L6=L5/L7:BOTTOM=L7 |
| U80_B | OTHERS | BUS | 3 | 5 | 5 | 10 | 5 | 14 | 6 | 10 | 12 | 12 | 12 | 12 |  | 50 Ohms | TOP=L2:L3=L2/L4:L6=L5/L7:BOTTOM=L7 |
| U80_B | OTHERS | BUS | 4 | 5 | 5 | 10 | 5 | 14 | 6 | 10 | 12 | 12 | 12 | 12 |  | 50 Ohms | TOP=L2:L3=L2/L4:L6=L5/L7:BOTTOM=L7 |
| U80_B | OTHERS | BUS | 5 | 5 | 5 | 10 | 5 | 14 | 6 | 10 | 12 | 12 | 12 | 12 |  | 50 Ohms | TOP=L2:L3=L2/L4:L6=L5/L7:BOTTOM=L7 |
| U80_B | OTHERS | BUS | 6 | 5 | 5 | 10 | 5 | 14 | 6 | 10 | 12 | 12 | 12 | 12 |  | 50 Ohms | TOP=L2:L3=L2/L4:L6=L5/L7:BOTTOM=L7 |
| U80_B | OTHERS | BUS | 7 | 5 | 5 | 10 | 5 | 14 | 6 | 10 | 12 | 12 | 12 | 12 |  | 50 Ohms | TOP=L2:L3=L2/L4:L6=L5/L7:BOTTOM=L7 |
| U80_B | OTHERS | BUS | 8 | 4.75 | 5 | 10 | 5 | 14 | 6 | 9.5 | 12 | 12 | 12 | 12 |  | 50 Ohms | TOP=L2:L3=L2/L4:L6=L5/L7:BOTTOM=L7 |
| U81_B | OTHERS | BUS | 1 | 4.75 | 5 | 10 | 5 | 14 | 6 | 9.5 | 12 | 12 | 12 | 12 |  | 50 Ohms | TOP=L2:L3=L2/L4:L6=L5/L7:BOTTOM=L7 |
| U81_B | OTHERS | BUS | 2 | 5 | 5 | 10 | 5 | 14 | 6 | 10 | 12 | 12 | 12 | 12 |  | 50 Ohms | TOP=L2:L3=L2/L4:L6=L5/L7:BOTTOM=L7 |
| U81_B | OTHERS | BUS | 3 | 5 | 5 | 10 | 5 | 14 | 6 | 10 | 12 | 12 | 12 | 12 |  | 50 Ohms | TOP=L2:L3=L2/L4:L6=L5/L7:BOTTOM=L7 |
| U81_B | OTHERS | BUS | 4 | 5 | 5 | 10 | 5 | 14 | 6 | 10 | 12 | 12 | 12 | 12 |  | 50 Ohms | TOP=L2:L3=L2/L4:L6=L5/L7:BOTTOM=L7 |
| U81_B | OTHERS | BUS | 5 | 5 | 5 | 10 | 5 | 14 | 6 | 10 | 12 | 12 | 12 | 12 |  | 50 Ohms | TOP=L2:L3=L2/L4:L6=L5/L7:BOTTOM=L7 |
| U81_B | OTHERS | BUS | 6 | 5 | 5 | 10 | 5 | 14 | 6 | 10 | 12 | 12 | 12 | 12 |  | 50 Ohms | TOP=L2:L3=L2/L4:L6=L5/L7:BOTTOM=L7 |
| U81_B | OTHERS | BUS | 7 | 5 | 5 | 10 | 5 | 14 | 6 | 10 | 12 | 12 | 12 | 12 |  | 50 Ohms | TOP=L2:L3=L2/L4:L6=L5/L7:BOTTOM=L7 |
| U81_B | OTHERS | BUS | 8 | 4.75 | 5 | 10 | 5 | 14 | 6 | 9.5 | 12 | 12 | 12 | 12 |  | 50 Ohms | TOP=L2:L3=L2/L4:L6=L5/L7:BOTTOM=L7 |
| U81_Y | OTHERS | BUS | 1 | 4.75 | 5 | 10 | 5 | 14 | 6 | 9.5 | 12 | 12 | 12 | 12 |  | 50 Ohms | TOP=L2:L3=L2/L4:L6=L5/L7:BOTTOM=L7 |
| U81_Y | OTHERS | BUS | 2 | 5 | 5 | 10 | 5 | 14 | 6 | 10 | 12 | 12 | 12 | 12 |  | 50 Ohms | TOP=L2:L3=L2/L4:L6=L5/L7:BOTTOM=L7 |
| U81_Y | OTHERS | BUS | 3 | 5 | 5 | 10 | 5 | 14 | 6 | 10 | 12 | 12 | 12 | 12 |  | 50 Ohms | TOP=L2:L3=L2/L4:L6=L5/L7:BOTTOM=L7 |
| U81_Y | OTHERS | BUS | 4 | 5 | 5 | 10 | 5 | 14 | 6 | 10 | 12 | 12 | 12 | 12 |  | 50 Ohms | TOP=L2:L3=L2/L4:L6=L5/L7:BOTTOM=L7 |
| U81_Y | OTHERS | BUS | 5 | 5 | 5 | 10 | 5 | 14 | 6 | 10 | 12 | 12 | 12 | 12 |  | 50 Ohms | TOP=L2:L3=L2/L4:L6=L5/L7:BOTTOM=L7 |
| U81_Y | OTHERS | BUS | 6 | 5 | 5 | 10 | 5 | 14 | 6 | 10 | 12 | 12 | 12 | 12 |  | 50 Ohms | TOP=L2:L3=L2/L4:L6=L5/L7:BOTTOM=L7 |
| U81_Y | OTHERS | BUS | 7 | 5 | 5 | 10 | 5 | 14 | 6 | 10 | 12 | 12 | 12 | 12 |  | 50 Ohms | TOP=L2:L3=L2/L4:L6=L5/L7:BOTTOM=L7 |
| U81_Y | OTHERS | BUS | 8 | 4.75 | 5 | 10 | 5 | 14 | 6 | 9.5 | 12 | 12 | 12 | 12 |  | 50 Ohms | TOP=L2:L3=L2/L4:L6=L5/L7:BOTTOM=L7 |
| U82_MR# | OTHERS | BUS | 1 | 4.75 | 5 | 10 | 5 | 14 | 6 | 9.5 | 12 | 12 | 12 | 12 |  | 50 Ohms | TOP=L2:L3=L2/L4:L6=L5/L7:BOTTOM=L7 |
| U82_MR# | OTHERS | BUS | 2 | 5 | 5 | 10 | 5 | 14 | 6 | 10 | 12 | 12 | 12 | 12 |  | 50 Ohms | TOP=L2:L3=L2/L4:L6=L5/L7:BOTTOM=L7 |
| U82_MR# | OTHERS | BUS | 3 | 5 | 5 | 10 | 5 | 14 | 6 | 10 | 12 | 12 | 12 | 12 |  | 50 Ohms | TOP=L2:L3=L2/L4:L6=L5/L7:BOTTOM=L7 |
| U82_MR# | OTHERS | BUS | 4 | 5 | 5 | 10 | 5 | 14 | 6 | 10 | 12 | 12 | 12 | 12 |  | 50 Ohms | TOP=L2:L3=L2/L4:L6=L5/L7:BOTTOM=L7 |
| U82_MR# | OTHERS | BUS | 5 | 5 | 5 | 10 | 5 | 14 | 6 | 10 | 12 | 12 | 12 | 12 |  | 50 Ohms | TOP=L2:L3=L2/L4:L6=L5/L7:BOTTOM=L7 |
| U82_MR# | OTHERS | BUS | 6 | 5 | 5 | 10 | 5 | 14 | 6 | 10 | 12 | 12 | 12 | 12 |  | 50 Ohms | TOP=L2:L3=L2/L4:L6=L5/L7:BOTTOM=L7 |
| U82_MR# | OTHERS | BUS | 7 | 5 | 5 | 10 | 5 | 14 | 6 | 10 | 12 | 12 | 12 | 12 |  | 50 Ohms | TOP=L2:L3=L2/L4:L6=L5/L7:BOTTOM=L7 |
| U82_MR# | OTHERS | BUS | 8 | 4.75 | 5 | 10 | 5 | 14 | 6 | 9.5 | 12 | 12 | 12 | 12 |  | 50 Ohms | TOP=L2:L3=L2/L4:L6=L5/L7:BOTTOM=L7 |
| U82_RST# | OTHERS | BUS | 1 | 4.75 | 5 | 10 | 5 | 14 | 6 | 9.5 | 12 | 12 | 12 | 12 |  | 50 Ohms | TOP=L2:L3=L2/L4:L6=L5/L7:BOTTOM=L7 |
| U82_RST# | OTHERS | BUS | 2 | 5 | 5 | 10 | 5 | 14 | 6 | 10 | 12 | 12 | 12 | 12 |  | 50 Ohms | TOP=L2:L3=L2/L4:L6=L5/L7:BOTTOM=L7 |
| U82_RST# | OTHERS | BUS | 3 | 5 | 5 | 10 | 5 | 14 | 6 | 10 | 12 | 12 | 12 | 12 |  | 50 Ohms | TOP=L2:L3=L2/L4:L6=L5/L7:BOTTOM=L7 |
| U82_RST# | OTHERS | BUS | 4 | 5 | 5 | 10 | 5 | 14 | 6 | 10 | 12 | 12 | 12 | 12 |  | 50 Ohms | TOP=L2:L3=L2/L4:L6=L5/L7:BOTTOM=L7 |
| U82_RST# | OTHERS | BUS | 5 | 5 | 5 | 10 | 5 | 14 | 6 | 10 | 12 | 12 | 12 | 12 |  | 50 Ohms | TOP=L2:L3=L2/L4:L6=L5/L7:BOTTOM=L7 |
| U82_RST# | OTHERS | BUS | 6 | 5 | 5 | 10 | 5 | 14 | 6 | 10 | 12 | 12 | 12 | 12 |  | 50 Ohms | TOP=L2:L3=L2/L4:L6=L5/L7:BOTTOM=L7 |
| U82_RST# | OTHERS | BUS | 7 | 5 | 5 | 10 | 5 | 14 | 6 | 10 | 12 | 12 | 12 | 12 |  | 50 Ohms | TOP=L2:L3=L2/L4:L6=L5/L7:BOTTOM=L7 |
| U82_RST# | OTHERS | BUS | 8 | 4.75 | 5 | 10 | 5 | 14 | 6 | 9.5 | 12 | 12 | 12 | 12 |  | 50 Ohms | TOP=L2:L3=L2/L4:L6=L5/L7:BOTTOM=L7 |
| UART_COUNT | OTHERS | BUS | 1 | 4.75 | 5 | 10 | 5 | 14 | 6 | 9.5 | 12 | 12 | 12 | 12 |  | 50 Ohms | TOP=L2:L3=L2/L4:L6=L5/L7:BOTTOM=L7 |
| UART_COUNT | OTHERS | BUS | 2 | 5 | 5 | 10 | 5 | 14 | 6 | 10 | 12 | 12 | 12 | 12 |  | 50 Ohms | TOP=L2:L3=L2/L4:L6=L5/L7:BOTTOM=L7 |
| UART_COUNT | OTHERS | BUS | 3 | 5 | 5 | 10 | 5 | 14 | 6 | 10 | 12 | 12 | 12 | 12 |  | 50 Ohms | TOP=L2:L3=L2/L4:L6=L5/L7:BOTTOM=L7 |
| UART_COUNT | OTHERS | BUS | 4 | 5 | 5 | 10 | 5 | 14 | 6 | 10 | 12 | 12 | 12 | 12 |  | 50 Ohms | TOP=L2:L3=L2/L4:L6=L5/L7:BOTTOM=L7 |
| UART_COUNT | OTHERS | BUS | 5 | 5 | 5 | 10 | 5 | 14 | 6 | 10 | 12 | 12 | 12 | 12 |  | 50 Ohms | TOP=L2:L3=L2/L4:L6=L5/L7:BOTTOM=L7 |
| UART_COUNT | OTHERS | BUS | 6 | 5 | 5 | 10 | 5 | 14 | 6 | 10 | 12 | 12 | 12 | 12 |  | 50 Ohms | TOP=L2:L3=L2/L4:L6=L5/L7:BOTTOM=L7 |
| UART_COUNT | OTHERS | BUS | 7 | 5 | 5 | 10 | 5 | 14 | 6 | 10 | 12 | 12 | 12 | 12 |  | 50 Ohms | TOP=L2:L3=L2/L4:L6=L5/L7:BOTTOM=L7 |
| UART_COUNT | OTHERS | BUS | 8 | 4.75 | 5 | 10 | 5 | 14 | 6 | 9.5 | 12 | 12 | 12 | 12 |  | 50 Ohms | TOP=L2:L3=L2/L4:L6=L5/L7:BOTTOM=L7 |
| UART_SWITCH_R | OTHERS | BUS | 1 | 4.75 | 5 | 10 | 5 | 14 | 6 | 9.5 | 12 | 12 | 12 | 12 |  | 50 Ohms | TOP=L2:L3=L2/L4:L6=L5/L7:BOTTOM=L7 |
| UART_SWITCH_R | OTHERS | BUS | 2 | 5 | 5 | 10 | 5 | 14 | 6 | 10 | 12 | 12 | 12 | 12 |  | 50 Ohms | TOP=L2:L3=L2/L4:L6=L5/L7:BOTTOM=L7 |
| UART_SWITCH_R | OTHERS | BUS | 3 | 5 | 5 | 10 | 5 | 14 | 6 | 10 | 12 | 12 | 12 | 12 |  | 50 Ohms | TOP=L2:L3=L2/L4:L6=L5/L7:BOTTOM=L7 |
| UART_SWITCH_R | OTHERS | BUS | 4 | 5 | 5 | 10 | 5 | 14 | 6 | 10 | 12 | 12 | 12 | 12 |  | 50 Ohms | TOP=L2:L3=L2/L4:L6=L5/L7:BOTTOM=L7 |
| UART_SWITCH_R | OTHERS | BUS | 5 | 5 | 5 | 10 | 5 | 14 | 6 | 10 | 12 | 12 | 12 | 12 |  | 50 Ohms | TOP=L2:L3=L2/L4:L6=L5/L7:BOTTOM=L7 |
| UART_SWITCH_R | OTHERS | BUS | 6 | 5 | 5 | 10 | 5 | 14 | 6 | 10 | 12 | 12 | 12 | 12 |  | 50 Ohms | TOP=L2:L3=L2/L4:L6=L5/L7:BOTTOM=L7 |
| UART_SWITCH_R | OTHERS | BUS | 7 | 5 | 5 | 10 | 5 | 14 | 6 | 10 | 12 | 12 | 12 | 12 |  | 50 Ohms | TOP=L2:L3=L2/L4:L6=L5/L7:BOTTOM=L7 |
| UART_SWITCH_R | OTHERS | BUS | 8 | 4.75 | 5 | 10 | 5 | 14 | 6 | 9.5 | 12 | 12 | 12 | 12 |  | 50 Ohms | TOP=L2:L3=L2/L4:L6=L5/L7:BOTTOM=L7 |
| UART_USIN | OTHERS | BUS | 1 | 4.75 | 5 | 10 | 5 | 14 | 6 | 9.5 | 12 | 12 | 12 | 12 |  | 50 Ohms | TOP=L2:L3=L2/L4:L6=L5/L7:BOTTOM=L7 |
| UART_USIN | OTHERS | BUS | 2 | 5 | 5 | 10 | 5 | 14 | 6 | 10 | 12 | 12 | 12 | 12 |  | 50 Ohms | TOP=L2:L3=L2/L4:L6=L5/L7:BOTTOM=L7 |
| UART_USIN | OTHERS | BUS | 3 | 5 | 5 | 10 | 5 | 14 | 6 | 10 | 12 | 12 | 12 | 12 |  | 50 Ohms | TOP=L2:L3=L2/L4:L6=L5/L7:BOTTOM=L7 |
| UART_USIN | OTHERS | BUS | 4 | 5 | 5 | 10 | 5 | 14 | 6 | 10 | 12 | 12 | 12 | 12 |  | 50 Ohms | TOP=L2:L3=L2/L4:L6=L5/L7:BOTTOM=L7 |
| UART_USIN | OTHERS | BUS | 5 | 5 | 5 | 10 | 5 | 14 | 6 | 10 | 12 | 12 | 12 | 12 |  | 50 Ohms | TOP=L2:L3=L2/L4:L6=L5/L7:BOTTOM=L7 |
| UART_USIN | OTHERS | BUS | 6 | 5 | 5 | 10 | 5 | 14 | 6 | 10 | 12 | 12 | 12 | 12 |  | 50 Ohms | TOP=L2:L3=L2/L4:L6=L5/L7:BOTTOM=L7 |
| UART_USIN | OTHERS | BUS | 7 | 5 | 5 | 10 | 5 | 14 | 6 | 10 | 12 | 12 | 12 | 12 |  | 50 Ohms | TOP=L2:L3=L2/L4:L6=L5/L7:BOTTOM=L7 |
| UART_USIN | OTHERS | BUS | 8 | 4.75 | 5 | 10 | 5 | 14 | 6 | 9.5 | 12 | 12 | 12 | 12 |  | 50 Ohms | TOP=L2:L3=L2/L4:L6=L5/L7:BOTTOM=L7 |
| UART_USOUT | OTHERS | BUS | 1 | 4.75 | 5 | 10 | 5 | 14 | 6 | 9.5 | 12 | 12 | 12 | 12 |  | 50 Ohms | TOP=L2:L3=L2/L4:L6=L5/L7:BOTTOM=L7 |
| UART_USOUT | OTHERS | BUS | 2 | 5 | 5 | 10 | 5 | 14 | 6 | 10 | 12 | 12 | 12 | 12 |  | 50 Ohms | TOP=L2:L3=L2/L4:L6=L5/L7:BOTTOM=L7 |
| UART_USOUT | OTHERS | BUS | 3 | 5 | 5 | 10 | 5 | 14 | 6 | 10 | 12 | 12 | 12 | 12 |  | 50 Ohms | TOP=L2:L3=L2/L4:L6=L5/L7:BOTTOM=L7 |
| UART_USOUT | OTHERS | BUS | 4 | 5 | 5 | 10 | 5 | 14 | 6 | 10 | 12 | 12 | 12 | 12 |  | 50 Ohms | TOP=L2:L3=L2/L4:L6=L5/L7:BOTTOM=L7 |
| UART_USOUT | OTHERS | BUS | 5 | 5 | 5 | 10 | 5 | 14 | 6 | 10 | 12 | 12 | 12 | 12 |  | 50 Ohms | TOP=L2:L3=L2/L4:L6=L5/L7:BOTTOM=L7 |
| UART_USOUT | OTHERS | BUS | 6 | 5 | 5 | 10 | 5 | 14 | 6 | 10 | 12 | 12 | 12 | 12 |  | 50 Ohms | TOP=L2:L3=L2/L4:L6=L5/L7:BOTTOM=L7 |
| UART_USOUT | OTHERS | BUS | 7 | 5 | 5 | 10 | 5 | 14 | 6 | 10 | 12 | 12 | 12 | 12 |  | 50 Ohms | TOP=L2:L3=L2/L4:L6=L5/L7:BOTTOM=L7 |
| UART_USOUT | OTHERS | BUS | 8 | 4.75 | 5 | 10 | 5 | 14 | 6 | 9.5 | 12 | 12 | 12 | 12 |  | 50 Ohms | TOP=L2:L3=L2/L4:L6=L5/L7:BOTTOM=L7 |
| UPLINK1 | OTHERS | BUS | 1 | 4.75 | 5 | 10 | 5 | 14 | 6 | 9.5 | 12 | 12 | 12 | 12 |  | 50 Ohms | TOP=L2:L3=L2/L4:L6=L5/L7:BOTTOM=L7 |
| UPLINK1 | OTHERS | BUS | 2 | 5 | 5 | 10 | 5 | 14 | 6 | 10 | 12 | 12 | 12 | 12 |  | 50 Ohms | TOP=L2:L3=L2/L4:L6=L5/L7:BOTTOM=L7 |
| UPLINK1 | OTHERS | BUS | 3 | 5 | 5 | 10 | 5 | 14 | 6 | 10 | 12 | 12 | 12 | 12 |  | 50 Ohms | TOP=L2:L3=L2/L4:L6=L5/L7:BOTTOM=L7 |
| UPLINK1 | OTHERS | BUS | 4 | 5 | 5 | 10 | 5 | 14 | 6 | 10 | 12 | 12 | 12 | 12 |  | 50 Ohms | TOP=L2:L3=L2/L4:L6=L5/L7:BOTTOM=L7 |
| UPLINK1 | OTHERS | BUS | 5 | 5 | 5 | 10 | 5 | 14 | 6 | 10 | 12 | 12 | 12 | 12 |  | 50 Ohms | TOP=L2:L3=L2/L4:L6=L5/L7:BOTTOM=L7 |
| UPLINK1 | OTHERS | BUS | 6 | 5 | 5 | 10 | 5 | 14 | 6 | 10 | 12 | 12 | 12 | 12 |  | 50 Ohms | TOP=L2:L3=L2/L4:L6=L5/L7:BOTTOM=L7 |
| UPLINK1 | OTHERS | BUS | 7 | 5 | 5 | 10 | 5 | 14 | 6 | 10 | 12 | 12 | 12 | 12 |  | 50 Ohms | TOP=L2:L3=L2/L4:L6=L5/L7:BOTTOM=L7 |
| UPLINK1 | OTHERS | BUS | 8 | 4.75 | 5 | 10 | 5 | 14 | 6 | 9.5 | 12 | 12 | 12 | 12 |  | 50 Ohms | TOP=L2:L3=L2/L4:L6=L5/L7:BOTTOM=L7 |
| UPLINK1_R | OTHERS | BUS | 1 | 4.75 | 5 | 10 | 5 | 14 | 6 | 9.5 | 12 | 12 | 12 | 12 |  | 50 Ohms | TOP=L2:L3=L2/L4:L6=L5/L7:BOTTOM=L7 |
| UPLINK1_R | OTHERS | BUS | 2 | 5 | 5 | 10 | 5 | 14 | 6 | 10 | 12 | 12 | 12 | 12 |  | 50 Ohms | TOP=L2:L3=L2/L4:L6=L5/L7:BOTTOM=L7 |
| UPLINK1_R | OTHERS | BUS | 3 | 5 | 5 | 10 | 5 | 14 | 6 | 10 | 12 | 12 | 12 | 12 |  | 50 Ohms | TOP=L2:L3=L2/L4:L6=L5/L7:BOTTOM=L7 |
| UPLINK1_R | OTHERS | BUS | 4 | 5 | 5 | 10 | 5 | 14 | 6 | 10 | 12 | 12 | 12 | 12 |  | 50 Ohms | TOP=L2:L3=L2/L4:L6=L5/L7:BOTTOM=L7 |
| UPLINK1_R | OTHERS | BUS | 5 | 5 | 5 | 10 | 5 | 14 | 6 | 10 | 12 | 12 | 12 | 12 |  | 50 Ohms | TOP=L2:L3=L2/L4:L6=L5/L7:BOTTOM=L7 |
| UPLINK1_R | OTHERS | BUS | 6 | 5 | 5 | 10 | 5 | 14 | 6 | 10 | 12 | 12 | 12 | 12 |  | 50 Ohms | TOP=L2:L3=L2/L4:L6=L5/L7:BOTTOM=L7 |
| UPLINK1_R | OTHERS | BUS | 7 | 5 | 5 | 10 | 5 | 14 | 6 | 10 | 12 | 12 | 12 | 12 |  | 50 Ohms | TOP=L2:L3=L2/L4:L6=L5/L7:BOTTOM=L7 |
| UPLINK1_R | OTHERS | BUS | 8 | 4.75 | 5 | 10 | 5 | 14 | 6 | 9.5 | 12 | 12 | 12 | 12 |  | 50 Ohms | TOP=L2:L3=L2/L4:L6=L5/L7:BOTTOM=L7 |
| UPLINK2 | OTHERS | BUS | 1 | 4.75 | 5 | 10 | 5 | 14 | 6 | 9.5 | 12 | 12 | 12 | 12 |  | 50 Ohms | TOP=L2:L3=L2/L4:L6=L5/L7:BOTTOM=L7 |
| UPLINK2 | OTHERS | BUS | 2 | 5 | 5 | 10 | 5 | 14 | 6 | 10 | 12 | 12 | 12 | 12 |  | 50 Ohms | TOP=L2:L3=L2/L4:L6=L5/L7:BOTTOM=L7 |
| UPLINK2 | OTHERS | BUS | 3 | 5 | 5 | 10 | 5 | 14 | 6 | 10 | 12 | 12 | 12 | 12 |  | 50 Ohms | TOP=L2:L3=L2/L4:L6=L5/L7:BOTTOM=L7 |
| UPLINK2 | OTHERS | BUS | 4 | 5 | 5 | 10 | 5 | 14 | 6 | 10 | 12 | 12 | 12 | 12 |  | 50 Ohms | TOP=L2:L3=L2/L4:L6=L5/L7:BOTTOM=L7 |
| UPLINK2 | OTHERS | BUS | 5 | 5 | 5 | 10 | 5 | 14 | 6 | 10 | 12 | 12 | 12 | 12 |  | 50 Ohms | TOP=L2:L3=L2/L4:L6=L5/L7:BOTTOM=L7 |
| UPLINK2 | OTHERS | BUS | 6 | 5 | 5 | 10 | 5 | 14 | 6 | 10 | 12 | 12 | 12 | 12 |  | 50 Ohms | TOP=L2:L3=L2/L4:L6=L5/L7:BOTTOM=L7 |
| UPLINK2 | OTHERS | BUS | 7 | 5 | 5 | 10 | 5 | 14 | 6 | 10 | 12 | 12 | 12 | 12 |  | 50 Ohms | TOP=L2:L3=L2/L4:L6=L5/L7:BOTTOM=L7 |
| UPLINK2 | OTHERS | BUS | 8 | 4.75 | 5 | 10 | 5 | 14 | 6 | 9.5 | 12 | 12 | 12 | 12 |  | 50 Ohms | TOP=L2:L3=L2/L4:L6=L5/L7:BOTTOM=L7 |
| UPLINK2_R | OTHERS | BUS | 1 | 4.75 | 5 | 10 | 5 | 14 | 6 | 9.5 | 12 | 12 | 12 | 12 |  | 50 Ohms | TOP=L2:L3=L2/L4:L6=L5/L7:BOTTOM=L7 |
| UPLINK2_R | OTHERS | BUS | 2 | 5 | 5 | 10 | 5 | 14 | 6 | 10 | 12 | 12 | 12 | 12 |  | 50 Ohms | TOP=L2:L3=L2/L4:L6=L5/L7:BOTTOM=L7 |
| UPLINK2_R | OTHERS | BUS | 3 | 5 | 5 | 10 | 5 | 14 | 6 | 10 | 12 | 12 | 12 | 12 |  | 50 Ohms | TOP=L2:L3=L2/L4:L6=L5/L7:BOTTOM=L7 |
| UPLINK2_R | OTHERS | BUS | 4 | 5 | 5 | 10 | 5 | 14 | 6 | 10 | 12 | 12 | 12 | 12 |  | 50 Ohms | TOP=L2:L3=L2/L4:L6=L5/L7:BOTTOM=L7 |
| UPLINK2_R | OTHERS | BUS | 5 | 5 | 5 | 10 | 5 | 14 | 6 | 10 | 12 | 12 | 12 | 12 |  | 50 Ohms | TOP=L2:L3=L2/L4:L6=L5/L7:BOTTOM=L7 |
| UPLINK2_R | OTHERS | BUS | 6 | 5 | 5 | 10 | 5 | 14 | 6 | 10 | 12 | 12 | 12 | 12 |  | 50 Ohms | TOP=L2:L3=L2/L4:L6=L5/L7:BOTTOM=L7 |
| UPLINK2_R | OTHERS | BUS | 7 | 5 | 5 | 10 | 5 | 14 | 6 | 10 | 12 | 12 | 12 | 12 |  | 50 Ohms | TOP=L2:L3=L2/L4:L6=L5/L7:BOTTOM=L7 |
| UPLINK2_R | OTHERS | BUS | 8 | 4.75 | 5 | 10 | 5 | 14 | 6 | 9.5 | 12 | 12 | 12 | 12 |  | 50 Ohms | TOP=L2:L3=L2/L4:L6=L5/L7:BOTTOM=L7 |
| UPLINK3 | OTHERS | BUS | 1 | 4.75 | 5 | 10 | 5 | 14 | 6 | 9.5 | 12 | 12 | 12 | 12 |  | 50 Ohms | TOP=L2:L3=L2/L4:L6=L5/L7:BOTTOM=L7 |
| UPLINK3 | OTHERS | BUS | 2 | 5 | 5 | 10 | 5 | 14 | 6 | 10 | 12 | 12 | 12 | 12 |  | 50 Ohms | TOP=L2:L3=L2/L4:L6=L5/L7:BOTTOM=L7 |
| UPLINK3 | OTHERS | BUS | 3 | 5 | 5 | 10 | 5 | 14 | 6 | 10 | 12 | 12 | 12 | 12 |  | 50 Ohms | TOP=L2:L3=L2/L4:L6=L5/L7:BOTTOM=L7 |
| UPLINK3 | OTHERS | BUS | 4 | 5 | 5 | 10 | 5 | 14 | 6 | 10 | 12 | 12 | 12 | 12 |  | 50 Ohms | TOP=L2:L3=L2/L4:L6=L5/L7:BOTTOM=L7 |
| UPLINK3 | OTHERS | BUS | 5 | 5 | 5 | 10 | 5 | 14 | 6 | 10 | 12 | 12 | 12 | 12 |  | 50 Ohms | TOP=L2:L3=L2/L4:L6=L5/L7:BOTTOM=L7 |
| UPLINK3 | OTHERS | BUS | 6 | 5 | 5 | 10 | 5 | 14 | 6 | 10 | 12 | 12 | 12 | 12 |  | 50 Ohms | TOP=L2:L3=L2/L4:L6=L5/L7:BOTTOM=L7 |
| UPLINK3 | OTHERS | BUS | 7 | 5 | 5 | 10 | 5 | 14 | 6 | 10 | 12 | 12 | 12 | 12 |  | 50 Ohms | TOP=L2:L3=L2/L4:L6=L5/L7:BOTTOM=L7 |
| UPLINK3 | OTHERS | BUS | 8 | 4.75 | 5 | 10 | 5 | 14 | 6 | 9.5 | 12 | 12 | 12 | 12 |  | 50 Ohms | TOP=L2:L3=L2/L4:L6=L5/L7:BOTTOM=L7 |
| UPLINK3_R | OTHERS | BUS | 1 | 4.75 | 5 | 10 | 5 | 14 | 6 | 9.5 | 12 | 12 | 12 | 12 |  | 50 Ohms | TOP=L2:L3=L2/L4:L6=L5/L7:BOTTOM=L7 |
| UPLINK3_R | OTHERS | BUS | 2 | 5 | 5 | 10 | 5 | 14 | 6 | 10 | 12 | 12 | 12 | 12 |  | 50 Ohms | TOP=L2:L3=L2/L4:L6=L5/L7:BOTTOM=L7 |
| UPLINK3_R | OTHERS | BUS | 3 | 5 | 5 | 10 | 5 | 14 | 6 | 10 | 12 | 12 | 12 | 12 |  | 50 Ohms | TOP=L2:L3=L2/L4:L6=L5/L7:BOTTOM=L7 |
| UPLINK3_R | OTHERS | BUS | 4 | 5 | 5 | 10 | 5 | 14 | 6 | 10 | 12 | 12 | 12 | 12 |  | 50 Ohms | TOP=L2:L3=L2/L4:L6=L5/L7:BOTTOM=L7 |
| UPLINK3_R | OTHERS | BUS | 5 | 5 | 5 | 10 | 5 | 14 | 6 | 10 | 12 | 12 | 12 | 12 |  | 50 Ohms | TOP=L2:L3=L2/L4:L6=L5/L7:BOTTOM=L7 |
| UPLINK3_R | OTHERS | BUS | 6 | 5 | 5 | 10 | 5 | 14 | 6 | 10 | 12 | 12 | 12 | 12 |  | 50 Ohms | TOP=L2:L3=L2/L4:L6=L5/L7:BOTTOM=L7 |
| UPLINK3_R | OTHERS | BUS | 7 | 5 | 5 | 10 | 5 | 14 | 6 | 10 | 12 | 12 | 12 | 12 |  | 50 Ohms | TOP=L2:L3=L2/L4:L6=L5/L7:BOTTOM=L7 |
| UPLINK3_R | OTHERS | BUS | 8 | 4.75 | 5 | 10 | 5 | 14 | 6 | 9.5 | 12 | 12 | 12 | 12 |  | 50 Ohms | TOP=L2:L3=L2/L4:L6=L5/L7:BOTTOM=L7 |
| UPLINK4 | OTHERS | BUS | 1 | 4.75 | 5 | 10 | 5 | 14 | 6 | 9.5 | 12 | 12 | 12 | 12 |  | 50 Ohms | TOP=L2:L3=L2/L4:L6=L5/L7:BOTTOM=L7 |
| UPLINK4 | OTHERS | BUS | 2 | 5 | 5 | 10 | 5 | 14 | 6 | 10 | 12 | 12 | 12 | 12 |  | 50 Ohms | TOP=L2:L3=L2/L4:L6=L5/L7:BOTTOM=L7 |
| UPLINK4 | OTHERS | BUS | 3 | 5 | 5 | 10 | 5 | 14 | 6 | 10 | 12 | 12 | 12 | 12 |  | 50 Ohms | TOP=L2:L3=L2/L4:L6=L5/L7:BOTTOM=L7 |
| UPLINK4 | OTHERS | BUS | 4 | 5 | 5 | 10 | 5 | 14 | 6 | 10 | 12 | 12 | 12 | 12 |  | 50 Ohms | TOP=L2:L3=L2/L4:L6=L5/L7:BOTTOM=L7 |
| UPLINK4 | OTHERS | BUS | 5 | 5 | 5 | 10 | 5 | 14 | 6 | 10 | 12 | 12 | 12 | 12 |  | 50 Ohms | TOP=L2:L3=L2/L4:L6=L5/L7:BOTTOM=L7 |
| UPLINK4 | OTHERS | BUS | 6 | 5 | 5 | 10 | 5 | 14 | 6 | 10 | 12 | 12 | 12 | 12 |  | 50 Ohms | TOP=L2:L3=L2/L4:L6=L5/L7:BOTTOM=L7 |
| UPLINK4 | OTHERS | BUS | 7 | 5 | 5 | 10 | 5 | 14 | 6 | 10 | 12 | 12 | 12 | 12 |  | 50 Ohms | TOP=L2:L3=L2/L4:L6=L5/L7:BOTTOM=L7 |
| UPLINK4 | OTHERS | BUS | 8 | 4.75 | 5 | 10 | 5 | 14 | 6 | 9.5 | 12 | 12 | 12 | 12 |  | 50 Ohms | TOP=L2:L3=L2/L4:L6=L5/L7:BOTTOM=L7 |
| UPLINK4_R | OTHERS | BUS | 1 | 4.75 | 5 | 10 | 5 | 14 | 6 | 9.5 | 12 | 12 | 12 | 12 |  | 50 Ohms | TOP=L2:L3=L2/L4:L6=L5/L7:BOTTOM=L7 |
| UPLINK4_R | OTHERS | BUS | 2 | 5 | 5 | 10 | 5 | 14 | 6 | 10 | 12 | 12 | 12 | 12 |  | 50 Ohms | TOP=L2:L3=L2/L4:L6=L5/L7:BOTTOM=L7 |
| UPLINK4_R | OTHERS | BUS | 3 | 5 | 5 | 10 | 5 | 14 | 6 | 10 | 12 | 12 | 12 | 12 |  | 50 Ohms | TOP=L2:L3=L2/L4:L6=L5/L7:BOTTOM=L7 |
| UPLINK4_R | OTHERS | BUS | 4 | 5 | 5 | 10 | 5 | 14 | 6 | 10 | 12 | 12 | 12 | 12 |  | 50 Ohms | TOP=L2:L3=L2/L4:L6=L5/L7:BOTTOM=L7 |
| UPLINK4_R | OTHERS | BUS | 5 | 5 | 5 | 10 | 5 | 14 | 6 | 10 | 12 | 12 | 12 | 12 |  | 50 Ohms | TOP=L2:L3=L2/L4:L6=L5/L7:BOTTOM=L7 |
| UPLINK4_R | OTHERS | BUS | 6 | 5 | 5 | 10 | 5 | 14 | 6 | 10 | 12 | 12 | 12 | 12 |  | 50 Ohms | TOP=L2:L3=L2/L4:L6=L5/L7:BOTTOM=L7 |
| UPLINK4_R | OTHERS | BUS | 7 | 5 | 5 | 10 | 5 | 14 | 6 | 10 | 12 | 12 | 12 | 12 |  | 50 Ohms | TOP=L2:L3=L2/L4:L6=L5/L7:BOTTOM=L7 |
| UPLINK4_R | OTHERS | BUS | 8 | 4.75 | 5 | 10 | 5 | 14 | 6 | 9.5 | 12 | 12 | 12 | 12 |  | 50 Ohms | TOP=L2:L3=L2/L4:L6=L5/L7:BOTTOM=L7 |
| UPLINK5 | OTHERS | BUS | 1 | 4.75 | 5 | 10 | 5 | 14 | 6 | 9.5 | 12 | 12 | 12 | 12 |  | 50 Ohms | TOP=L2:L3=L2/L4:L6=L5/L7:BOTTOM=L7 |
| UPLINK5 | OTHERS | BUS | 2 | 5 | 5 | 10 | 5 | 14 | 6 | 10 | 12 | 12 | 12 | 12 |  | 50 Ohms | TOP=L2:L3=L2/L4:L6=L5/L7:BOTTOM=L7 |
| UPLINK5 | OTHERS | BUS | 3 | 5 | 5 | 10 | 5 | 14 | 6 | 10 | 12 | 12 | 12 | 12 |  | 50 Ohms | TOP=L2:L3=L2/L4:L6=L5/L7:BOTTOM=L7 |
| UPLINK5 | OTHERS | BUS | 4 | 5 | 5 | 10 | 5 | 14 | 6 | 10 | 12 | 12 | 12 | 12 |  | 50 Ohms | TOP=L2:L3=L2/L4:L6=L5/L7:BOTTOM=L7 |
| UPLINK5 | OTHERS | BUS | 5 | 5 | 5 | 10 | 5 | 14 | 6 | 10 | 12 | 12 | 12 | 12 |  | 50 Ohms | TOP=L2:L3=L2/L4:L6=L5/L7:BOTTOM=L7 |
| UPLINK5 | OTHERS | BUS | 6 | 5 | 5 | 10 | 5 | 14 | 6 | 10 | 12 | 12 | 12 | 12 |  | 50 Ohms | TOP=L2:L3=L2/L4:L6=L5/L7:BOTTOM=L7 |
| UPLINK5 | OTHERS | BUS | 7 | 5 | 5 | 10 | 5 | 14 | 6 | 10 | 12 | 12 | 12 | 12 |  | 50 Ohms | TOP=L2:L3=L2/L4:L6=L5/L7:BOTTOM=L7 |
| UPLINK5 | OTHERS | BUS | 8 | 4.75 | 5 | 10 | 5 | 14 | 6 | 9.5 | 12 | 12 | 12 | 12 |  | 50 Ohms | TOP=L2:L3=L2/L4:L6=L5/L7:BOTTOM=L7 |
| UPLINK5_R | OTHERS | BUS | 1 | 4.75 | 5 | 10 | 5 | 14 | 6 | 9.5 | 12 | 12 | 12 | 12 |  | 50 Ohms | TOP=L2:L3=L2/L4:L6=L5/L7:BOTTOM=L7 |
| UPLINK5_R | OTHERS | BUS | 2 | 5 | 5 | 10 | 5 | 14 | 6 | 10 | 12 | 12 | 12 | 12 |  | 50 Ohms | TOP=L2:L3=L2/L4:L6=L5/L7:BOTTOM=L7 |
| UPLINK5_R | OTHERS | BUS | 3 | 5 | 5 | 10 | 5 | 14 | 6 | 10 | 12 | 12 | 12 | 12 |  | 50 Ohms | TOP=L2:L3=L2/L4:L6=L5/L7:BOTTOM=L7 |
| UPLINK5_R | OTHERS | BUS | 4 | 5 | 5 | 10 | 5 | 14 | 6 | 10 | 12 | 12 | 12 | 12 |  | 50 Ohms | TOP=L2:L3=L2/L4:L6=L5/L7:BOTTOM=L7 |
| UPLINK5_R | OTHERS | BUS | 5 | 5 | 5 | 10 | 5 | 14 | 6 | 10 | 12 | 12 | 12 | 12 |  | 50 Ohms | TOP=L2:L3=L2/L4:L6=L5/L7:BOTTOM=L7 |
| UPLINK5_R | OTHERS | BUS | 6 | 5 | 5 | 10 | 5 | 14 | 6 | 10 | 12 | 12 | 12 | 12 |  | 50 Ohms | TOP=L2:L3=L2/L4:L6=L5/L7:BOTTOM=L7 |
| UPLINK5_R | OTHERS | BUS | 7 | 5 | 5 | 10 | 5 | 14 | 6 | 10 | 12 | 12 | 12 | 12 |  | 50 Ohms | TOP=L2:L3=L2/L4:L6=L5/L7:BOTTOM=L7 |
| UPLINK5_R | OTHERS | BUS | 8 | 4.75 | 5 | 10 | 5 | 14 | 6 | 9.5 | 12 | 12 | 12 | 12 |  | 50 Ohms | TOP=L2:L3=L2/L4:L6=L5/L7:BOTTOM=L7 |
| UPLINK6 | OTHERS | BUS | 1 | 4.75 | 5 | 10 | 5 | 14 | 6 | 9.5 | 12 | 12 | 12 | 12 |  | 50 Ohms | TOP=L2:L3=L2/L4:L6=L5/L7:BOTTOM=L7 |
| UPLINK6 | OTHERS | BUS | 2 | 5 | 5 | 10 | 5 | 14 | 6 | 10 | 12 | 12 | 12 | 12 |  | 50 Ohms | TOP=L2:L3=L2/L4:L6=L5/L7:BOTTOM=L7 |
| UPLINK6 | OTHERS | BUS | 3 | 5 | 5 | 10 | 5 | 14 | 6 | 10 | 12 | 12 | 12 | 12 |  | 50 Ohms | TOP=L2:L3=L2/L4:L6=L5/L7:BOTTOM=L7 |
| UPLINK6 | OTHERS | BUS | 4 | 5 | 5 | 10 | 5 | 14 | 6 | 10 | 12 | 12 | 12 | 12 |  | 50 Ohms | TOP=L2:L3=L2/L4:L6=L5/L7:BOTTOM=L7 |
| UPLINK6 | OTHERS | BUS | 5 | 5 | 5 | 10 | 5 | 14 | 6 | 10 | 12 | 12 | 12 | 12 |  | 50 Ohms | TOP=L2:L3=L2/L4:L6=L5/L7:BOTTOM=L7 |
| UPLINK6 | OTHERS | BUS | 6 | 5 | 5 | 10 | 5 | 14 | 6 | 10 | 12 | 12 | 12 | 12 |  | 50 Ohms | TOP=L2:L3=L2/L4:L6=L5/L7:BOTTOM=L7 |
| UPLINK6 | OTHERS | BUS | 7 | 5 | 5 | 10 | 5 | 14 | 6 | 10 | 12 | 12 | 12 | 12 |  | 50 Ohms | TOP=L2:L3=L2/L4:L6=L5/L7:BOTTOM=L7 |
| UPLINK6 | OTHERS | BUS | 8 | 4.75 | 5 | 10 | 5 | 14 | 6 | 9.5 | 12 | 12 | 12 | 12 |  | 50 Ohms | TOP=L2:L3=L2/L4:L6=L5/L7:BOTTOM=L7 |
| UPLINK6_R | OTHERS | BUS | 1 | 4.75 | 5 | 10 | 5 | 14 | 6 | 9.5 | 12 | 12 | 12 | 12 |  | 50 Ohms | TOP=L2:L3=L2/L4:L6=L5/L7:BOTTOM=L7 |
| UPLINK6_R | OTHERS | BUS | 2 | 5 | 5 | 10 | 5 | 14 | 6 | 10 | 12 | 12 | 12 | 12 |  | 50 Ohms | TOP=L2:L3=L2/L4:L6=L5/L7:BOTTOM=L7 |
| UPLINK6_R | OTHERS | BUS | 3 | 5 | 5 | 10 | 5 | 14 | 6 | 10 | 12 | 12 | 12 | 12 |  | 50 Ohms | TOP=L2:L3=L2/L4:L6=L5/L7:BOTTOM=L7 |
| UPLINK6_R | OTHERS | BUS | 4 | 5 | 5 | 10 | 5 | 14 | 6 | 10 | 12 | 12 | 12 | 12 |  | 50 Ohms | TOP=L2:L3=L2/L4:L6=L5/L7:BOTTOM=L7 |
| UPLINK6_R | OTHERS | BUS | 5 | 5 | 5 | 10 | 5 | 14 | 6 | 10 | 12 | 12 | 12 | 12 |  | 50 Ohms | TOP=L2:L3=L2/L4:L6=L5/L7:BOTTOM=L7 |
| UPLINK6_R | OTHERS | BUS | 6 | 5 | 5 | 10 | 5 | 14 | 6 | 10 | 12 | 12 | 12 | 12 |  | 50 Ohms | TOP=L2:L3=L2/L4:L6=L5/L7:BOTTOM=L7 |
| UPLINK6_R | OTHERS | BUS | 7 | 5 | 5 | 10 | 5 | 14 | 6 | 10 | 12 | 12 | 12 | 12 |  | 50 Ohms | TOP=L2:L3=L2/L4:L6=L5/L7:BOTTOM=L7 |
| UPLINK6_R | OTHERS | BUS | 8 | 4.75 | 5 | 10 | 5 | 14 | 6 | 9.5 | 12 | 12 | 12 | 12 |  | 50 Ohms | TOP=L2:L3=L2/L4:L6=L5/L7:BOTTOM=L7 |
| UPLINK7 | OTHERS | BUS | 1 | 4.75 | 5 | 10 | 5 | 14 | 6 | 9.5 | 12 | 12 | 12 | 12 |  | 50 Ohms | TOP=L2:L3=L2/L4:L6=L5/L7:BOTTOM=L7 |
| UPLINK7 | OTHERS | BUS | 2 | 5 | 5 | 10 | 5 | 14 | 6 | 10 | 12 | 12 | 12 | 12 |  | 50 Ohms | TOP=L2:L3=L2/L4:L6=L5/L7:BOTTOM=L7 |
| UPLINK7 | OTHERS | BUS | 3 | 5 | 5 | 10 | 5 | 14 | 6 | 10 | 12 | 12 | 12 | 12 |  | 50 Ohms | TOP=L2:L3=L2/L4:L6=L5/L7:BOTTOM=L7 |
| UPLINK7 | OTHERS | BUS | 4 | 5 | 5 | 10 | 5 | 14 | 6 | 10 | 12 | 12 | 12 | 12 |  | 50 Ohms | TOP=L2:L3=L2/L4:L6=L5/L7:BOTTOM=L7 |
| UPLINK7 | OTHERS | BUS | 5 | 5 | 5 | 10 | 5 | 14 | 6 | 10 | 12 | 12 | 12 | 12 |  | 50 Ohms | TOP=L2:L3=L2/L4:L6=L5/L7:BOTTOM=L7 |
| UPLINK7 | OTHERS | BUS | 6 | 5 | 5 | 10 | 5 | 14 | 6 | 10 | 12 | 12 | 12 | 12 |  | 50 Ohms | TOP=L2:L3=L2/L4:L6=L5/L7:BOTTOM=L7 |
| UPLINK7 | OTHERS | BUS | 7 | 5 | 5 | 10 | 5 | 14 | 6 | 10 | 12 | 12 | 12 | 12 |  | 50 Ohms | TOP=L2:L3=L2/L4:L6=L5/L7:BOTTOM=L7 |
| UPLINK7 | OTHERS | BUS | 8 | 4.75 | 5 | 10 | 5 | 14 | 6 | 9.5 | 12 | 12 | 12 | 12 |  | 50 Ohms | TOP=L2:L3=L2/L4:L6=L5/L7:BOTTOM=L7 |
| UPLINK7_R | OTHERS | BUS | 1 | 4.75 | 5 | 10 | 5 | 14 | 6 | 9.5 | 12 | 12 | 12 | 12 |  | 50 Ohms | TOP=L2:L3=L2/L4:L6=L5/L7:BOTTOM=L7 |
| UPLINK7_R | OTHERS | BUS | 2 | 5 | 5 | 10 | 5 | 14 | 6 | 10 | 12 | 12 | 12 | 12 |  | 50 Ohms | TOP=L2:L3=L2/L4:L6=L5/L7:BOTTOM=L7 |
| UPLINK7_R | OTHERS | BUS | 3 | 5 | 5 | 10 | 5 | 14 | 6 | 10 | 12 | 12 | 12 | 12 |  | 50 Ohms | TOP=L2:L3=L2/L4:L6=L5/L7:BOTTOM=L7 |
| UPLINK7_R | OTHERS | BUS | 4 | 5 | 5 | 10 | 5 | 14 | 6 | 10 | 12 | 12 | 12 | 12 |  | 50 Ohms | TOP=L2:L3=L2/L4:L6=L5/L7:BOTTOM=L7 |
| UPLINK7_R | OTHERS | BUS | 5 | 5 | 5 | 10 | 5 | 14 | 6 | 10 | 12 | 12 | 12 | 12 |  | 50 Ohms | TOP=L2:L3=L2/L4:L6=L5/L7:BOTTOM=L7 |
| UPLINK7_R | OTHERS | BUS | 6 | 5 | 5 | 10 | 5 | 14 | 6 | 10 | 12 | 12 | 12 | 12 |  | 50 Ohms | TOP=L2:L3=L2/L4:L6=L5/L7:BOTTOM=L7 |
| UPLINK7_R | OTHERS | BUS | 7 | 5 | 5 | 10 | 5 | 14 | 6 | 10 | 12 | 12 | 12 | 12 |  | 50 Ohms | TOP=L2:L3=L2/L4:L6=L5/L7:BOTTOM=L7 |
| UPLINK7_R | OTHERS | BUS | 8 | 4.75 | 5 | 10 | 5 | 14 | 6 | 9.5 | 12 | 12 | 12 | 12 |  | 50 Ohms | TOP=L2:L3=L2/L4:L6=L5/L7:BOTTOM=L7 |
| UPLINK8 | OTHERS | BUS | 1 | 4.75 | 5 | 10 | 5 | 14 | 6 | 9.5 | 12 | 12 | 12 | 12 |  | 50 Ohms | TOP=L2:L3=L2/L4:L6=L5/L7:BOTTOM=L7 |
| UPLINK8 | OTHERS | BUS | 2 | 5 | 5 | 10 | 5 | 14 | 6 | 10 | 12 | 12 | 12 | 12 |  | 50 Ohms | TOP=L2:L3=L2/L4:L6=L5/L7:BOTTOM=L7 |
| UPLINK8 | OTHERS | BUS | 3 | 5 | 5 | 10 | 5 | 14 | 6 | 10 | 12 | 12 | 12 | 12 |  | 50 Ohms | TOP=L2:L3=L2/L4:L6=L5/L7:BOTTOM=L7 |
| UPLINK8 | OTHERS | BUS | 4 | 5 | 5 | 10 | 5 | 14 | 6 | 10 | 12 | 12 | 12 | 12 |  | 50 Ohms | TOP=L2:L3=L2/L4:L6=L5/L7:BOTTOM=L7 |
| UPLINK8 | OTHERS | BUS | 5 | 5 | 5 | 10 | 5 | 14 | 6 | 10 | 12 | 12 | 12 | 12 |  | 50 Ohms | TOP=L2:L3=L2/L4:L6=L5/L7:BOTTOM=L7 |
| UPLINK8 | OTHERS | BUS | 6 | 5 | 5 | 10 | 5 | 14 | 6 | 10 | 12 | 12 | 12 | 12 |  | 50 Ohms | TOP=L2:L3=L2/L4:L6=L5/L7:BOTTOM=L7 |
| UPLINK8 | OTHERS | BUS | 7 | 5 | 5 | 10 | 5 | 14 | 6 | 10 | 12 | 12 | 12 | 12 |  | 50 Ohms | TOP=L2:L3=L2/L4:L6=L5/L7:BOTTOM=L7 |
| UPLINK8 | OTHERS | BUS | 8 | 4.75 | 5 | 10 | 5 | 14 | 6 | 9.5 | 12 | 12 | 12 | 12 |  | 50 Ohms | TOP=L2:L3=L2/L4:L6=L5/L7:BOTTOM=L7 |
| UPLINK8_R | OTHERS | BUS | 1 | 4.75 | 5 | 10 | 5 | 14 | 6 | 9.5 | 12 | 12 | 12 | 12 |  | 50 Ohms | TOP=L2:L3=L2/L4:L6=L5/L7:BOTTOM=L7 |
| UPLINK8_R | OTHERS | BUS | 2 | 5 | 5 | 10 | 5 | 14 | 6 | 10 | 12 | 12 | 12 | 12 |  | 50 Ohms | TOP=L2:L3=L2/L4:L6=L5/L7:BOTTOM=L7 |
| UPLINK8_R | OTHERS | BUS | 3 | 5 | 5 | 10 | 5 | 14 | 6 | 10 | 12 | 12 | 12 | 12 |  | 50 Ohms | TOP=L2:L3=L2/L4:L6=L5/L7:BOTTOM=L7 |
| UPLINK8_R | OTHERS | BUS | 4 | 5 | 5 | 10 | 5 | 14 | 6 | 10 | 12 | 12 | 12 | 12 |  | 50 Ohms | TOP=L2:L3=L2/L4:L6=L5/L7:BOTTOM=L7 |
| UPLINK8_R | OTHERS | BUS | 5 | 5 | 5 | 10 | 5 | 14 | 6 | 10 | 12 | 12 | 12 | 12 |  | 50 Ohms | TOP=L2:L3=L2/L4:L6=L5/L7:BOTTOM=L7 |
| UPLINK8_R | OTHERS | BUS | 6 | 5 | 5 | 10 | 5 | 14 | 6 | 10 | 12 | 12 | 12 | 12 |  | 50 Ohms | TOP=L2:L3=L2/L4:L6=L5/L7:BOTTOM=L7 |
| UPLINK8_R | OTHERS | BUS | 7 | 5 | 5 | 10 | 5 | 14 | 6 | 10 | 12 | 12 | 12 | 12 |  | 50 Ohms | TOP=L2:L3=L2/L4:L6=L5/L7:BOTTOM=L7 |
| UPLINK8_R | OTHERS | BUS | 8 | 4.75 | 5 | 10 | 5 | 14 | 6 | 9.5 | 12 | 12 | 12 | 12 |  | 50 Ohms | TOP=L2:L3=L2/L4:L6=L5/L7:BOTTOM=L7 |
| USB_OC# | OTHERS | BUS | 1 | 4.75 | 5 | 10 | 5 | 14 | 6 | 9.5 | 12 | 12 | 12 | 12 |  | 50 Ohms | TOP=L2:L3=L2/L4:L6=L5/L7:BOTTOM=L7 |
| USB_OC# | OTHERS | BUS | 2 | 5 | 5 | 10 | 5 | 14 | 6 | 10 | 12 | 12 | 12 | 12 |  | 50 Ohms | TOP=L2:L3=L2/L4:L6=L5/L7:BOTTOM=L7 |
| USB_OC# | OTHERS | BUS | 3 | 5 | 5 | 10 | 5 | 14 | 6 | 10 | 12 | 12 | 12 | 12 |  | 50 Ohms | TOP=L2:L3=L2/L4:L6=L5/L7:BOTTOM=L7 |
| USB_OC# | OTHERS | BUS | 4 | 5 | 5 | 10 | 5 | 14 | 6 | 10 | 12 | 12 | 12 | 12 |  | 50 Ohms | TOP=L2:L3=L2/L4:L6=L5/L7:BOTTOM=L7 |
| USB_OC# | OTHERS | BUS | 5 | 5 | 5 | 10 | 5 | 14 | 6 | 10 | 12 | 12 | 12 | 12 |  | 50 Ohms | TOP=L2:L3=L2/L4:L6=L5/L7:BOTTOM=L7 |
| USB_OC# | OTHERS | BUS | 6 | 5 | 5 | 10 | 5 | 14 | 6 | 10 | 12 | 12 | 12 | 12 |  | 50 Ohms | TOP=L2:L3=L2/L4:L6=L5/L7:BOTTOM=L7 |
| USB_OC# | OTHERS | BUS | 7 | 5 | 5 | 10 | 5 | 14 | 6 | 10 | 12 | 12 | 12 | 12 |  | 50 Ohms | TOP=L2:L3=L2/L4:L6=L5/L7:BOTTOM=L7 |
| USB_OC# | OTHERS | BUS | 8 | 4.75 | 5 | 10 | 5 | 14 | 6 | 9.5 | 12 | 12 | 12 | 12 |  | 50 Ohms | TOP=L2:L3=L2/L4:L6=L5/L7:BOTTOM=L7 |
| USB5V_EN | OTHERS | BUS | 1 | 4.75 | 5 | 10 | 5 | 14 | 6 | 9.5 | 12 | 12 | 12 | 12 |  | 50 Ohms | TOP=L2:L3=L2/L4:L6=L5/L7:BOTTOM=L7 |
| USB5V_EN | OTHERS | BUS | 2 | 5 | 5 | 10 | 5 | 14 | 6 | 10 | 12 | 12 | 12 | 12 |  | 50 Ohms | TOP=L2:L3=L2/L4:L6=L5/L7:BOTTOM=L7 |
| USB5V_EN | OTHERS | BUS | 3 | 5 | 5 | 10 | 5 | 14 | 6 | 10 | 12 | 12 | 12 | 12 |  | 50 Ohms | TOP=L2:L3=L2/L4:L6=L5/L7:BOTTOM=L7 |
| USB5V_EN | OTHERS | BUS | 4 | 5 | 5 | 10 | 5 | 14 | 6 | 10 | 12 | 12 | 12 | 12 |  | 50 Ohms | TOP=L2:L3=L2/L4:L6=L5/L7:BOTTOM=L7 |
| USB5V_EN | OTHERS | BUS | 5 | 5 | 5 | 10 | 5 | 14 | 6 | 10 | 12 | 12 | 12 | 12 |  | 50 Ohms | TOP=L2:L3=L2/L4:L6=L5/L7:BOTTOM=L7 |
| USB5V_EN | OTHERS | BUS | 6 | 5 | 5 | 10 | 5 | 14 | 6 | 10 | 12 | 12 | 12 | 12 |  | 50 Ohms | TOP=L2:L3=L2/L4:L6=L5/L7:BOTTOM=L7 |
| USB5V_EN | OTHERS | BUS | 7 | 5 | 5 | 10 | 5 | 14 | 6 | 10 | 12 | 12 | 12 | 12 |  | 50 Ohms | TOP=L2:L3=L2/L4:L6=L5/L7:BOTTOM=L7 |
| USB5V_EN | OTHERS | BUS | 8 | 4.75 | 5 | 10 | 5 | 14 | 6 | 9.5 | 12 | 12 | 12 | 12 |  | 50 Ohms | TOP=L2:L3=L2/L4:L6=L5/L7:BOTTOM=L7 |
| VREF_2V2 | OTHERS | BUS | 1 | 4.75 | 5 | 10 | 5 | 14 | 6 | 9.5 | 12 | 12 | 12 | 12 |  | 50 Ohms | TOP=L2:L3=L2/L4:L6=L5/L7:BOTTOM=L7 |
| VREF_2V2 | OTHERS | BUS | 2 | 5 | 5 | 10 | 5 | 14 | 6 | 10 | 12 | 12 | 12 | 12 |  | 50 Ohms | TOP=L2:L3=L2/L4:L6=L5/L7:BOTTOM=L7 |
| VREF_2V2 | OTHERS | BUS | 3 | 5 | 5 | 10 | 5 | 14 | 6 | 10 | 12 | 12 | 12 | 12 |  | 50 Ohms | TOP=L2:L3=L2/L4:L6=L5/L7:BOTTOM=L7 |
| VREF_2V2 | OTHERS | BUS | 4 | 5 | 5 | 10 | 5 | 14 | 6 | 10 | 12 | 12 | 12 | 12 |  | 50 Ohms | TOP=L2:L3=L2/L4:L6=L5/L7:BOTTOM=L7 |
| VREF_2V2 | OTHERS | BUS | 5 | 5 | 5 | 10 | 5 | 14 | 6 | 10 | 12 | 12 | 12 | 12 |  | 50 Ohms | TOP=L2:L3=L2/L4:L6=L5/L7:BOTTOM=L7 |
| VREF_2V2 | OTHERS | BUS | 6 | 5 | 5 | 10 | 5 | 14 | 6 | 10 | 12 | 12 | 12 | 12 |  | 50 Ohms | TOP=L2:L3=L2/L4:L6=L5/L7:BOTTOM=L7 |
| VREF_2V2 | OTHERS | BUS | 7 | 5 | 5 | 10 | 5 | 14 | 6 | 10 | 12 | 12 | 12 | 12 |  | 50 Ohms | TOP=L2:L3=L2/L4:L6=L5/L7:BOTTOM=L7 |
| VREF_2V2 | OTHERS | BUS | 8 | 4.75 | 5 | 10 | 5 | 14 | 6 | 9.5 | 12 | 12 | 12 | 12 |  | 50 Ohms | TOP=L2:L3=L2/L4:L6=L5/L7:BOTTOM=L7 |
| VS1_LED | OTHERS | BUS | 1 | 4.75 | 5 | 10 | 5 | 14 | 6 | 9.5 | 12 | 12 | 12 | 12 |  | 50 Ohms | TOP=L2:L3=L2/L4:L6=L5/L7:BOTTOM=L7 |
| VS1_LED | OTHERS | BUS | 2 | 5 | 5 | 10 | 5 | 14 | 6 | 10 | 12 | 12 | 12 | 12 |  | 50 Ohms | TOP=L2:L3=L2/L4:L6=L5/L7:BOTTOM=L7 |
| VS1_LED | OTHERS | BUS | 3 | 5 | 5 | 10 | 5 | 14 | 6 | 10 | 12 | 12 | 12 | 12 |  | 50 Ohms | TOP=L2:L3=L2/L4:L6=L5/L7:BOTTOM=L7 |
| VS1_LED | OTHERS | BUS | 4 | 5 | 5 | 10 | 5 | 14 | 6 | 10 | 12 | 12 | 12 | 12 |  | 50 Ohms | TOP=L2:L3=L2/L4:L6=L5/L7:BOTTOM=L7 |
| VS1_LED | OTHERS | BUS | 5 | 5 | 5 | 10 | 5 | 14 | 6 | 10 | 12 | 12 | 12 | 12 |  | 50 Ohms | TOP=L2:L3=L2/L4:L6=L5/L7:BOTTOM=L7 |
| VS1_LED | OTHERS | BUS | 6 | 5 | 5 | 10 | 5 | 14 | 6 | 10 | 12 | 12 | 12 | 12 |  | 50 Ohms | TOP=L2:L3=L2/L4:L6=L5/L7:BOTTOM=L7 |
| VS1_LED | OTHERS | BUS | 7 | 5 | 5 | 10 | 5 | 14 | 6 | 10 | 12 | 12 | 12 | 12 |  | 50 Ohms | TOP=L2:L3=L2/L4:L6=L5/L7:BOTTOM=L7 |
| VS1_LED | OTHERS | BUS | 8 | 4.75 | 5 | 10 | 5 | 14 | 6 | 9.5 | 12 | 12 | 12 | 12 |  | 50 Ohms | TOP=L2:L3=L2/L4:L6=L5/L7:BOTTOM=L7 |
| VS1_LED_R | OTHERS | BUS | 1 | 4.75 | 5 | 10 | 5 | 14 | 6 | 9.5 | 12 | 12 | 12 | 12 |  | 50 Ohms | TOP=L2:L3=L2/L4:L6=L5/L7:BOTTOM=L7 |
| VS1_LED_R | OTHERS | BUS | 2 | 5 | 5 | 10 | 5 | 14 | 6 | 10 | 12 | 12 | 12 | 12 |  | 50 Ohms | TOP=L2:L3=L2/L4:L6=L5/L7:BOTTOM=L7 |
| VS1_LED_R | OTHERS | BUS | 3 | 5 | 5 | 10 | 5 | 14 | 6 | 10 | 12 | 12 | 12 | 12 |  | 50 Ohms | TOP=L2:L3=L2/L4:L6=L5/L7:BOTTOM=L7 |
| VS1_LED_R | OTHERS | BUS | 4 | 5 | 5 | 10 | 5 | 14 | 6 | 10 | 12 | 12 | 12 | 12 |  | 50 Ohms | TOP=L2:L3=L2/L4:L6=L5/L7:BOTTOM=L7 |
| VS1_LED_R | OTHERS | BUS | 5 | 5 | 5 | 10 | 5 | 14 | 6 | 10 | 12 | 12 | 12 | 12 |  | 50 Ohms | TOP=L2:L3=L2/L4:L6=L5/L7:BOTTOM=L7 |
| VS1_LED_R | OTHERS | BUS | 6 | 5 | 5 | 10 | 5 | 14 | 6 | 10 | 12 | 12 | 12 | 12 |  | 50 Ohms | TOP=L2:L3=L2/L4:L6=L5/L7:BOTTOM=L7 |
| VS1_LED_R | OTHERS | BUS | 7 | 5 | 5 | 10 | 5 | 14 | 6 | 10 | 12 | 12 | 12 | 12 |  | 50 Ohms | TOP=L2:L3=L2/L4:L6=L5/L7:BOTTOM=L7 |
| VS1_LED_R | OTHERS | BUS | 8 | 4.75 | 5 | 10 | 5 | 14 | 6 | 9.5 | 12 | 12 | 12 | 12 |  | 50 Ohms | TOP=L2:L3=L2/L4:L6=L5/L7:BOTTOM=L7 |
| VS2_LED | OTHERS | BUS | 1 | 4.75 | 5 | 10 | 5 | 14 | 6 | 9.5 | 12 | 12 | 12 | 12 |  | 50 Ohms | TOP=L2:L3=L2/L4:L6=L5/L7:BOTTOM=L7 |
| VS2_LED | OTHERS | BUS | 2 | 5 | 5 | 10 | 5 | 14 | 6 | 10 | 12 | 12 | 12 | 12 |  | 50 Ohms | TOP=L2:L3=L2/L4:L6=L5/L7:BOTTOM=L7 |
| VS2_LED | OTHERS | BUS | 3 | 5 | 5 | 10 | 5 | 14 | 6 | 10 | 12 | 12 | 12 | 12 |  | 50 Ohms | TOP=L2:L3=L2/L4:L6=L5/L7:BOTTOM=L7 |
| VS2_LED | OTHERS | BUS | 4 | 5 | 5 | 10 | 5 | 14 | 6 | 10 | 12 | 12 | 12 | 12 |  | 50 Ohms | TOP=L2:L3=L2/L4:L6=L5/L7:BOTTOM=L7 |
| VS2_LED | OTHERS | BUS | 5 | 5 | 5 | 10 | 5 | 14 | 6 | 10 | 12 | 12 | 12 | 12 |  | 50 Ohms | TOP=L2:L3=L2/L4:L6=L5/L7:BOTTOM=L7 |
| VS2_LED | OTHERS | BUS | 6 | 5 | 5 | 10 | 5 | 14 | 6 | 10 | 12 | 12 | 12 | 12 |  | 50 Ohms | TOP=L2:L3=L2/L4:L6=L5/L7:BOTTOM=L7 |
| VS2_LED | OTHERS | BUS | 7 | 5 | 5 | 10 | 5 | 14 | 6 | 10 | 12 | 12 | 12 | 12 |  | 50 Ohms | TOP=L2:L3=L2/L4:L6=L5/L7:BOTTOM=L7 |
| VS2_LED | OTHERS | BUS | 8 | 4.75 | 5 | 10 | 5 | 14 | 6 | 9.5 | 12 | 12 | 12 | 12 |  | 50 Ohms | TOP=L2:L3=L2/L4:L6=L5/L7:BOTTOM=L7 |
| VS2_LED_R | OTHERS | BUS | 1 | 4.75 | 5 | 10 | 5 | 14 | 6 | 9.5 | 12 | 12 | 12 | 12 |  | 50 Ohms | TOP=L2:L3=L2/L4:L6=L5/L7:BOTTOM=L7 |
| VS2_LED_R | OTHERS | BUS | 2 | 5 | 5 | 10 | 5 | 14 | 6 | 10 | 12 | 12 | 12 | 12 |  | 50 Ohms | TOP=L2:L3=L2/L4:L6=L5/L7:BOTTOM=L7 |
| VS2_LED_R | OTHERS | BUS | 3 | 5 | 5 | 10 | 5 | 14 | 6 | 10 | 12 | 12 | 12 | 12 |  | 50 Ohms | TOP=L2:L3=L2/L4:L6=L5/L7:BOTTOM=L7 |
| VS2_LED_R | OTHERS | BUS | 4 | 5 | 5 | 10 | 5 | 14 | 6 | 10 | 12 | 12 | 12 | 12 |  | 50 Ohms | TOP=L2:L3=L2/L4:L6=L5/L7:BOTTOM=L7 |
| VS2_LED_R | OTHERS | BUS | 5 | 5 | 5 | 10 | 5 | 14 | 6 | 10 | 12 | 12 | 12 | 12 |  | 50 Ohms | TOP=L2:L3=L2/L4:L6=L5/L7:BOTTOM=L7 |
| VS2_LED_R | OTHERS | BUS | 6 | 5 | 5 | 10 | 5 | 14 | 6 | 10 | 12 | 12 | 12 | 12 |  | 50 Ohms | TOP=L2:L3=L2/L4:L6=L5/L7:BOTTOM=L7 |
| VS2_LED_R | OTHERS | BUS | 7 | 5 | 5 | 10 | 5 | 14 | 6 | 10 | 12 | 12 | 12 | 12 |  | 50 Ohms | TOP=L2:L3=L2/L4:L6=L5/L7:BOTTOM=L7 |
| VS2_LED_R | OTHERS | BUS | 8 | 4.75 | 5 | 10 | 5 | 14 | 6 | 9.5 | 12 | 12 | 12 | 12 |  | 50 Ohms | TOP=L2:L3=L2/L4:L6=L5/L7:BOTTOM=L7 |
| VS3_LED | OTHERS | BUS | 1 | 4.75 | 5 | 10 | 5 | 14 | 6 | 9.5 | 12 | 12 | 12 | 12 |  | 50 Ohms | TOP=L2:L3=L2/L4:L6=L5/L7:BOTTOM=L7 |
| VS3_LED | OTHERS | BUS | 2 | 5 | 5 | 10 | 5 | 14 | 6 | 10 | 12 | 12 | 12 | 12 |  | 50 Ohms | TOP=L2:L3=L2/L4:L6=L5/L7:BOTTOM=L7 |
| VS3_LED | OTHERS | BUS | 3 | 5 | 5 | 10 | 5 | 14 | 6 | 10 | 12 | 12 | 12 | 12 |  | 50 Ohms | TOP=L2:L3=L2/L4:L6=L5/L7:BOTTOM=L7 |
| VS3_LED | OTHERS | BUS | 4 | 5 | 5 | 10 | 5 | 14 | 6 | 10 | 12 | 12 | 12 | 12 |  | 50 Ohms | TOP=L2:L3=L2/L4:L6=L5/L7:BOTTOM=L7 |
| VS3_LED | OTHERS | BUS | 5 | 5 | 5 | 10 | 5 | 14 | 6 | 10 | 12 | 12 | 12 | 12 |  | 50 Ohms | TOP=L2:L3=L2/L4:L6=L5/L7:BOTTOM=L7 |
| VS3_LED | OTHERS | BUS | 6 | 5 | 5 | 10 | 5 | 14 | 6 | 10 | 12 | 12 | 12 | 12 |  | 50 Ohms | TOP=L2:L3=L2/L4:L6=L5/L7:BOTTOM=L7 |
| VS3_LED | OTHERS | BUS | 7 | 5 | 5 | 10 | 5 | 14 | 6 | 10 | 12 | 12 | 12 | 12 |  | 50 Ohms | TOP=L2:L3=L2/L4:L6=L5/L7:BOTTOM=L7 |
| VS3_LED | OTHERS | BUS | 8 | 4.75 | 5 | 10 | 5 | 14 | 6 | 9.5 | 12 | 12 | 12 | 12 |  | 50 Ohms | TOP=L2:L3=L2/L4:L6=L5/L7:BOTTOM=L7 |
| VS3_LED_R | OTHERS | BUS | 1 | 4.75 | 5 | 10 | 5 | 14 | 6 | 9.5 | 12 | 12 | 12 | 12 |  | 50 Ohms | TOP=L2:L3=L2/L4:L6=L5/L7:BOTTOM=L7 |
| VS3_LED_R | OTHERS | BUS | 2 | 5 | 5 | 10 | 5 | 14 | 6 | 10 | 12 | 12 | 12 | 12 |  | 50 Ohms | TOP=L2:L3=L2/L4:L6=L5/L7:BOTTOM=L7 |
| VS3_LED_R | OTHERS | BUS | 3 | 5 | 5 | 10 | 5 | 14 | 6 | 10 | 12 | 12 | 12 | 12 |  | 50 Ohms | TOP=L2:L3=L2/L4:L6=L5/L7:BOTTOM=L7 |
| VS3_LED_R | OTHERS | BUS | 4 | 5 | 5 | 10 | 5 | 14 | 6 | 10 | 12 | 12 | 12 | 12 |  | 50 Ohms | TOP=L2:L3=L2/L4:L6=L5/L7:BOTTOM=L7 |
| VS3_LED_R | OTHERS | BUS | 5 | 5 | 5 | 10 | 5 | 14 | 6 | 10 | 12 | 12 | 12 | 12 |  | 50 Ohms | TOP=L2:L3=L2/L4:L6=L5/L7:BOTTOM=L7 |
| VS3_LED_R | OTHERS | BUS | 6 | 5 | 5 | 10 | 5 | 14 | 6 | 10 | 12 | 12 | 12 | 12 |  | 50 Ohms | TOP=L2:L3=L2/L4:L6=L5/L7:BOTTOM=L7 |
| VS3_LED_R | OTHERS | BUS | 7 | 5 | 5 | 10 | 5 | 14 | 6 | 10 | 12 | 12 | 12 | 12 |  | 50 Ohms | TOP=L2:L3=L2/L4:L6=L5/L7:BOTTOM=L7 |
| VS3_LED_R | OTHERS | BUS | 8 | 4.75 | 5 | 10 | 5 | 14 | 6 | 9.5 | 12 | 12 | 12 | 12 |  | 50 Ohms | TOP=L2:L3=L2/L4:L6=L5/L7:BOTTOM=L7 |
| VS4_LED | OTHERS | BUS | 1 | 4.75 | 5 | 10 | 5 | 14 | 6 | 9.5 | 12 | 12 | 12 | 12 |  | 50 Ohms | TOP=L2:L3=L2/L4:L6=L5/L7:BOTTOM=L7 |
| VS4_LED | OTHERS | BUS | 2 | 5 | 5 | 10 | 5 | 14 | 6 | 10 | 12 | 12 | 12 | 12 |  | 50 Ohms | TOP=L2:L3=L2/L4:L6=L5/L7:BOTTOM=L7 |
| VS4_LED | OTHERS | BUS | 3 | 5 | 5 | 10 | 5 | 14 | 6 | 10 | 12 | 12 | 12 | 12 |  | 50 Ohms | TOP=L2:L3=L2/L4:L6=L5/L7:BOTTOM=L7 |
| VS4_LED | OTHERS | BUS | 4 | 5 | 5 | 10 | 5 | 14 | 6 | 10 | 12 | 12 | 12 | 12 |  | 50 Ohms | TOP=L2:L3=L2/L4:L6=L5/L7:BOTTOM=L7 |
| VS4_LED | OTHERS | BUS | 5 | 5 | 5 | 10 | 5 | 14 | 6 | 10 | 12 | 12 | 12 | 12 |  | 50 Ohms | TOP=L2:L3=L2/L4:L6=L5/L7:BOTTOM=L7 |
| VS4_LED | OTHERS | BUS | 6 | 5 | 5 | 10 | 5 | 14 | 6 | 10 | 12 | 12 | 12 | 12 |  | 50 Ohms | TOP=L2:L3=L2/L4:L6=L5/L7:BOTTOM=L7 |
| VS4_LED | OTHERS | BUS | 7 | 5 | 5 | 10 | 5 | 14 | 6 | 10 | 12 | 12 | 12 | 12 |  | 50 Ohms | TOP=L2:L3=L2/L4:L6=L5/L7:BOTTOM=L7 |
| VS4_LED | OTHERS | BUS | 8 | 4.75 | 5 | 10 | 5 | 14 | 6 | 9.5 | 12 | 12 | 12 | 12 |  | 50 Ohms | TOP=L2:L3=L2/L4:L6=L5/L7:BOTTOM=L7 |
| VS4_LED_R | OTHERS | BUS | 1 | 4.75 | 5 | 10 | 5 | 14 | 6 | 9.5 | 12 | 12 | 12 | 12 |  | 50 Ohms | TOP=L2:L3=L2/L4:L6=L5/L7:BOTTOM=L7 |
| VS4_LED_R | OTHERS | BUS | 2 | 5 | 5 | 10 | 5 | 14 | 6 | 10 | 12 | 12 | 12 | 12 |  | 50 Ohms | TOP=L2:L3=L2/L4:L6=L5/L7:BOTTOM=L7 |
| VS4_LED_R | OTHERS | BUS | 3 | 5 | 5 | 10 | 5 | 14 | 6 | 10 | 12 | 12 | 12 | 12 |  | 50 Ohms | TOP=L2:L3=L2/L4:L6=L5/L7:BOTTOM=L7 |
| VS4_LED_R | OTHERS | BUS | 4 | 5 | 5 | 10 | 5 | 14 | 6 | 10 | 12 | 12 | 12 | 12 |  | 50 Ohms | TOP=L2:L3=L2/L4:L6=L5/L7:BOTTOM=L7 |
| VS4_LED_R | OTHERS | BUS | 5 | 5 | 5 | 10 | 5 | 14 | 6 | 10 | 12 | 12 | 12 | 12 |  | 50 Ohms | TOP=L2:L3=L2/L4:L6=L5/L7:BOTTOM=L7 |
| VS4_LED_R | OTHERS | BUS | 6 | 5 | 5 | 10 | 5 | 14 | 6 | 10 | 12 | 12 | 12 | 12 |  | 50 Ohms | TOP=L2:L3=L2/L4:L6=L5/L7:BOTTOM=L7 |
| VS4_LED_R | OTHERS | BUS | 7 | 5 | 5 | 10 | 5 | 14 | 6 | 10 | 12 | 12 | 12 | 12 |  | 50 Ohms | TOP=L2:L3=L2/L4:L6=L5/L7:BOTTOM=L7 |
| VS4_LED_R | OTHERS | BUS | 8 | 4.75 | 5 | 10 | 5 | 14 | 6 | 9.5 | 12 | 12 | 12 | 12 |  | 50 Ohms | TOP=L2:L3=L2/L4:L6=L5/L7:BOTTOM=L7 |
| VS5_LED | OTHERS | BUS | 1 | 4.75 | 5 | 10 | 5 | 14 | 6 | 9.5 | 12 | 12 | 12 | 12 |  | 50 Ohms | TOP=L2:L3=L2/L4:L6=L5/L7:BOTTOM=L7 |
| VS5_LED | OTHERS | BUS | 2 | 5 | 5 | 10 | 5 | 14 | 6 | 10 | 12 | 12 | 12 | 12 |  | 50 Ohms | TOP=L2:L3=L2/L4:L6=L5/L7:BOTTOM=L7 |
| VS5_LED | OTHERS | BUS | 3 | 5 | 5 | 10 | 5 | 14 | 6 | 10 | 12 | 12 | 12 | 12 |  | 50 Ohms | TOP=L2:L3=L2/L4:L6=L5/L7:BOTTOM=L7 |
| VS5_LED | OTHERS | BUS | 4 | 5 | 5 | 10 | 5 | 14 | 6 | 10 | 12 | 12 | 12 | 12 |  | 50 Ohms | TOP=L2:L3=L2/L4:L6=L5/L7:BOTTOM=L7 |
| VS5_LED | OTHERS | BUS | 5 | 5 | 5 | 10 | 5 | 14 | 6 | 10 | 12 | 12 | 12 | 12 |  | 50 Ohms | TOP=L2:L3=L2/L4:L6=L5/L7:BOTTOM=L7 |
| VS5_LED | OTHERS | BUS | 6 | 5 | 5 | 10 | 5 | 14 | 6 | 10 | 12 | 12 | 12 | 12 |  | 50 Ohms | TOP=L2:L3=L2/L4:L6=L5/L7:BOTTOM=L7 |
| VS5_LED | OTHERS | BUS | 7 | 5 | 5 | 10 | 5 | 14 | 6 | 10 | 12 | 12 | 12 | 12 |  | 50 Ohms | TOP=L2:L3=L2/L4:L6=L5/L7:BOTTOM=L7 |
| VS5_LED | OTHERS | BUS | 8 | 4.75 | 5 | 10 | 5 | 14 | 6 | 9.5 | 12 | 12 | 12 | 12 |  | 50 Ohms | TOP=L2:L3=L2/L4:L6=L5/L7:BOTTOM=L7 |
| VS5_LED_R | OTHERS | BUS | 1 | 4.75 | 5 | 10 | 5 | 14 | 6 | 9.5 | 12 | 12 | 12 | 12 |  | 50 Ohms | TOP=L2:L3=L2/L4:L6=L5/L7:BOTTOM=L7 |
| VS5_LED_R | OTHERS | BUS | 2 | 5 | 5 | 10 | 5 | 14 | 6 | 10 | 12 | 12 | 12 | 12 |  | 50 Ohms | TOP=L2:L3=L2/L4:L6=L5/L7:BOTTOM=L7 |
| VS5_LED_R | OTHERS | BUS | 3 | 5 | 5 | 10 | 5 | 14 | 6 | 10 | 12 | 12 | 12 | 12 |  | 50 Ohms | TOP=L2:L3=L2/L4:L6=L5/L7:BOTTOM=L7 |
| VS5_LED_R | OTHERS | BUS | 4 | 5 | 5 | 10 | 5 | 14 | 6 | 10 | 12 | 12 | 12 | 12 |  | 50 Ohms | TOP=L2:L3=L2/L4:L6=L5/L7:BOTTOM=L7 |
| VS5_LED_R | OTHERS | BUS | 5 | 5 | 5 | 10 | 5 | 14 | 6 | 10 | 12 | 12 | 12 | 12 |  | 50 Ohms | TOP=L2:L3=L2/L4:L6=L5/L7:BOTTOM=L7 |
| VS5_LED_R | OTHERS | BUS | 6 | 5 | 5 | 10 | 5 | 14 | 6 | 10 | 12 | 12 | 12 | 12 |  | 50 Ohms | TOP=L2:L3=L2/L4:L6=L5/L7:BOTTOM=L7 |
| VS5_LED_R | OTHERS | BUS | 7 | 5 | 5 | 10 | 5 | 14 | 6 | 10 | 12 | 12 | 12 | 12 |  | 50 Ohms | TOP=L2:L3=L2/L4:L6=L5/L7:BOTTOM=L7 |
| VS5_LED_R | OTHERS | BUS | 8 | 4.75 | 5 | 10 | 5 | 14 | 6 | 9.5 | 12 | 12 | 12 | 12 |  | 50 Ohms | TOP=L2:L3=L2/L4:L6=L5/L7:BOTTOM=L7 |
| VS6_LED | OTHERS | BUS | 1 | 4.75 | 5 | 10 | 5 | 14 | 6 | 9.5 | 12 | 12 | 12 | 12 |  | 50 Ohms | TOP=L2:L3=L2/L4:L6=L5/L7:BOTTOM=L7 |
| VS6_LED | OTHERS | BUS | 2 | 5 | 5 | 10 | 5 | 14 | 6 | 10 | 12 | 12 | 12 | 12 |  | 50 Ohms | TOP=L2:L3=L2/L4:L6=L5/L7:BOTTOM=L7 |
| VS6_LED | OTHERS | BUS | 3 | 5 | 5 | 10 | 5 | 14 | 6 | 10 | 12 | 12 | 12 | 12 |  | 50 Ohms | TOP=L2:L3=L2/L4:L6=L5/L7:BOTTOM=L7 |
| VS6_LED | OTHERS | BUS | 4 | 5 | 5 | 10 | 5 | 14 | 6 | 10 | 12 | 12 | 12 | 12 |  | 50 Ohms | TOP=L2:L3=L2/L4:L6=L5/L7:BOTTOM=L7 |
| VS6_LED | OTHERS | BUS | 5 | 5 | 5 | 10 | 5 | 14 | 6 | 10 | 12 | 12 | 12 | 12 |  | 50 Ohms | TOP=L2:L3=L2/L4:L6=L5/L7:BOTTOM=L7 |
| VS6_LED | OTHERS | BUS | 6 | 5 | 5 | 10 | 5 | 14 | 6 | 10 | 12 | 12 | 12 | 12 |  | 50 Ohms | TOP=L2:L3=L2/L4:L6=L5/L7:BOTTOM=L7 |
| VS6_LED | OTHERS | BUS | 7 | 5 | 5 | 10 | 5 | 14 | 6 | 10 | 12 | 12 | 12 | 12 |  | 50 Ohms | TOP=L2:L3=L2/L4:L6=L5/L7:BOTTOM=L7 |
| VS6_LED | OTHERS | BUS | 8 | 4.75 | 5 | 10 | 5 | 14 | 6 | 9.5 | 12 | 12 | 12 | 12 |  | 50 Ohms | TOP=L2:L3=L2/L4:L6=L5/L7:BOTTOM=L7 |
| VS6_LED_R | OTHERS | BUS | 1 | 4.75 | 5 | 10 | 5 | 14 | 6 | 9.5 | 12 | 12 | 12 | 12 |  | 50 Ohms | TOP=L2:L3=L2/L4:L6=L5/L7:BOTTOM=L7 |
| VS6_LED_R | OTHERS | BUS | 2 | 5 | 5 | 10 | 5 | 14 | 6 | 10 | 12 | 12 | 12 | 12 |  | 50 Ohms | TOP=L2:L3=L2/L4:L6=L5/L7:BOTTOM=L7 |
| VS6_LED_R | OTHERS | BUS | 3 | 5 | 5 | 10 | 5 | 14 | 6 | 10 | 12 | 12 | 12 | 12 |  | 50 Ohms | TOP=L2:L3=L2/L4:L6=L5/L7:BOTTOM=L7 |
| VS6_LED_R | OTHERS | BUS | 4 | 5 | 5 | 10 | 5 | 14 | 6 | 10 | 12 | 12 | 12 | 12 |  | 50 Ohms | TOP=L2:L3=L2/L4:L6=L5/L7:BOTTOM=L7 |
| VS6_LED_R | OTHERS | BUS | 5 | 5 | 5 | 10 | 5 | 14 | 6 | 10 | 12 | 12 | 12 | 12 |  | 50 Ohms | TOP=L2:L3=L2/L4:L6=L5/L7:BOTTOM=L7 |
| VS6_LED_R | OTHERS | BUS | 6 | 5 | 5 | 10 | 5 | 14 | 6 | 10 | 12 | 12 | 12 | 12 |  | 50 Ohms | TOP=L2:L3=L2/L4:L6=L5/L7:BOTTOM=L7 |
| VS6_LED_R | OTHERS | BUS | 7 | 5 | 5 | 10 | 5 | 14 | 6 | 10 | 12 | 12 | 12 | 12 |  | 50 Ohms | TOP=L2:L3=L2/L4:L6=L5/L7:BOTTOM=L7 |
| VS6_LED_R | OTHERS | BUS | 8 | 4.75 | 5 | 10 | 5 | 14 | 6 | 9.5 | 12 | 12 | 12 | 12 |  | 50 Ohms | TOP=L2:L3=L2/L4:L6=L5/L7:BOTTOM=L7 |
| VSS_571 | OTHERS | BUS | 1 | 4.75 | 5 | 10 | 5 | 14 | 6 | 9.5 | 12 | 12 | 12 | 12 |  | 50 Ohms | TOP=L2:L3=L2/L4:L6=L5/L7:BOTTOM=L7 |
| VSS_571 | OTHERS | BUS | 2 | 5 | 5 | 10 | 5 | 14 | 6 | 10 | 12 | 12 | 12 | 12 |  | 50 Ohms | TOP=L2:L3=L2/L4:L6=L5/L7:BOTTOM=L7 |
| VSS_571 | OTHERS | BUS | 3 | 5 | 5 | 10 | 5 | 14 | 6 | 10 | 12 | 12 | 12 | 12 |  | 50 Ohms | TOP=L2:L3=L2/L4:L6=L5/L7:BOTTOM=L7 |
| VSS_571 | OTHERS | BUS | 4 | 5 | 5 | 10 | 5 | 14 | 6 | 10 | 12 | 12 | 12 | 12 |  | 50 Ohms | TOP=L2:L3=L2/L4:L6=L5/L7:BOTTOM=L7 |
| VSS_571 | OTHERS | BUS | 5 | 5 | 5 | 10 | 5 | 14 | 6 | 10 | 12 | 12 | 12 | 12 |  | 50 Ohms | TOP=L2:L3=L2/L4:L6=L5/L7:BOTTOM=L7 |
| VSS_571 | OTHERS | BUS | 6 | 5 | 5 | 10 | 5 | 14 | 6 | 10 | 12 | 12 | 12 | 12 |  | 50 Ohms | TOP=L2:L3=L2/L4:L6=L5/L7:BOTTOM=L7 |
| VSS_571 | OTHERS | BUS | 7 | 5 | 5 | 10 | 5 | 14 | 6 | 10 | 12 | 12 | 12 | 12 |  | 50 Ohms | TOP=L2:L3=L2/L4:L6=L5/L7:BOTTOM=L7 |
| VSS_571 | OTHERS | BUS | 8 | 4.75 | 5 | 10 | 5 | 14 | 6 | 9.5 | 12 | 12 | 12 | 12 |  | 50 Ohms | TOP=L2:L3=L2/L4:L6=L5/L7:BOTTOM=L7 |
| VSS_572 | OTHERS | BUS | 1 | 4.75 | 5 | 10 | 5 | 14 | 6 | 9.5 | 12 | 12 | 12 | 12 |  | 50 Ohms | TOP=L2:L3=L2/L4:L6=L5/L7:BOTTOM=L7 |
| VSS_572 | OTHERS | BUS | 2 | 5 | 5 | 10 | 5 | 14 | 6 | 10 | 12 | 12 | 12 | 12 |  | 50 Ohms | TOP=L2:L3=L2/L4:L6=L5/L7:BOTTOM=L7 |
| VSS_572 | OTHERS | BUS | 3 | 5 | 5 | 10 | 5 | 14 | 6 | 10 | 12 | 12 | 12 | 12 |  | 50 Ohms | TOP=L2:L3=L2/L4:L6=L5/L7:BOTTOM=L7 |
| VSS_572 | OTHERS | BUS | 4 | 5 | 5 | 10 | 5 | 14 | 6 | 10 | 12 | 12 | 12 | 12 |  | 50 Ohms | TOP=L2:L3=L2/L4:L6=L5/L7:BOTTOM=L7 |
| VSS_572 | OTHERS | BUS | 5 | 5 | 5 | 10 | 5 | 14 | 6 | 10 | 12 | 12 | 12 | 12 |  | 50 Ohms | TOP=L2:L3=L2/L4:L6=L5/L7:BOTTOM=L7 |
| VSS_572 | OTHERS | BUS | 6 | 5 | 5 | 10 | 5 | 14 | 6 | 10 | 12 | 12 | 12 | 12 |  | 50 Ohms | TOP=L2:L3=L2/L4:L6=L5/L7:BOTTOM=L7 |
| VSS_572 | OTHERS | BUS | 7 | 5 | 5 | 10 | 5 | 14 | 6 | 10 | 12 | 12 | 12 | 12 |  | 50 Ohms | TOP=L2:L3=L2/L4:L6=L5/L7:BOTTOM=L7 |
| VSS_572 | OTHERS | BUS | 8 | 4.75 | 5 | 10 | 5 | 14 | 6 | 9.5 | 12 | 12 | 12 | 12 |  | 50 Ohms | TOP=L2:L3=L2/L4:L6=L5/L7:BOTTOM=L7 |
| VSS_573 | OTHERS | BUS | 1 | 4.75 | 5 | 10 | 5 | 14 | 6 | 9.5 | 12 | 12 | 12 | 12 |  | 50 Ohms | TOP=L2:L3=L2/L4:L6=L5/L7:BOTTOM=L7 |
| VSS_573 | OTHERS | BUS | 2 | 5 | 5 | 10 | 5 | 14 | 6 | 10 | 12 | 12 | 12 | 12 |  | 50 Ohms | TOP=L2:L3=L2/L4:L6=L5/L7:BOTTOM=L7 |
| VSS_573 | OTHERS | BUS | 3 | 5 | 5 | 10 | 5 | 14 | 6 | 10 | 12 | 12 | 12 | 12 |  | 50 Ohms | TOP=L2:L3=L2/L4:L6=L5/L7:BOTTOM=L7 |
| VSS_573 | OTHERS | BUS | 4 | 5 | 5 | 10 | 5 | 14 | 6 | 10 | 12 | 12 | 12 | 12 |  | 50 Ohms | TOP=L2:L3=L2/L4:L6=L5/L7:BOTTOM=L7 |
| VSS_573 | OTHERS | BUS | 5 | 5 | 5 | 10 | 5 | 14 | 6 | 10 | 12 | 12 | 12 | 12 |  | 50 Ohms | TOP=L2:L3=L2/L4:L6=L5/L7:BOTTOM=L7 |
| VSS_573 | OTHERS | BUS | 6 | 5 | 5 | 10 | 5 | 14 | 6 | 10 | 12 | 12 | 12 | 12 |  | 50 Ohms | TOP=L2:L3=L2/L4:L6=L5/L7:BOTTOM=L7 |
| VSS_573 | OTHERS | BUS | 7 | 5 | 5 | 10 | 5 | 14 | 6 | 10 | 12 | 12 | 12 | 12 |  | 50 Ohms | TOP=L2:L3=L2/L4:L6=L5/L7:BOTTOM=L7 |
| VSS_573 | OTHERS | BUS | 8 | 4.75 | 5 | 10 | 5 | 14 | 6 | 9.5 | 12 | 12 | 12 | 12 |  | 50 Ohms | TOP=L2:L3=L2/L4:L6=L5/L7:BOTTOM=L7 |
| WP_DISABLE | OTHERS | BUS | 1 | 4.75 | 5 | 10 | 5 | 14 | 6 | 9.5 | 12 | 12 | 12 | 12 |  | 50 Ohms | TOP=L2:L3=L2/L4:L6=L5/L7:BOTTOM=L7 |
| WP_DISABLE | OTHERS | BUS | 2 | 5 | 5 | 10 | 5 | 14 | 6 | 10 | 12 | 12 | 12 | 12 |  | 50 Ohms | TOP=L2:L3=L2/L4:L6=L5/L7:BOTTOM=L7 |
| WP_DISABLE | OTHERS | BUS | 3 | 5 | 5 | 10 | 5 | 14 | 6 | 10 | 12 | 12 | 12 | 12 |  | 50 Ohms | TOP=L2:L3=L2/L4:L6=L5/L7:BOTTOM=L7 |
| WP_DISABLE | OTHERS | BUS | 4 | 5 | 5 | 10 | 5 | 14 | 6 | 10 | 12 | 12 | 12 | 12 |  | 50 Ohms | TOP=L2:L3=L2/L4:L6=L5/L7:BOTTOM=L7 |
| WP_DISABLE | OTHERS | BUS | 5 | 5 | 5 | 10 | 5 | 14 | 6 | 10 | 12 | 12 | 12 | 12 |  | 50 Ohms | TOP=L2:L3=L2/L4:L6=L5/L7:BOTTOM=L7 |
| WP_DISABLE | OTHERS | BUS | 6 | 5 | 5 | 10 | 5 | 14 | 6 | 10 | 12 | 12 | 12 | 12 |  | 50 Ohms | TOP=L2:L3=L2/L4:L6=L5/L7:BOTTOM=L7 |
| WP_DISABLE | OTHERS | BUS | 7 | 5 | 5 | 10 | 5 | 14 | 6 | 10 | 12 | 12 | 12 | 12 |  | 50 Ohms | TOP=L2:L3=L2/L4:L6=L5/L7:BOTTOM=L7 |
| WP_DISABLE | OTHERS | BUS | 8 | 4.75 | 5 | 10 | 5 | 14 | 6 | 9.5 | 12 | 12 | 12 | 12 |  | 50 Ohms | TOP=L2:L3=L2/L4:L6=L5/L7:BOTTOM=L7 |
| WP_ENABLE | OTHERS | BUS | 1 | 4.75 | 5 | 10 | 5 | 14 | 6 | 9.5 | 12 | 12 | 12 | 12 |  | 50 Ohms | TOP=L2:L3=L2/L4:L6=L5/L7:BOTTOM=L7 |
| WP_ENABLE | OTHERS | BUS | 2 | 5 | 5 | 10 | 5 | 14 | 6 | 10 | 12 | 12 | 12 | 12 |  | 50 Ohms | TOP=L2:L3=L2/L4:L6=L5/L7:BOTTOM=L7 |
| WP_ENABLE | OTHERS | BUS | 3 | 5 | 5 | 10 | 5 | 14 | 6 | 10 | 12 | 12 | 12 | 12 |  | 50 Ohms | TOP=L2:L3=L2/L4:L6=L5/L7:BOTTOM=L7 |
| WP_ENABLE | OTHERS | BUS | 4 | 5 | 5 | 10 | 5 | 14 | 6 | 10 | 12 | 12 | 12 | 12 |  | 50 Ohms | TOP=L2:L3=L2/L4:L6=L5/L7:BOTTOM=L7 |
| WP_ENABLE | OTHERS | BUS | 5 | 5 | 5 | 10 | 5 | 14 | 6 | 10 | 12 | 12 | 12 | 12 |  | 50 Ohms | TOP=L2:L3=L2/L4:L6=L5/L7:BOTTOM=L7 |
| WP_ENABLE | OTHERS | BUS | 6 | 5 | 5 | 10 | 5 | 14 | 6 | 10 | 12 | 12 | 12 | 12 |  | 50 Ohms | TOP=L2:L3=L2/L4:L6=L5/L7:BOTTOM=L7 |
| WP_ENABLE | OTHERS | BUS | 7 | 5 | 5 | 10 | 5 | 14 | 6 | 10 | 12 | 12 | 12 | 12 |  | 50 Ohms | TOP=L2:L3=L2/L4:L6=L5/L7:BOTTOM=L7 |
| WP_ENABLE | OTHERS | BUS | 8 | 4.75 | 5 | 10 | 5 | 14 | 6 | 9.5 | 12 | 12 | 12 | 12 |  | 50 Ohms | TOP=L2:L3=L2/L4:L6=L5/L7:BOTTOM=L7 |
| MB0_P12V_MAIN_R | P12V | BUS | 1 | 400 | 5 | 10 | 5 | 14 | 6 | 6 | 12 | 12 | 12 | 12 |  |  |  |
| P12V | P12V | BUS | 1 | 400 | 5 | 10 | 5 | 14 | 6 | 6 | 12 | 12 | 12 | 12 |  |  |  |
| P12V_PCIE | P12V | BUS | 1 | 400 | 5 | 10 | 5 | 14 | 6 | 6 | 12 | 12 | 12 | 12 |  |  |  |
| P0V9_E_MODE | POWER | BUS | 1 | 10 | 5 | 10 | 5 | 14 | 6 | 6 | 12 | 12 | 12 | 12 |  |  |  |
| P0V9_E_RF | POWER | BUS | 1 | 10 | 5 | 10 | 5 | 14 | 6 | 6 | 12 | 12 | 12 | 12 |  |  |  |
| P0V9_E_SNB | POWER | BUS | 1 | 10 | 5 | 10 | 5 | 14 | 6 | 6 | 12 | 12 | 12 | 12 |  |  |  |
| P0V9_E_SW_R | POWER | BUS | 1 | 10 | 5 | 10 | 5 | 14 | 6 | 6 | 12 | 12 | 12 | 12 |  |  |  |
| P0V9_E_TRIP | POWER | BUS | 1 | 10 | 5 | 10 | 5 | 14 | 6 | 6 | 12 | 12 | 12 | 12 |  |  |  |
| P0V9_E_VBST | POWER | BUS | 1 | 10 | 5 | 10 | 5 | 14 | 6 | 6 | 12 | 12 | 12 | 12 |  |  |  |
| P0V9_E_VBST_RC | POWER | BUS | 1 | 10 | 5 | 10 | 5 | 14 | 6 | 6 | 12 | 12 | 12 | 12 |  |  |  |
| P0V9_E_VDD | POWER | BUS | 1 | 10 | 5 | 10 | 5 | 14 | 6 | 6 | 12 | 12 | 12 | 12 |  |  |  |
| P0V9_E_VFB | POWER | BUS | 1 | 10 | 5 | 10 | 5 | 14 | 6 | 6 | 12 | 12 | 12 | 12 |  |  |  |
| P0V9_E_VFB_R | POWER | BUS | 1 | 10 | 5 | 10 | 5 | 14 | 6 | 6 | 12 | 12 | 12 | 12 |  |  |  |
| P0V9_E_VIN | POWER | BUS | 1 | 10 | 5 | 10 | 5 | 14 | 6 | 6 | 12 | 12 | 12 | 12 |  |  |  |
| P0V9_E_VREG | POWER | BUS | 1 | 10 | 5 | 10 | 5 | 14 | 6 | 6 | 12 | 12 | 12 | 12 |  |  |  |
| P0V9_LX | POWER | BUS | 1 | 10 | 5 | 10 | 5 | 14 | 6 | 6 | 12 | 12 | 12 | 12 |  |  |  |
| P0V9_MODE | POWER | BUS | 1 | 10 | 5 | 10 | 5 | 14 | 6 | 6 | 12 | 12 | 12 | 12 |  |  |  |
| P0V9_RF | POWER | BUS | 1 | 10 | 5 | 10 | 5 | 14 | 6 | 6 | 12 | 12 | 12 | 12 |  |  |  |
| P0V9_SNB | POWER | BUS | 1 | 10 | 5 | 10 | 5 | 14 | 6 | 6 | 12 | 12 | 12 | 12 |  |  |  |
| P0V9_SW_R | POWER | BUS | 1 | 10 | 5 | 10 | 5 | 14 | 6 | 6 | 12 | 12 | 12 | 12 |  |  |  |
| P0V9_TRIP | POWER | BUS | 1 | 10 | 5 | 10 | 5 | 14 | 6 | 6 | 12 | 12 | 12 | 12 |  |  |  |
| P0V9_VBST | POWER | BUS | 1 | 10 | 5 | 10 | 5 | 14 | 6 | 6 | 12 | 12 | 12 | 12 |  |  |  |
| P0V9_VBST_RC | POWER | BUS | 1 | 10 | 5 | 10 | 5 | 14 | 6 | 6 | 12 | 12 | 12 | 12 |  |  |  |
| P0V9_VDD | POWER | BUS | 1 | 10 | 5 | 10 | 5 | 14 | 6 | 6 | 12 | 12 | 12 | 12 |  |  |  |
| P0V9_VFB | POWER | BUS | 1 | 10 | 5 | 10 | 5 | 14 | 6 | 6 | 12 | 12 | 12 | 12 |  |  |  |
| P0V9_VFB_R | POWER | BUS | 1 | 10 | 5 | 10 | 5 | 14 | 6 | 6 | 12 | 12 | 12 | 12 |  |  |  |
| P0V9_VIN | POWER | BUS | 1 | 10 | 5 | 10 | 5 | 14 | 6 | 6 | 12 | 12 | 12 | 12 |  |  |  |
| P0V9_VREG | POWER | BUS | 1 | 10 | 5 | 10 | 5 | 14 | 6 | 6 | 12 | 12 | 12 | 12 |  |  |  |
| P1V8_CLKGEN | POWER | BUS | 1 | 10 | 5 | 10 | 5 | 14 | 6 | 6 | 12 | 12 | 12 | 12 |  |  |  |
| P1V8_CLKGEN_A | POWER | BUS | 1 | 10 | 5 | 10 | 5 | 14 | 6 | 6 | 12 | 12 | 12 | 12 |  |  |  |
| P3V3_STBY_LL | POWER | BUS | 1 | 10 | 5 | 10 | 5 | 14 | 6 | 6 | 12 | 12 | 12 | 12 |  |  |  |
| P3V3_STBY_LL_R | POWER | BUS | 1 | 10 | 5 | 10 | 5 | 14 | 6 | 6 | 12 | 12 | 12 | 12 |  |  |  |
| P3V3_STBY_MODE | POWER | BUS | 1 | 10 | 5 | 10 | 5 | 14 | 6 | 6 | 12 | 12 | 12 | 12 |  |  |  |
| P3V3_STBY_RF | POWER | BUS | 1 | 10 | 5 | 10 | 5 | 14 | 6 | 6 | 12 | 12 | 12 | 12 |  |  |  |
| P3V3_STBY_ROVP | POWER | BUS | 1 | 10 | 5 | 10 | 5 | 14 | 6 | 6 | 12 | 12 | 12 | 12 |  |  |  |
| P3V3_STBY_SNB | POWER | BUS | 1 | 10 | 5 | 10 | 5 | 14 | 6 | 6 | 12 | 12 | 12 | 12 |  |  |  |
| P3V3_STBY_TRIP | POWER | BUS | 1 | 10 | 5 | 10 | 5 | 14 | 6 | 6 | 12 | 12 | 12 | 12 |  |  |  |
| P3V3_STBY_VBST | POWER | BUS | 1 | 10 | 5 | 10 | 5 | 14 | 6 | 6 | 12 | 12 | 12 | 12 |  |  |  |
| P3V3_STBY_VBST_RC | POWER | BUS | 1 | 10 | 5 | 10 | 5 | 14 | 6 | 6 | 12 | 12 | 12 | 12 |  |  |  |
| P3V3_STBY_VFB | POWER | BUS | 1 | 10 | 5 | 10 | 5 | 14 | 6 | 6 | 12 | 12 | 12 | 12 |  |  |  |
| P3V3_STBY_VFB_R | POWER | BUS | 1 | 10 | 5 | 10 | 5 | 14 | 6 | 6 | 12 | 12 | 12 | 12 |  |  |  |
| P3V3_STBY_VIN | POWER | BUS | 1 | 10 | 5 | 10 | 5 | 14 | 6 | 6 | 12 | 12 | 12 | 12 |  |  |  |
| P3V3_STBY_VREG | POWER | BUS | 1 | 10 | 5 | 10 | 5 | 14 | 6 | 6 | 12 | 12 | 12 | 12 |  |  |  |
| P5V_STBY_BS | POWER | BUS | 1 | 10 | 5 | 10 | 5 | 14 | 6 | 6 | 12 | 12 | 12 | 12 |  |  |  |
| P5V_STBY_BS_RC | POWER | BUS | 1 | 10 | 5 | 10 | 5 | 14 | 6 | 6 | 12 | 12 | 12 | 12 |  |  |  |
| P5V_STBY_FB | POWER | BUS | 1 | 10 | 5 | 10 | 5 | 14 | 6 | 6 | 12 | 12 | 12 | 12 |  |  |  |
| VR_P1V26_STBY_BIAS | POWER | BUS | 1 | 10 | 5 | 10 | 5 | 14 | 6 | 6 | 12 | 12 | 12 | 12 |  |  |  |
| VR_P1V26_STBY_EN_R | POWER | BUS | 1 | 10 | 5 | 10 | 5 | 14 | 6 | 6 | 12 | 12 | 12 | 12 |  |  |  |
| VR_P1V26_STBY_FB | POWER | BUS | 1 | 10 | 5 | 10 | 5 | 14 | 6 | 6 | 12 | 12 | 12 | 12 |  |  |  |
| VR_P1V26_STBY_IN | POWER | BUS | 1 | 10 | 5 | 10 | 5 | 14 | 6 | 6 | 12 | 12 | 12 | 12 |  |  |  |
| VR_P1V26_STBY_SS_C | POWER | BUS | 1 | 10 | 5 | 10 | 5 | 14 | 6 | 6 | 12 | 12 | 12 | 12 |  |  |  |
| VR_P1V538_STBY_BIAS | POWER | BUS | 1 | 10 | 5 | 10 | 5 | 14 | 6 | 6 | 12 | 12 | 12 | 12 |  |  |  |
| VR_P1V538_STBY_EN_R | POWER | BUS | 1 | 10 | 5 | 10 | 5 | 14 | 6 | 6 | 12 | 12 | 12 | 12 |  |  |  |
| VR_P1V538_STBY_FB | POWER | BUS | 1 | 10 | 5 | 10 | 5 | 14 | 6 | 6 | 12 | 12 | 12 | 12 |  |  |  |
| VR_P1V538_STBY_IN | POWER | BUS | 1 | 10 | 5 | 10 | 5 | 14 | 6 | 6 | 12 | 12 | 12 | 12 |  |  |  |
| VR_P1V538_STBY_SS_C | POWER | BUS | 1 | 10 | 5 | 10 | 5 | 14 | 6 | 6 | 12 | 12 | 12 | 12 |  |  |  |
| VR_P1V8_STBY_BIAS | POWER | BUS | 1 | 10 | 5 | 10 | 5 | 14 | 6 | 6 | 12 | 12 | 12 | 12 |  |  |  |
| VR_P1V8_STBY_EN_R | POWER | BUS | 1 | 10 | 5 | 10 | 5 | 14 | 6 | 6 | 12 | 12 | 12 | 12 |  |  |  |
| VR_P1V8_STBY_FB | POWER | BUS | 1 | 10 | 5 | 10 | 5 | 14 | 6 | 6 | 12 | 12 | 12 | 12 |  |  |  |
| VR_P1V8_STBY_IN | POWER | BUS | 1 | 10 | 5 | 10 | 5 | 14 | 6 | 6 | 12 | 12 | 12 | 12 |  |  |  |
| VR_P1V8_STBY_SS_C | POWER | BUS | 1 | 10 | 5 | 10 | 5 | 14 | 6 | 6 | 12 | 12 | 12 | 12 |  |  |  |
| DUT_AVD_PCIE | POWER-12A | BUS | 1 | 550 | 5 | 10 | 5 | 14 | 6 | 6 | 12 | 12 | 12 | 12 |  |  |  |
| DUT_AVD_PCIE_Q | POWER-12A | BUS | 1 | 550 | 5 | 10 | 5 | 14 | 6 | 6 | 12 | 12 | 12 | 12 |  |  |  |
| I210_CBOT | POWER-12MIL | BUS | 1 | 12 | 5 | 10 | 5 | 14 | 6 | 6 | 12 | 12 | 12 | 12 |  |  |  |
| I210_CTOP | POWER-12MIL | BUS | 1 | 12 | 5 | 10 | 5 | 14 | 6 | 6 | 12 | 12 | 12 | 12 |  |  |  |
| DUT_VDDO | POWER-14A | BUS | 1 | 600 | 5 | 10 | 5 | 14 | 6 | 6 | 12 | 12 | 12 | 12 |  |  |  |
| DUT_VDDO_REF | POWER-14A | BUS | 1 | 600 | 5 | 10 | 5 | 14 | 6 | 6 | 12 | 12 | 12 | 12 |  |  |  |
| P0V9 | POWER-16A | BUS | 1 | 720 | 5 | 10 | 5 | 14 | 6 | 6 | 12 | 12 | 12 | 12 |  |  |  |
| P0V9_E_LX | POWER-16A | BUS | 1 | 720 | 5 | 10 | 5 | 14 | 6 | 6 | 12 | 12 | 12 | 12 |  |  |  |
| P3V3_GPIO | POWER-20MIL | BUS | 1 | 20 | 5 | 10 | 5 | 14 | 6 | 6 | 12 | 12 | 12 | 12 |  |  |  |
| Q43_C | POWER-20MIL | BUS | 1 | 20 | 5 | 10 | 5 | 14 | 6 | 6 | 12 | 12 | 12 | 12 |  |  |  |
| Q46_D | POWER-20MIL | BUS | 1 | 20 | 5 | 10 | 5 | 14 | 6 | 6 | 12 | 12 | 12 | 12 |  |  |  |
| DUT_VDD | POWER-26A | BUS | 1 | 1200 | 5 | 10 | 5 | 14 | 6 | 6 | 12 | 12 | 12 | 12 |  |  |  |
| P0V9_E | POWER-26A | BUS | 1 | 1200 | 5 | 10 | 5 | 14 | 6 | 6 | 12 | 12 | 12 | 12 |  |  |  |
| DUT_AVD_TX | POWER-5A | BUS | 1 | 250 | 5 | 10 | 5 | 14 | 6 | 6 | 12 | 12 | 12 | 12 |  |  |  |
| ADCAV33 | POWER-BMC | BUS | 1 | 40 | 5 | 10 | 5 | 14 | 6 | 6 | 12 | 12 | 12 | 12 |  |  |  |
| V1PLLAV12 | POWER-BMC | BUS | 1 | 40 | 5 | 10 | 5 | 14 | 6 | 6 | 12 | 12 | 12 | 12 |  |  |  |
| RMII_BMC_PHY_TXD0 | RMII | BUS | 1 | 4.75 | 5 | 10 | 5 | 14 | 6 | 10 | 12 | 12 | 12 | 12 |  |  |  |
| RMII_BMC_PHY_TXD0 | RMII | BUS | 2 | 5 | 5 | 10 | 5 | 14 | 6 | 10 | 12 | 12 | 12 | 12 |  |  |  |
| RMII_BMC_PHY_TXD0 | RMII | BUS | 3 | 5 | 5 | 10 | 5 | 14 | 6 | 10 | 12 | 12 | 12 | 12 |  |  |  |
| RMII_BMC_PHY_TXD0 | RMII | BUS | 4 | 5 | 5 | 10 | 5 | 14 | 6 | 10 | 12 | 12 | 12 | 12 |  |  |  |
| RMII_BMC_PHY_TXD0 | RMII | BUS | 5 | 5 | 5 | 10 | 5 | 14 | 6 | 10 | 12 | 12 | 12 | 12 |  |  |  |
| RMII_BMC_PHY_TXD0 | RMII | BUS | 6 | 5 | 5 | 10 | 5 | 14 | 6 | 10 | 12 | 12 | 12 | 12 |  |  |  |
| RMII_BMC_PHY_TXD0 | RMII | BUS | 7 | 5 | 5 | 10 | 5 | 14 | 6 | 10 | 12 | 12 | 12 | 12 |  |  |  |
| RMII_BMC_PHY_TXD0 | RMII | BUS | 8 | 4.75 | 5 | 10 | 5 | 14 | 6 | 10 | 12 | 12 | 12 | 12 |  |  |  |
| RMII_BMC_PHY_TXD1 | RMII | BUS | 1 | 4.75 | 5 | 10 | 5 | 14 | 6 | 10 | 12 | 12 | 12 | 12 |  |  |  |
| RMII_BMC_PHY_TXD1 | RMII | BUS | 2 | 5 | 5 | 10 | 5 | 14 | 6 | 10 | 12 | 12 | 12 | 12 |  |  |  |
| RMII_BMC_PHY_TXD1 | RMII | BUS | 3 | 5 | 5 | 10 | 5 | 14 | 6 | 10 | 12 | 12 | 12 | 12 |  |  |  |
| RMII_BMC_PHY_TXD1 | RMII | BUS | 4 | 5 | 5 | 10 | 5 | 14 | 6 | 10 | 12 | 12 | 12 | 12 |  |  |  |
| RMII_BMC_PHY_TXD1 | RMII | BUS | 5 | 5 | 5 | 10 | 5 | 14 | 6 | 10 | 12 | 12 | 12 | 12 |  |  |  |
| RMII_BMC_PHY_TXD1 | RMII | BUS | 6 | 5 | 5 | 10 | 5 | 14 | 6 | 10 | 12 | 12 | 12 | 12 |  |  |  |
| RMII_BMC_PHY_TXD1 | RMII | BUS | 7 | 5 | 5 | 10 | 5 | 14 | 6 | 10 | 12 | 12 | 12 | 12 |  |  |  |
| RMII_BMC_PHY_TXD1 | RMII | BUS | 8 | 4.75 | 5 | 10 | 5 | 14 | 6 | 10 | 12 | 12 | 12 | 12 |  |  |  |
| RMII_PHY_BMC_RXD0 | RMII | BUS | 1 | 4.75 | 5 | 10 | 5 | 14 | 6 | 10 | 12 | 12 | 12 | 12 |  |  |  |
| RMII_PHY_BMC_RXD0 | RMII | BUS | 2 | 5 | 5 | 10 | 5 | 14 | 6 | 10 | 12 | 12 | 12 | 12 |  |  |  |
| RMII_PHY_BMC_RXD0 | RMII | BUS | 3 | 5 | 5 | 10 | 5 | 14 | 6 | 10 | 12 | 12 | 12 | 12 |  |  |  |
| RMII_PHY_BMC_RXD0 | RMII | BUS | 4 | 5 | 5 | 10 | 5 | 14 | 6 | 10 | 12 | 12 | 12 | 12 |  |  |  |
| RMII_PHY_BMC_RXD0 | RMII | BUS | 5 | 5 | 5 | 10 | 5 | 14 | 6 | 10 | 12 | 12 | 12 | 12 |  |  |  |
| RMII_PHY_BMC_RXD0 | RMII | BUS | 6 | 5 | 5 | 10 | 5 | 14 | 6 | 10 | 12 | 12 | 12 | 12 |  |  |  |
| RMII_PHY_BMC_RXD0 | RMII | BUS | 7 | 5 | 5 | 10 | 5 | 14 | 6 | 10 | 12 | 12 | 12 | 12 |  |  |  |
| RMII_PHY_BMC_RXD0 | RMII | BUS | 8 | 4.75 | 5 | 10 | 5 | 14 | 6 | 10 | 12 | 12 | 12 | 12 |  |  |  |
| RMII_PHY_BMC_RXD0_R | RMII | BUS | 1 | 4.75 | 5 | 10 | 5 | 14 | 6 | 10 | 12 | 12 | 12 | 12 |  |  |  |
| RMII_PHY_BMC_RXD0_R | RMII | BUS | 2 | 5 | 5 | 10 | 5 | 14 | 6 | 10 | 12 | 12 | 12 | 12 |  |  |  |
| RMII_PHY_BMC_RXD0_R | RMII | BUS | 3 | 5 | 5 | 10 | 5 | 14 | 6 | 10 | 12 | 12 | 12 | 12 |  |  |  |
| RMII_PHY_BMC_RXD0_R | RMII | BUS | 4 | 5 | 5 | 10 | 5 | 14 | 6 | 10 | 12 | 12 | 12 | 12 |  |  |  |
| RMII_PHY_BMC_RXD0_R | RMII | BUS | 5 | 5 | 5 | 10 | 5 | 14 | 6 | 10 | 12 | 12 | 12 | 12 |  |  |  |
| RMII_PHY_BMC_RXD0_R | RMII | BUS | 6 | 5 | 5 | 10 | 5 | 14 | 6 | 10 | 12 | 12 | 12 | 12 |  |  |  |
| RMII_PHY_BMC_RXD0_R | RMII | BUS | 7 | 5 | 5 | 10 | 5 | 14 | 6 | 10 | 12 | 12 | 12 | 12 |  |  |  |
| RMII_PHY_BMC_RXD0_R | RMII | BUS | 8 | 4.75 | 5 | 10 | 5 | 14 | 6 | 10 | 12 | 12 | 12 | 12 |  |  |  |
| RMII_PHY_BMC_RXD1 | RMII | BUS | 1 | 4.75 | 5 | 10 | 5 | 14 | 6 | 10 | 12 | 12 | 12 | 12 |  |  |  |
| RMII_PHY_BMC_RXD1 | RMII | BUS | 2 | 5 | 5 | 10 | 5 | 14 | 6 | 10 | 12 | 12 | 12 | 12 |  |  |  |
| RMII_PHY_BMC_RXD1 | RMII | BUS | 3 | 5 | 5 | 10 | 5 | 14 | 6 | 10 | 12 | 12 | 12 | 12 |  |  |  |
| RMII_PHY_BMC_RXD1 | RMII | BUS | 4 | 5 | 5 | 10 | 5 | 14 | 6 | 10 | 12 | 12 | 12 | 12 |  |  |  |
| RMII_PHY_BMC_RXD1 | RMII | BUS | 5 | 5 | 5 | 10 | 5 | 14 | 6 | 10 | 12 | 12 | 12 | 12 |  |  |  |
| RMII_PHY_BMC_RXD1 | RMII | BUS | 6 | 5 | 5 | 10 | 5 | 14 | 6 | 10 | 12 | 12 | 12 | 12 |  |  |  |
| RMII_PHY_BMC_RXD1 | RMII | BUS | 7 | 5 | 5 | 10 | 5 | 14 | 6 | 10 | 12 | 12 | 12 | 12 |  |  |  |
| RMII_PHY_BMC_RXD1 | RMII | BUS | 8 | 4.75 | 5 | 10 | 5 | 14 | 6 | 10 | 12 | 12 | 12 | 12 |  |  |  |
| RMII_PHY_BMC_RXD1_R | RMII | BUS | 1 | 4.75 | 5 | 10 | 5 | 14 | 6 | 10 | 12 | 12 | 12 | 12 |  |  |  |
| RMII_PHY_BMC_RXD1_R | RMII | BUS | 2 | 5 | 5 | 10 | 5 | 14 | 6 | 10 | 12 | 12 | 12 | 12 |  |  |  |
| RMII_PHY_BMC_RXD1_R | RMII | BUS | 3 | 5 | 5 | 10 | 5 | 14 | 6 | 10 | 12 | 12 | 12 | 12 |  |  |  |
| RMII_PHY_BMC_RXD1_R | RMII | BUS | 4 | 5 | 5 | 10 | 5 | 14 | 6 | 10 | 12 | 12 | 12 | 12 |  |  |  |
| RMII_PHY_BMC_RXD1_R | RMII | BUS | 5 | 5 | 5 | 10 | 5 | 14 | 6 | 10 | 12 | 12 | 12 | 12 |  |  |  |
| RMII_PHY_BMC_RXD1_R | RMII | BUS | 6 | 5 | 5 | 10 | 5 | 14 | 6 | 10 | 12 | 12 | 12 | 12 |  |  |  |
| RMII_PHY_BMC_RXD1_R | RMII | BUS | 7 | 5 | 5 | 10 | 5 | 14 | 6 | 10 | 12 | 12 | 12 | 12 |  |  |  |
| RMII_PHY_BMC_RXD1_R | RMII | BUS | 8 | 4.75 | 5 | 10 | 5 | 14 | 6 | 10 | 12 | 12 | 12 | 12 |  |  |  |
| RMII_RXD_0 | RMII | BUS | 1 | 4.75 | 5 | 10 | 5 | 14 | 6 | 10 | 12 | 12 | 12 | 12 |  |  |  |
| RMII_RXD_0 | RMII | BUS | 2 | 5 | 5 | 10 | 5 | 14 | 6 | 10 | 12 | 12 | 12 | 12 |  |  |  |
| RMII_RXD_0 | RMII | BUS | 3 | 5 | 5 | 10 | 5 | 14 | 6 | 10 | 12 | 12 | 12 | 12 |  |  |  |
| RMII_RXD_0 | RMII | BUS | 4 | 5 | 5 | 10 | 5 | 14 | 6 | 10 | 12 | 12 | 12 | 12 |  |  |  |
| RMII_RXD_0 | RMII | BUS | 5 | 5 | 5 | 10 | 5 | 14 | 6 | 10 | 12 | 12 | 12 | 12 |  |  |  |
| RMII_RXD_0 | RMII | BUS | 6 | 5 | 5 | 10 | 5 | 14 | 6 | 10 | 12 | 12 | 12 | 12 |  |  |  |
| RMII_RXD_0 | RMII | BUS | 7 | 5 | 5 | 10 | 5 | 14 | 6 | 10 | 12 | 12 | 12 | 12 |  |  |  |
| RMII_RXD_0 | RMII | BUS | 8 | 4.75 | 5 | 10 | 5 | 14 | 6 | 10 | 12 | 12 | 12 | 12 |  |  |  |
| RMII_RXD_1 | RMII | BUS | 1 | 4.75 | 5 | 10 | 5 | 14 | 6 | 10 | 12 | 12 | 12 | 12 |  |  |  |
| RMII_RXD_1 | RMII | BUS | 2 | 5 | 5 | 10 | 5 | 14 | 6 | 10 | 12 | 12 | 12 | 12 |  |  |  |
| RMII_RXD_1 | RMII | BUS | 3 | 5 | 5 | 10 | 5 | 14 | 6 | 10 | 12 | 12 | 12 | 12 |  |  |  |
| RMII_RXD_1 | RMII | BUS | 4 | 5 | 5 | 10 | 5 | 14 | 6 | 10 | 12 | 12 | 12 | 12 |  |  |  |
| RMII_RXD_1 | RMII | BUS | 5 | 5 | 5 | 10 | 5 | 14 | 6 | 10 | 12 | 12 | 12 | 12 |  |  |  |
| RMII_RXD_1 | RMII | BUS | 6 | 5 | 5 | 10 | 5 | 14 | 6 | 10 | 12 | 12 | 12 | 12 |  |  |  |
| RMII_RXD_1 | RMII | BUS | 7 | 5 | 5 | 10 | 5 | 14 | 6 | 10 | 12 | 12 | 12 | 12 |  |  |  |
| RMII_RXD_1 | RMII | BUS | 8 | 4.75 | 5 | 10 | 5 | 14 | 6 | 10 | 12 | 12 | 12 | 12 |  |  |  |
| RMII_TXD_0 | RMII | BUS | 1 | 4.75 | 5 | 10 | 5 | 14 | 6 | 10 | 12 | 12 | 12 | 12 |  |  |  |
| RMII_TXD_0 | RMII | BUS | 2 | 5 | 5 | 10 | 5 | 14 | 6 | 10 | 12 | 12 | 12 | 12 |  |  |  |
| RMII_TXD_0 | RMII | BUS | 3 | 5 | 5 | 10 | 5 | 14 | 6 | 10 | 12 | 12 | 12 | 12 |  |  |  |
| RMII_TXD_0 | RMII | BUS | 4 | 5 | 5 | 10 | 5 | 14 | 6 | 10 | 12 | 12 | 12 | 12 |  |  |  |
| RMII_TXD_0 | RMII | BUS | 5 | 5 | 5 | 10 | 5 | 14 | 6 | 10 | 12 | 12 | 12 | 12 |  |  |  |
| RMII_TXD_0 | RMII | BUS | 6 | 5 | 5 | 10 | 5 | 14 | 6 | 10 | 12 | 12 | 12 | 12 |  |  |  |
| RMII_TXD_0 | RMII | BUS | 7 | 5 | 5 | 10 | 5 | 14 | 6 | 10 | 12 | 12 | 12 | 12 |  |  |  |
| RMII_TXD_0 | RMII | BUS | 8 | 4.75 | 5 | 10 | 5 | 14 | 6 | 10 | 12 | 12 | 12 | 12 |  |  |  |
| RMII_TXD_1 | RMII | BUS | 1 | 4.75 | 5 | 10 | 5 | 14 | 6 | 10 | 12 | 12 | 12 | 12 |  |  |  |
| RMII_TXD_1 | RMII | BUS | 2 | 5 | 5 | 10 | 5 | 14 | 6 | 10 | 12 | 12 | 12 | 12 |  |  |  |
| RMII_TXD_1 | RMII | BUS | 3 | 5 | 5 | 10 | 5 | 14 | 6 | 10 | 12 | 12 | 12 | 12 |  |  |  |
| RMII_TXD_1 | RMII | BUS | 4 | 5 | 5 | 10 | 5 | 14 | 6 | 10 | 12 | 12 | 12 | 12 |  |  |  |
| RMII_TXD_1 | RMII | BUS | 5 | 5 | 5 | 10 | 5 | 14 | 6 | 10 | 12 | 12 | 12 | 12 |  |  |  |
| RMII_TXD_1 | RMII | BUS | 6 | 5 | 5 | 10 | 5 | 14 | 6 | 10 | 12 | 12 | 12 | 12 |  |  |  |
| RMII_TXD_1 | RMII | BUS | 7 | 5 | 5 | 10 | 5 | 14 | 6 | 10 | 12 | 12 | 12 | 12 |  |  |  |
| RMII_TXD_1 | RMII | BUS | 8 | 4.75 | 5 | 10 | 5 | 14 | 6 | 10 | 12 | 12 | 12 | 12 |  |  |  |
| RMII0_BMC_C_PHY_TXD0 | RMII | BUS | 1 | 4.75 | 5 | 10 | 5 | 14 | 6 | 10 | 12 | 12 | 12 | 12 |  |  |  |
| RMII0_BMC_C_PHY_TXD0 | RMII | BUS | 2 | 5 | 5 | 10 | 5 | 14 | 6 | 10 | 12 | 12 | 12 | 12 |  |  |  |
| RMII0_BMC_C_PHY_TXD0 | RMII | BUS | 3 | 5 | 5 | 10 | 5 | 14 | 6 | 10 | 12 | 12 | 12 | 12 |  |  |  |
| RMII0_BMC_C_PHY_TXD0 | RMII | BUS | 4 | 5 | 5 | 10 | 5 | 14 | 6 | 10 | 12 | 12 | 12 | 12 |  |  |  |
| RMII0_BMC_C_PHY_TXD0 | RMII | BUS | 5 | 5 | 5 | 10 | 5 | 14 | 6 | 10 | 12 | 12 | 12 | 12 |  |  |  |
| RMII0_BMC_C_PHY_TXD0 | RMII | BUS | 6 | 5 | 5 | 10 | 5 | 14 | 6 | 10 | 12 | 12 | 12 | 12 |  |  |  |
| RMII0_BMC_C_PHY_TXD0 | RMII | BUS | 7 | 5 | 5 | 10 | 5 | 14 | 6 | 10 | 12 | 12 | 12 | 12 |  |  |  |
| RMII0_BMC_C_PHY_TXD0 | RMII | BUS | 8 | 4.75 | 5 | 10 | 5 | 14 | 6 | 10 | 12 | 12 | 12 | 12 |  |  |  |
| RMII0_BMC_C_PHY_TXD1 | RMII | BUS | 1 | 4.75 | 5 | 10 | 5 | 14 | 6 | 10 | 12 | 12 | 12 | 12 |  |  |  |
| RMII0_BMC_C_PHY_TXD1 | RMII | BUS | 2 | 5 | 5 | 10 | 5 | 14 | 6 | 10 | 12 | 12 | 12 | 12 |  |  |  |
| RMII0_BMC_C_PHY_TXD1 | RMII | BUS | 3 | 5 | 5 | 10 | 5 | 14 | 6 | 10 | 12 | 12 | 12 | 12 |  |  |  |
| RMII0_BMC_C_PHY_TXD1 | RMII | BUS | 4 | 5 | 5 | 10 | 5 | 14 | 6 | 10 | 12 | 12 | 12 | 12 |  |  |  |
| RMII0_BMC_C_PHY_TXD1 | RMII | BUS | 5 | 5 | 5 | 10 | 5 | 14 | 6 | 10 | 12 | 12 | 12 | 12 |  |  |  |
| RMII0_BMC_C_PHY_TXD1 | RMII | BUS | 6 | 5 | 5 | 10 | 5 | 14 | 6 | 10 | 12 | 12 | 12 | 12 |  |  |  |
| RMII0_BMC_C_PHY_TXD1 | RMII | BUS | 7 | 5 | 5 | 10 | 5 | 14 | 6 | 10 | 12 | 12 | 12 | 12 |  |  |  |
| RMII0_BMC_C_PHY_TXD1 | RMII | BUS | 8 | 4.75 | 5 | 10 | 5 | 14 | 6 | 10 | 12 | 12 | 12 | 12 |  |  |  |
| NVM_SK | SPI | BUS | 1 | 4.75 | 5 | 10 | 5 | 14 | 6 | 20 | 12 | 12 | 12 | 12 |  |  |  |
| NVM_SK | SPI | BUS | 2 | 5 | 5 | 10 | 5 | 14 | 6 | 20 | 12 | 12 | 12 | 12 |  |  |  |
| NVM_SK | SPI | BUS | 3 | 5 | 5 | 10 | 5 | 14 | 6 | 20 | 12 | 12 | 12 | 12 |  |  |  |
| NVM_SK | SPI | BUS | 4 | 5 | 5 | 10 | 5 | 14 | 6 | 20 | 12 | 12 | 12 | 12 |  |  |  |
| NVM_SK | SPI | BUS | 5 | 5 | 5 | 10 | 5 | 14 | 6 | 20 | 12 | 12 | 12 | 12 |  |  |  |
| NVM_SK | SPI | BUS | 6 | 5 | 5 | 10 | 5 | 14 | 6 | 20 | 12 | 12 | 12 | 12 |  |  |  |
| NVM_SK | SPI | BUS | 7 | 5 | 5 | 10 | 5 | 14 | 6 | 20 | 12 | 12 | 12 | 12 |  |  |  |
| NVM_SK | SPI | BUS | 8 | 4.75 | 5 | 10 | 5 | 14 | 6 | 20 | 12 | 12 | 12 | 12 |  |  |  |
| NVM_SK_R | SPI | BUS | 1 | 4.75 | 5 | 10 | 5 | 14 | 6 | 20 | 12 | 12 | 12 | 12 |  |  |  |
| NVM_SK_R | SPI | BUS | 2 | 5 | 5 | 10 | 5 | 14 | 6 | 20 | 12 | 12 | 12 | 12 |  |  |  |
| NVM_SK_R | SPI | BUS | 3 | 5 | 5 | 10 | 5 | 14 | 6 | 20 | 12 | 12 | 12 | 12 |  |  |  |
| NVM_SK_R | SPI | BUS | 4 | 5 | 5 | 10 | 5 | 14 | 6 | 20 | 12 | 12 | 12 | 12 |  |  |  |
| NVM_SK_R | SPI | BUS | 5 | 5 | 5 | 10 | 5 | 14 | 6 | 20 | 12 | 12 | 12 | 12 |  |  |  |
| NVM_SK_R | SPI | BUS | 6 | 5 | 5 | 10 | 5 | 14 | 6 | 20 | 12 | 12 | 12 | 12 |  |  |  |
| NVM_SK_R | SPI | BUS | 7 | 5 | 5 | 10 | 5 | 14 | 6 | 20 | 12 | 12 | 12 | 12 |  |  |  |
| NVM_SK_R | SPI | BUS | 8 | 4.75 | 5 | 10 | 5 | 14 | 6 | 20 | 12 | 12 | 12 | 12 |  |  |  |
| ROMD0 | SPI | BUS | 1 | 4.75 | 5 | 10 | 5 | 14 | 6 | 20 | 12 | 12 | 12 | 12 |  |  |  |
| ROMD0 | SPI | BUS | 2 | 5 | 5 | 10 | 5 | 14 | 6 | 20 | 12 | 12 | 12 | 12 |  |  |  |
| ROMD0 | SPI | BUS | 3 | 5 | 5 | 10 | 5 | 14 | 6 | 20 | 12 | 12 | 12 | 12 |  |  |  |
| ROMD0 | SPI | BUS | 4 | 5 | 5 | 10 | 5 | 14 | 6 | 20 | 12 | 12 | 12 | 12 |  |  |  |
| ROMD0 | SPI | BUS | 5 | 5 | 5 | 10 | 5 | 14 | 6 | 20 | 12 | 12 | 12 | 12 |  |  |  |
| ROMD0 | SPI | BUS | 6 | 5 | 5 | 10 | 5 | 14 | 6 | 20 | 12 | 12 | 12 | 12 |  |  |  |
| ROMD0 | SPI | BUS | 7 | 5 | 5 | 10 | 5 | 14 | 6 | 20 | 12 | 12 | 12 | 12 |  |  |  |
| ROMD0 | SPI | BUS | 8 | 4.75 | 5 | 10 | 5 | 14 | 6 | 20 | 12 | 12 | 12 | 12 |  |  |  |
| ROMD0_R | SPI | BUS | 1 | 4.75 | 5 | 10 | 5 | 14 | 6 | 20 | 12 | 12 | 12 | 12 |  |  |  |
| ROMD0_R | SPI | BUS | 2 | 5 | 5 | 10 | 5 | 14 | 6 | 20 | 12 | 12 | 12 | 12 |  |  |  |
| ROMD0_R | SPI | BUS | 3 | 5 | 5 | 10 | 5 | 14 | 6 | 20 | 12 | 12 | 12 | 12 |  |  |  |
| ROMD0_R | SPI | BUS | 4 | 5 | 5 | 10 | 5 | 14 | 6 | 20 | 12 | 12 | 12 | 12 |  |  |  |
| ROMD0_R | SPI | BUS | 5 | 5 | 5 | 10 | 5 | 14 | 6 | 20 | 12 | 12 | 12 | 12 |  |  |  |
| ROMD0_R | SPI | BUS | 6 | 5 | 5 | 10 | 5 | 14 | 6 | 20 | 12 | 12 | 12 | 12 |  |  |  |
| ROMD0_R | SPI | BUS | 7 | 5 | 5 | 10 | 5 | 14 | 6 | 20 | 12 | 12 | 12 | 12 |  |  |  |
| ROMD0_R | SPI | BUS | 8 | 4.75 | 5 | 10 | 5 | 14 | 6 | 20 | 12 | 12 | 12 | 12 |  |  |  |
| SPI_CLK0 | SPI | BUS | 1 | 4.75 | 5 | 10 | 5 | 14 | 6 | 20 | 12 | 12 | 12 | 12 |  |  |  |
| SPI_CLK0 | SPI | BUS | 2 | 5 | 5 | 10 | 5 | 14 | 6 | 20 | 12 | 12 | 12 | 12 |  |  |  |
| SPI_CLK0 | SPI | BUS | 3 | 5 | 5 | 10 | 5 | 14 | 6 | 20 | 12 | 12 | 12 | 12 |  |  |  |
| SPI_CLK0 | SPI | BUS | 4 | 5 | 5 | 10 | 5 | 14 | 6 | 20 | 12 | 12 | 12 | 12 |  |  |  |
| SPI_CLK0 | SPI | BUS | 5 | 5 | 5 | 10 | 5 | 14 | 6 | 20 | 12 | 12 | 12 | 12 |  |  |  |
| SPI_CLK0 | SPI | BUS | 6 | 5 | 5 | 10 | 5 | 14 | 6 | 20 | 12 | 12 | 12 | 12 |  |  |  |
| SPI_CLK0 | SPI | BUS | 7 | 5 | 5 | 10 | 5 | 14 | 6 | 20 | 12 | 12 | 12 | 12 |  |  |  |
| SPI_CLK0 | SPI | BUS | 8 | 4.75 | 5 | 10 | 5 | 14 | 6 | 20 | 12 | 12 | 12 | 12 |  |  |  |
| SPI_CLK0_R | SPI | BUS | 1 | 4.75 | 5 | 10 | 5 | 14 | 6 | 20 | 12 | 12 | 12 | 12 |  |  |  |
| SPI_CLK0_R | SPI | BUS | 2 | 5 | 5 | 10 | 5 | 14 | 6 | 20 | 12 | 12 | 12 | 12 |  |  |  |
| SPI_CLK0_R | SPI | BUS | 3 | 5 | 5 | 10 | 5 | 14 | 6 | 20 | 12 | 12 | 12 | 12 |  |  |  |
| SPI_CLK0_R | SPI | BUS | 4 | 5 | 5 | 10 | 5 | 14 | 6 | 20 | 12 | 12 | 12 | 12 |  |  |  |
| SPI_CLK0_R | SPI | BUS | 5 | 5 | 5 | 10 | 5 | 14 | 6 | 20 | 12 | 12 | 12 | 12 |  |  |  |
| SPI_CLK0_R | SPI | BUS | 6 | 5 | 5 | 10 | 5 | 14 | 6 | 20 | 12 | 12 | 12 | 12 |  |  |  |
| SPI_CLK0_R | SPI | BUS | 7 | 5 | 5 | 10 | 5 | 14 | 6 | 20 | 12 | 12 | 12 | 12 |  |  |  |
| SPI_CLK0_R | SPI | BUS | 8 | 4.75 | 5 | 10 | 5 | 14 | 6 | 20 | 12 | 12 | 12 | 12 |  |  |  |
| SPICK | SPI | BUS | 1 | 4.75 | 5 | 10 | 5 | 14 | 6 | 20 | 12 | 12 | 12 | 12 |  |  |  |
| SPICK | SPI | BUS | 2 | 5 | 5 | 10 | 5 | 14 | 6 | 20 | 12 | 12 | 12 | 12 |  |  |  |
| SPICK | SPI | BUS | 3 | 5 | 5 | 10 | 5 | 14 | 6 | 20 | 12 | 12 | 12 | 12 |  |  |  |
| SPICK | SPI | BUS | 4 | 5 | 5 | 10 | 5 | 14 | 6 | 20 | 12 | 12 | 12 | 12 |  |  |  |
| SPICK | SPI | BUS | 5 | 5 | 5 | 10 | 5 | 14 | 6 | 20 | 12 | 12 | 12 | 12 |  |  |  |
| SPICK | SPI | BUS | 6 | 5 | 5 | 10 | 5 | 14 | 6 | 20 | 12 | 12 | 12 | 12 |  |  |  |
| SPICK | SPI | BUS | 7 | 5 | 5 | 10 | 5 | 14 | 6 | 20 | 12 | 12 | 12 | 12 |  |  |  |
| SPICK | SPI | BUS | 8 | 4.75 | 5 | 10 | 5 | 14 | 6 | 20 | 12 | 12 | 12 | 12 |  |  |  |
| SPICK_R | SPI | BUS | 1 | 4.75 | 5 | 10 | 5 | 14 | 6 | 20 | 12 | 12 | 12 | 12 |  |  |  |
| SPICK_R | SPI | BUS | 2 | 5 | 5 | 10 | 5 | 14 | 6 | 20 | 12 | 12 | 12 | 12 |  |  |  |
| SPICK_R | SPI | BUS | 3 | 5 | 5 | 10 | 5 | 14 | 6 | 20 | 12 | 12 | 12 | 12 |  |  |  |
| SPICK_R | SPI | BUS | 4 | 5 | 5 | 10 | 5 | 14 | 6 | 20 | 12 | 12 | 12 | 12 |  |  |  |
| SPICK_R | SPI | BUS | 5 | 5 | 5 | 10 | 5 | 14 | 6 | 20 | 12 | 12 | 12 | 12 |  |  |  |
| SPICK_R | SPI | BUS | 6 | 5 | 5 | 10 | 5 | 14 | 6 | 20 | 12 | 12 | 12 | 12 |  |  |  |
| SPICK_R | SPI | BUS | 7 | 5 | 5 | 10 | 5 | 14 | 6 | 20 | 12 | 12 | 12 | 12 |  |  |  |
| SPICK_R | SPI | BUS | 8 | 4.75 | 5 | 10 | 5 | 14 | 6 | 20 | 12 | 12 | 12 | 12 |  |  |  |
| NVM_CS_N | SPI-DATA | BUS | 1 | 4.75 | 5 | 10 | 5 | 14 | 6 | 15 | 12 | 12 | 12 | 12 |  |  |  |
| NVM_CS_N | SPI-DATA | BUS | 2 | 5 | 5 | 10 | 5 | 14 | 6 | 15 | 12 | 12 | 12 | 12 |  |  |  |
| NVM_CS_N | SPI-DATA | BUS | 3 | 5 | 5 | 10 | 5 | 14 | 6 | 15 | 12 | 12 | 12 | 12 |  |  |  |
| NVM_CS_N | SPI-DATA | BUS | 4 | 5 | 5 | 10 | 5 | 14 | 6 | 15 | 12 | 12 | 12 | 12 |  |  |  |
| NVM_CS_N | SPI-DATA | BUS | 5 | 5 | 5 | 10 | 5 | 14 | 6 | 15 | 12 | 12 | 12 | 12 |  |  |  |
| NVM_CS_N | SPI-DATA | BUS | 6 | 5 | 5 | 10 | 5 | 14 | 6 | 15 | 12 | 12 | 12 | 12 |  |  |  |
| NVM_CS_N | SPI-DATA | BUS | 7 | 5 | 5 | 10 | 5 | 14 | 6 | 15 | 12 | 12 | 12 | 12 |  |  |  |
| NVM_CS_N | SPI-DATA | BUS | 8 | 4.75 | 5 | 10 | 5 | 14 | 6 | 15 | 12 | 12 | 12 | 12 |  |  |  |
| NVM_CS_N_R | SPI-DATA | BUS | 1 | 4.75 | 5 | 10 | 5 | 14 | 6 | 15 | 12 | 12 | 12 | 12 |  |  |  |
| NVM_CS_N_R | SPI-DATA | BUS | 2 | 5 | 5 | 10 | 5 | 14 | 6 | 15 | 12 | 12 | 12 | 12 |  |  |  |
| NVM_CS_N_R | SPI-DATA | BUS | 3 | 5 | 5 | 10 | 5 | 14 | 6 | 15 | 12 | 12 | 12 | 12 |  |  |  |
| NVM_CS_N_R | SPI-DATA | BUS | 4 | 5 | 5 | 10 | 5 | 14 | 6 | 15 | 12 | 12 | 12 | 12 |  |  |  |
| NVM_CS_N_R | SPI-DATA | BUS | 5 | 5 | 5 | 10 | 5 | 14 | 6 | 15 | 12 | 12 | 12 | 12 |  |  |  |
| NVM_CS_N_R | SPI-DATA | BUS | 6 | 5 | 5 | 10 | 5 | 14 | 6 | 15 | 12 | 12 | 12 | 12 |  |  |  |
| NVM_CS_N_R | SPI-DATA | BUS | 7 | 5 | 5 | 10 | 5 | 14 | 6 | 15 | 12 | 12 | 12 | 12 |  |  |  |
| NVM_CS_N_R | SPI-DATA | BUS | 8 | 4.75 | 5 | 10 | 5 | 14 | 6 | 15 | 12 | 12 | 12 | 12 |  |  |  |
| NVM_SI | SPI-DATA | BUS | 1 | 4.75 | 5 | 10 | 5 | 14 | 6 | 15 | 12 | 12 | 12 | 12 |  |  |  |
| NVM_SI | SPI-DATA | BUS | 2 | 5 | 5 | 10 | 5 | 14 | 6 | 15 | 12 | 12 | 12 | 12 |  |  |  |
| NVM_SI | SPI-DATA | BUS | 3 | 5 | 5 | 10 | 5 | 14 | 6 | 15 | 12 | 12 | 12 | 12 |  |  |  |
| NVM_SI | SPI-DATA | BUS | 4 | 5 | 5 | 10 | 5 | 14 | 6 | 15 | 12 | 12 | 12 | 12 |  |  |  |
| NVM_SI | SPI-DATA | BUS | 5 | 5 | 5 | 10 | 5 | 14 | 6 | 15 | 12 | 12 | 12 | 12 |  |  |  |
| NVM_SI | SPI-DATA | BUS | 6 | 5 | 5 | 10 | 5 | 14 | 6 | 15 | 12 | 12 | 12 | 12 |  |  |  |
| NVM_SI | SPI-DATA | BUS | 7 | 5 | 5 | 10 | 5 | 14 | 6 | 15 | 12 | 12 | 12 | 12 |  |  |  |
| NVM_SI | SPI-DATA | BUS | 8 | 4.75 | 5 | 10 | 5 | 14 | 6 | 15 | 12 | 12 | 12 | 12 |  |  |  |
| NVM_SI_R | SPI-DATA | BUS | 1 | 4.75 | 5 | 10 | 5 | 14 | 6 | 15 | 12 | 12 | 12 | 12 |  |  |  |
| NVM_SI_R | SPI-DATA | BUS | 2 | 5 | 5 | 10 | 5 | 14 | 6 | 15 | 12 | 12 | 12 | 12 |  |  |  |
| NVM_SI_R | SPI-DATA | BUS | 3 | 5 | 5 | 10 | 5 | 14 | 6 | 15 | 12 | 12 | 12 | 12 |  |  |  |
| NVM_SI_R | SPI-DATA | BUS | 4 | 5 | 5 | 10 | 5 | 14 | 6 | 15 | 12 | 12 | 12 | 12 |  |  |  |
| NVM_SI_R | SPI-DATA | BUS | 5 | 5 | 5 | 10 | 5 | 14 | 6 | 15 | 12 | 12 | 12 | 12 |  |  |  |
| NVM_SI_R | SPI-DATA | BUS | 6 | 5 | 5 | 10 | 5 | 14 | 6 | 15 | 12 | 12 | 12 | 12 |  |  |  |
| NVM_SI_R | SPI-DATA | BUS | 7 | 5 | 5 | 10 | 5 | 14 | 6 | 15 | 12 | 12 | 12 | 12 |  |  |  |
| NVM_SI_R | SPI-DATA | BUS | 8 | 4.75 | 5 | 10 | 5 | 14 | 6 | 15 | 12 | 12 | 12 | 12 |  |  |  |
| NVM_SO | SPI-DATA | BUS | 1 | 4.75 | 5 | 10 | 5 | 14 | 6 | 15 | 12 | 12 | 12 | 12 |  |  |  |
| NVM_SO | SPI-DATA | BUS | 2 | 5 | 5 | 10 | 5 | 14 | 6 | 15 | 12 | 12 | 12 | 12 |  |  |  |
| NVM_SO | SPI-DATA | BUS | 3 | 5 | 5 | 10 | 5 | 14 | 6 | 15 | 12 | 12 | 12 | 12 |  |  |  |
| NVM_SO | SPI-DATA | BUS | 4 | 5 | 5 | 10 | 5 | 14 | 6 | 15 | 12 | 12 | 12 | 12 |  |  |  |
| NVM_SO | SPI-DATA | BUS | 5 | 5 | 5 | 10 | 5 | 14 | 6 | 15 | 12 | 12 | 12 | 12 |  |  |  |
| NVM_SO | SPI-DATA | BUS | 6 | 5 | 5 | 10 | 5 | 14 | 6 | 15 | 12 | 12 | 12 | 12 |  |  |  |
| NVM_SO | SPI-DATA | BUS | 7 | 5 | 5 | 10 | 5 | 14 | 6 | 15 | 12 | 12 | 12 | 12 |  |  |  |
| NVM_SO | SPI-DATA | BUS | 8 | 4.75 | 5 | 10 | 5 | 14 | 6 | 15 | 12 | 12 | 12 | 12 |  |  |  |
| NVM_SO_R | SPI-DATA | BUS | 1 | 4.75 | 5 | 10 | 5 | 14 | 6 | 15 | 12 | 12 | 12 | 12 |  |  |  |
| NVM_SO_R | SPI-DATA | BUS | 2 | 5 | 5 | 10 | 5 | 14 | 6 | 15 | 12 | 12 | 12 | 12 |  |  |  |
| NVM_SO_R | SPI-DATA | BUS | 3 | 5 | 5 | 10 | 5 | 14 | 6 | 15 | 12 | 12 | 12 | 12 |  |  |  |
| NVM_SO_R | SPI-DATA | BUS | 4 | 5 | 5 | 10 | 5 | 14 | 6 | 15 | 12 | 12 | 12 | 12 |  |  |  |
| NVM_SO_R | SPI-DATA | BUS | 5 | 5 | 5 | 10 | 5 | 14 | 6 | 15 | 12 | 12 | 12 | 12 |  |  |  |
| NVM_SO_R | SPI-DATA | BUS | 6 | 5 | 5 | 10 | 5 | 14 | 6 | 15 | 12 | 12 | 12 | 12 |  |  |  |
| NVM_SO_R | SPI-DATA | BUS | 7 | 5 | 5 | 10 | 5 | 14 | 6 | 15 | 12 | 12 | 12 | 12 |  |  |  |
| NVM_SO_R | SPI-DATA | BUS | 8 | 4.75 | 5 | 10 | 5 | 14 | 6 | 15 | 12 | 12 | 12 | 12 |  |  |  |
| ROMD1 | SPI-DATA | BUS | 1 | 4.75 | 5 | 10 | 5 | 14 | 6 | 15 | 12 | 12 | 12 | 12 |  |  |  |
| ROMD1 | SPI-DATA | BUS | 2 | 5 | 5 | 10 | 5 | 14 | 6 | 15 | 12 | 12 | 12 | 12 |  |  |  |
| ROMD1 | SPI-DATA | BUS | 3 | 5 | 5 | 10 | 5 | 14 | 6 | 15 | 12 | 12 | 12 | 12 |  |  |  |
| ROMD1 | SPI-DATA | BUS | 4 | 5 | 5 | 10 | 5 | 14 | 6 | 15 | 12 | 12 | 12 | 12 |  |  |  |
| ROMD1 | SPI-DATA | BUS | 5 | 5 | 5 | 10 | 5 | 14 | 6 | 15 | 12 | 12 | 12 | 12 |  |  |  |
| ROMD1 | SPI-DATA | BUS | 6 | 5 | 5 | 10 | 5 | 14 | 6 | 15 | 12 | 12 | 12 | 12 |  |  |  |
| ROMD1 | SPI-DATA | BUS | 7 | 5 | 5 | 10 | 5 | 14 | 6 | 15 | 12 | 12 | 12 | 12 |  |  |  |
| ROMD1 | SPI-DATA | BUS | 8 | 4.75 | 5 | 10 | 5 | 14 | 6 | 15 | 12 | 12 | 12 | 12 |  |  |  |
| ROMD1_R | SPI-DATA | BUS | 1 | 4.75 | 5 | 10 | 5 | 14 | 6 | 15 | 12 | 12 | 12 | 12 |  |  |  |
| ROMD1_R | SPI-DATA | BUS | 2 | 5 | 5 | 10 | 5 | 14 | 6 | 15 | 12 | 12 | 12 | 12 |  |  |  |
| ROMD1_R | SPI-DATA | BUS | 3 | 5 | 5 | 10 | 5 | 14 | 6 | 15 | 12 | 12 | 12 | 12 |  |  |  |
| ROMD1_R | SPI-DATA | BUS | 4 | 5 | 5 | 10 | 5 | 14 | 6 | 15 | 12 | 12 | 12 | 12 |  |  |  |
| ROMD1_R | SPI-DATA | BUS | 5 | 5 | 5 | 10 | 5 | 14 | 6 | 15 | 12 | 12 | 12 | 12 |  |  |  |
| ROMD1_R | SPI-DATA | BUS | 6 | 5 | 5 | 10 | 5 | 14 | 6 | 15 | 12 | 12 | 12 | 12 |  |  |  |
| ROMD1_R | SPI-DATA | BUS | 7 | 5 | 5 | 10 | 5 | 14 | 6 | 15 | 12 | 12 | 12 | 12 |  |  |  |
| ROMD1_R | SPI-DATA | BUS | 8 | 4.75 | 5 | 10 | 5 | 14 | 6 | 15 | 12 | 12 | 12 | 12 |  |  |  |
| ROMD2 | SPI-DATA | BUS | 1 | 4.75 | 5 | 10 | 5 | 14 | 6 | 15 | 12 | 12 | 12 | 12 |  |  |  |
| ROMD2 | SPI-DATA | BUS | 2 | 5 | 5 | 10 | 5 | 14 | 6 | 15 | 12 | 12 | 12 | 12 |  |  |  |
| ROMD2 | SPI-DATA | BUS | 3 | 5 | 5 | 10 | 5 | 14 | 6 | 15 | 12 | 12 | 12 | 12 |  |  |  |
| ROMD2 | SPI-DATA | BUS | 4 | 5 | 5 | 10 | 5 | 14 | 6 | 15 | 12 | 12 | 12 | 12 |  |  |  |
| ROMD2 | SPI-DATA | BUS | 5 | 5 | 5 | 10 | 5 | 14 | 6 | 15 | 12 | 12 | 12 | 12 |  |  |  |
| ROMD2 | SPI-DATA | BUS | 6 | 5 | 5 | 10 | 5 | 14 | 6 | 15 | 12 | 12 | 12 | 12 |  |  |  |
| ROMD2 | SPI-DATA | BUS | 7 | 5 | 5 | 10 | 5 | 14 | 6 | 15 | 12 | 12 | 12 | 12 |  |  |  |
| ROMD2 | SPI-DATA | BUS | 8 | 4.75 | 5 | 10 | 5 | 14 | 6 | 15 | 12 | 12 | 12 | 12 |  |  |  |
| ROMD2_R | SPI-DATA | BUS | 1 | 4.75 | 5 | 10 | 5 | 14 | 6 | 15 | 12 | 12 | 12 | 12 |  |  |  |
| ROMD2_R | SPI-DATA | BUS | 2 | 5 | 5 | 10 | 5 | 14 | 6 | 15 | 12 | 12 | 12 | 12 |  |  |  |
| ROMD2_R | SPI-DATA | BUS | 3 | 5 | 5 | 10 | 5 | 14 | 6 | 15 | 12 | 12 | 12 | 12 |  |  |  |
| ROMD2_R | SPI-DATA | BUS | 4 | 5 | 5 | 10 | 5 | 14 | 6 | 15 | 12 | 12 | 12 | 12 |  |  |  |
| ROMD2_R | SPI-DATA | BUS | 5 | 5 | 5 | 10 | 5 | 14 | 6 | 15 | 12 | 12 | 12 | 12 |  |  |  |
| ROMD2_R | SPI-DATA | BUS | 6 | 5 | 5 | 10 | 5 | 14 | 6 | 15 | 12 | 12 | 12 | 12 |  |  |  |
| ROMD2_R | SPI-DATA | BUS | 7 | 5 | 5 | 10 | 5 | 14 | 6 | 15 | 12 | 12 | 12 | 12 |  |  |  |
| ROMD2_R | SPI-DATA | BUS | 8 | 4.75 | 5 | 10 | 5 | 14 | 6 | 15 | 12 | 12 | 12 | 12 |  |  |  |
| SPI_CSB0_0 | SPI-DATA | BUS | 1 | 4.75 | 5 | 10 | 5 | 14 | 6 | 15 | 12 | 12 | 12 | 12 |  |  |  |
| SPI_CSB0_0 | SPI-DATA | BUS | 2 | 5 | 5 | 10 | 5 | 14 | 6 | 15 | 12 | 12 | 12 | 12 |  |  |  |
| SPI_CSB0_0 | SPI-DATA | BUS | 3 | 5 | 5 | 10 | 5 | 14 | 6 | 15 | 12 | 12 | 12 | 12 |  |  |  |
| SPI_CSB0_0 | SPI-DATA | BUS | 4 | 5 | 5 | 10 | 5 | 14 | 6 | 15 | 12 | 12 | 12 | 12 |  |  |  |
| SPI_CSB0_0 | SPI-DATA | BUS | 5 | 5 | 5 | 10 | 5 | 14 | 6 | 15 | 12 | 12 | 12 | 12 |  |  |  |
| SPI_CSB0_0 | SPI-DATA | BUS | 6 | 5 | 5 | 10 | 5 | 14 | 6 | 15 | 12 | 12 | 12 | 12 |  |  |  |
| SPI_CSB0_0 | SPI-DATA | BUS | 7 | 5 | 5 | 10 | 5 | 14 | 6 | 15 | 12 | 12 | 12 | 12 |  |  |  |
| SPI_CSB0_0 | SPI-DATA | BUS | 8 | 4.75 | 5 | 10 | 5 | 14 | 6 | 15 | 12 | 12 | 12 | 12 |  |  |  |
| SPI_CSB0_1 | SPI-DATA | BUS | 1 | 4.75 | 5 | 10 | 5 | 14 | 6 | 15 | 12 | 12 | 12 | 12 |  |  |  |
| SPI_CSB0_1 | SPI-DATA | BUS | 2 | 5 | 5 | 10 | 5 | 14 | 6 | 15 | 12 | 12 | 12 | 12 |  |  |  |
| SPI_CSB0_1 | SPI-DATA | BUS | 3 | 5 | 5 | 10 | 5 | 14 | 6 | 15 | 12 | 12 | 12 | 12 |  |  |  |
| SPI_CSB0_1 | SPI-DATA | BUS | 4 | 5 | 5 | 10 | 5 | 14 | 6 | 15 | 12 | 12 | 12 | 12 |  |  |  |
| SPI_CSB0_1 | SPI-DATA | BUS | 5 | 5 | 5 | 10 | 5 | 14 | 6 | 15 | 12 | 12 | 12 | 12 |  |  |  |
| SPI_CSB0_1 | SPI-DATA | BUS | 6 | 5 | 5 | 10 | 5 | 14 | 6 | 15 | 12 | 12 | 12 | 12 |  |  |  |
| SPI_CSB0_1 | SPI-DATA | BUS | 7 | 5 | 5 | 10 | 5 | 14 | 6 | 15 | 12 | 12 | 12 | 12 |  |  |  |
| SPI_CSB0_1 | SPI-DATA | BUS | 8 | 4.75 | 5 | 10 | 5 | 14 | 6 | 15 | 12 | 12 | 12 | 12 |  |  |  |
| SPI_DATA0_0 | SPI-DATA | BUS | 1 | 4.75 | 5 | 10 | 5 | 14 | 6 | 15 | 12 | 12 | 12 | 12 |  |  |  |
| SPI_DATA0_0 | SPI-DATA | BUS | 2 | 5 | 5 | 10 | 5 | 14 | 6 | 15 | 12 | 12 | 12 | 12 |  |  |  |
| SPI_DATA0_0 | SPI-DATA | BUS | 3 | 5 | 5 | 10 | 5 | 14 | 6 | 15 | 12 | 12 | 12 | 12 |  |  |  |
| SPI_DATA0_0 | SPI-DATA | BUS | 4 | 5 | 5 | 10 | 5 | 14 | 6 | 15 | 12 | 12 | 12 | 12 |  |  |  |
| SPI_DATA0_0 | SPI-DATA | BUS | 5 | 5 | 5 | 10 | 5 | 14 | 6 | 15 | 12 | 12 | 12 | 12 |  |  |  |
| SPI_DATA0_0 | SPI-DATA | BUS | 6 | 5 | 5 | 10 | 5 | 14 | 6 | 15 | 12 | 12 | 12 | 12 |  |  |  |
| SPI_DATA0_0 | SPI-DATA | BUS | 7 | 5 | 5 | 10 | 5 | 14 | 6 | 15 | 12 | 12 | 12 | 12 |  |  |  |
| SPI_DATA0_0 | SPI-DATA | BUS | 8 | 4.75 | 5 | 10 | 5 | 14 | 6 | 15 | 12 | 12 | 12 | 12 |  |  |  |
| SPI_DATA0_0_R | SPI-DATA | BUS | 1 | 4.75 | 5 | 10 | 5 | 14 | 6 | 15 | 12 | 12 | 12 | 12 |  |  |  |
| SPI_DATA0_0_R | SPI-DATA | BUS | 2 | 5 | 5 | 10 | 5 | 14 | 6 | 15 | 12 | 12 | 12 | 12 |  |  |  |
| SPI_DATA0_0_R | SPI-DATA | BUS | 3 | 5 | 5 | 10 | 5 | 14 | 6 | 15 | 12 | 12 | 12 | 12 |  |  |  |
| SPI_DATA0_0_R | SPI-DATA | BUS | 4 | 5 | 5 | 10 | 5 | 14 | 6 | 15 | 12 | 12 | 12 | 12 |  |  |  |
| SPI_DATA0_0_R | SPI-DATA | BUS | 5 | 5 | 5 | 10 | 5 | 14 | 6 | 15 | 12 | 12 | 12 | 12 |  |  |  |
| SPI_DATA0_0_R | SPI-DATA | BUS | 6 | 5 | 5 | 10 | 5 | 14 | 6 | 15 | 12 | 12 | 12 | 12 |  |  |  |
| SPI_DATA0_0_R | SPI-DATA | BUS | 7 | 5 | 5 | 10 | 5 | 14 | 6 | 15 | 12 | 12 | 12 | 12 |  |  |  |
| SPI_DATA0_0_R | SPI-DATA | BUS | 8 | 4.75 | 5 | 10 | 5 | 14 | 6 | 15 | 12 | 12 | 12 | 12 |  |  |  |
| SPI_DATA0_1 | SPI-DATA | BUS | 1 | 4.75 | 5 | 10 | 5 | 14 | 6 | 15 | 12 | 12 | 12 | 12 |  |  |  |
| SPI_DATA0_1 | SPI-DATA | BUS | 2 | 5 | 5 | 10 | 5 | 14 | 6 | 15 | 12 | 12 | 12 | 12 |  |  |  |
| SPI_DATA0_1 | SPI-DATA | BUS | 3 | 5 | 5 | 10 | 5 | 14 | 6 | 15 | 12 | 12 | 12 | 12 |  |  |  |
| SPI_DATA0_1 | SPI-DATA | BUS | 4 | 5 | 5 | 10 | 5 | 14 | 6 | 15 | 12 | 12 | 12 | 12 |  |  |  |
| SPI_DATA0_1 | SPI-DATA | BUS | 5 | 5 | 5 | 10 | 5 | 14 | 6 | 15 | 12 | 12 | 12 | 12 |  |  |  |
| SPI_DATA0_1 | SPI-DATA | BUS | 6 | 5 | 5 | 10 | 5 | 14 | 6 | 15 | 12 | 12 | 12 | 12 |  |  |  |
| SPI_DATA0_1 | SPI-DATA | BUS | 7 | 5 | 5 | 10 | 5 | 14 | 6 | 15 | 12 | 12 | 12 | 12 |  |  |  |
| SPI_DATA0_1 | SPI-DATA | BUS | 8 | 4.75 | 5 | 10 | 5 | 14 | 6 | 15 | 12 | 12 | 12 | 12 |  |  |  |
| SPI_DATA0_1_R | SPI-DATA | BUS | 1 | 4.75 | 5 | 10 | 5 | 14 | 6 | 15 | 12 | 12 | 12 | 12 |  |  |  |
| SPI_DATA0_1_R | SPI-DATA | BUS | 2 | 5 | 5 | 10 | 5 | 14 | 6 | 15 | 12 | 12 | 12 | 12 |  |  |  |
| SPI_DATA0_1_R | SPI-DATA | BUS | 3 | 5 | 5 | 10 | 5 | 14 | 6 | 15 | 12 | 12 | 12 | 12 |  |  |  |
| SPI_DATA0_1_R | SPI-DATA | BUS | 4 | 5 | 5 | 10 | 5 | 14 | 6 | 15 | 12 | 12 | 12 | 12 |  |  |  |
| SPI_DATA0_1_R | SPI-DATA | BUS | 5 | 5 | 5 | 10 | 5 | 14 | 6 | 15 | 12 | 12 | 12 | 12 |  |  |  |
| SPI_DATA0_1_R | SPI-DATA | BUS | 6 | 5 | 5 | 10 | 5 | 14 | 6 | 15 | 12 | 12 | 12 | 12 |  |  |  |
| SPI_DATA0_1_R | SPI-DATA | BUS | 7 | 5 | 5 | 10 | 5 | 14 | 6 | 15 | 12 | 12 | 12 | 12 |  |  |  |
| SPI_DATA0_1_R | SPI-DATA | BUS | 8 | 4.75 | 5 | 10 | 5 | 14 | 6 | 15 | 12 | 12 | 12 | 12 |  |  |  |
| SPI_DATA0_2 | SPI-DATA | BUS | 1 | 4.75 | 5 | 10 | 5 | 14 | 6 | 15 | 12 | 12 | 12 | 12 |  |  |  |
| SPI_DATA0_2 | SPI-DATA | BUS | 2 | 5 | 5 | 10 | 5 | 14 | 6 | 15 | 12 | 12 | 12 | 12 |  |  |  |
| SPI_DATA0_2 | SPI-DATA | BUS | 3 | 5 | 5 | 10 | 5 | 14 | 6 | 15 | 12 | 12 | 12 | 12 |  |  |  |
| SPI_DATA0_2 | SPI-DATA | BUS | 4 | 5 | 5 | 10 | 5 | 14 | 6 | 15 | 12 | 12 | 12 | 12 |  |  |  |
| SPI_DATA0_2 | SPI-DATA | BUS | 5 | 5 | 5 | 10 | 5 | 14 | 6 | 15 | 12 | 12 | 12 | 12 |  |  |  |
| SPI_DATA0_2 | SPI-DATA | BUS | 6 | 5 | 5 | 10 | 5 | 14 | 6 | 15 | 12 | 12 | 12 | 12 |  |  |  |
| SPI_DATA0_2 | SPI-DATA | BUS | 7 | 5 | 5 | 10 | 5 | 14 | 6 | 15 | 12 | 12 | 12 | 12 |  |  |  |
| SPI_DATA0_2 | SPI-DATA | BUS | 8 | 4.75 | 5 | 10 | 5 | 14 | 6 | 15 | 12 | 12 | 12 | 12 |  |  |  |
| SPI_DATA0_2_R | SPI-DATA | BUS | 1 | 4.75 | 5 | 10 | 5 | 14 | 6 | 15 | 12 | 12 | 12 | 12 |  |  |  |
| SPI_DATA0_2_R | SPI-DATA | BUS | 2 | 5 | 5 | 10 | 5 | 14 | 6 | 15 | 12 | 12 | 12 | 12 |  |  |  |
| SPI_DATA0_2_R | SPI-DATA | BUS | 3 | 5 | 5 | 10 | 5 | 14 | 6 | 15 | 12 | 12 | 12 | 12 |  |  |  |
| SPI_DATA0_2_R | SPI-DATA | BUS | 4 | 5 | 5 | 10 | 5 | 14 | 6 | 15 | 12 | 12 | 12 | 12 |  |  |  |
| SPI_DATA0_2_R | SPI-DATA | BUS | 5 | 5 | 5 | 10 | 5 | 14 | 6 | 15 | 12 | 12 | 12 | 12 |  |  |  |
| SPI_DATA0_2_R | SPI-DATA | BUS | 6 | 5 | 5 | 10 | 5 | 14 | 6 | 15 | 12 | 12 | 12 | 12 |  |  |  |
| SPI_DATA0_2_R | SPI-DATA | BUS | 7 | 5 | 5 | 10 | 5 | 14 | 6 | 15 | 12 | 12 | 12 | 12 |  |  |  |
| SPI_DATA0_2_R | SPI-DATA | BUS | 8 | 4.75 | 5 | 10 | 5 | 14 | 6 | 15 | 12 | 12 | 12 | 12 |  |  |  |
| SPI_DATA0_3 | SPI-DATA | BUS | 1 | 4.75 | 5 | 10 | 5 | 14 | 6 | 15 | 12 | 12 | 12 | 12 |  |  |  |
| SPI_DATA0_3 | SPI-DATA | BUS | 2 | 5 | 5 | 10 | 5 | 14 | 6 | 15 | 12 | 12 | 12 | 12 |  |  |  |
| SPI_DATA0_3 | SPI-DATA | BUS | 3 | 5 | 5 | 10 | 5 | 14 | 6 | 15 | 12 | 12 | 12 | 12 |  |  |  |
| SPI_DATA0_3 | SPI-DATA | BUS | 4 | 5 | 5 | 10 | 5 | 14 | 6 | 15 | 12 | 12 | 12 | 12 |  |  |  |
| SPI_DATA0_3 | SPI-DATA | BUS | 5 | 5 | 5 | 10 | 5 | 14 | 6 | 15 | 12 | 12 | 12 | 12 |  |  |  |
| SPI_DATA0_3 | SPI-DATA | BUS | 6 | 5 | 5 | 10 | 5 | 14 | 6 | 15 | 12 | 12 | 12 | 12 |  |  |  |
| SPI_DATA0_3 | SPI-DATA | BUS | 7 | 5 | 5 | 10 | 5 | 14 | 6 | 15 | 12 | 12 | 12 | 12 |  |  |  |
| SPI_DATA0_3 | SPI-DATA | BUS | 8 | 4.75 | 5 | 10 | 5 | 14 | 6 | 15 | 12 | 12 | 12 | 12 |  |  |  |
| SPI_DATA0_3_R | SPI-DATA | BUS | 1 | 4.75 | 5 | 10 | 5 | 14 | 6 | 15 | 12 | 12 | 12 | 12 |  |  |  |
| SPI_DATA0_3_R | SPI-DATA | BUS | 2 | 5 | 5 | 10 | 5 | 14 | 6 | 15 | 12 | 12 | 12 | 12 |  |  |  |
| SPI_DATA0_3_R | SPI-DATA | BUS | 3 | 5 | 5 | 10 | 5 | 14 | 6 | 15 | 12 | 12 | 12 | 12 |  |  |  |
| SPI_DATA0_3_R | SPI-DATA | BUS | 4 | 5 | 5 | 10 | 5 | 14 | 6 | 15 | 12 | 12 | 12 | 12 |  |  |  |
| SPI_DATA0_3_R | SPI-DATA | BUS | 5 | 5 | 5 | 10 | 5 | 14 | 6 | 15 | 12 | 12 | 12 | 12 |  |  |  |
| SPI_DATA0_3_R | SPI-DATA | BUS | 6 | 5 | 5 | 10 | 5 | 14 | 6 | 15 | 12 | 12 | 12 | 12 |  |  |  |
| SPI_DATA0_3_R | SPI-DATA | BUS | 7 | 5 | 5 | 10 | 5 | 14 | 6 | 15 | 12 | 12 | 12 | 12 |  |  |  |
| SPI_DATA0_3_R | SPI-DATA | BUS | 8 | 4.75 | 5 | 10 | 5 | 14 | 6 | 15 | 12 | 12 | 12 | 12 |  |  |  |
| SPICS0_N | SPI-DATA | BUS | 1 | 4.75 | 5 | 10 | 5 | 14 | 6 | 15 | 12 | 12 | 12 | 12 |  |  |  |
| SPICS0_N | SPI-DATA | BUS | 2 | 5 | 5 | 10 | 5 | 14 | 6 | 15 | 12 | 12 | 12 | 12 |  |  |  |
| SPICS0_N | SPI-DATA | BUS | 3 | 5 | 5 | 10 | 5 | 14 | 6 | 15 | 12 | 12 | 12 | 12 |  |  |  |
| SPICS0_N | SPI-DATA | BUS | 4 | 5 | 5 | 10 | 5 | 14 | 6 | 15 | 12 | 12 | 12 | 12 |  |  |  |
| SPICS0_N | SPI-DATA | BUS | 5 | 5 | 5 | 10 | 5 | 14 | 6 | 15 | 12 | 12 | 12 | 12 |  |  |  |
| SPICS0_N | SPI-DATA | BUS | 6 | 5 | 5 | 10 | 5 | 14 | 6 | 15 | 12 | 12 | 12 | 12 |  |  |  |
| SPICS0_N | SPI-DATA | BUS | 7 | 5 | 5 | 10 | 5 | 14 | 6 | 15 | 12 | 12 | 12 | 12 |  |  |  |
| SPICS0_N | SPI-DATA | BUS | 8 | 4.75 | 5 | 10 | 5 | 14 | 6 | 15 | 12 | 12 | 12 | 12 |  |  |  |
| SPICS0_N_R | SPI-DATA | BUS | 1 | 4.75 | 5 | 10 | 5 | 14 | 6 | 15 | 12 | 12 | 12 | 12 |  |  |  |
| SPICS0_N_R | SPI-DATA | BUS | 2 | 5 | 5 | 10 | 5 | 14 | 6 | 15 | 12 | 12 | 12 | 12 |  |  |  |
| SPICS0_N_R | SPI-DATA | BUS | 3 | 5 | 5 | 10 | 5 | 14 | 6 | 15 | 12 | 12 | 12 | 12 |  |  |  |
| SPICS0_N_R | SPI-DATA | BUS | 4 | 5 | 5 | 10 | 5 | 14 | 6 | 15 | 12 | 12 | 12 | 12 |  |  |  |
| SPICS0_N_R | SPI-DATA | BUS | 5 | 5 | 5 | 10 | 5 | 14 | 6 | 15 | 12 | 12 | 12 | 12 |  |  |  |
| SPICS0_N_R | SPI-DATA | BUS | 6 | 5 | 5 | 10 | 5 | 14 | 6 | 15 | 12 | 12 | 12 | 12 |  |  |  |
| SPICS0_N_R | SPI-DATA | BUS | 7 | 5 | 5 | 10 | 5 | 14 | 6 | 15 | 12 | 12 | 12 | 12 |  |  |  |
| SPICS0_N_R | SPI-DATA | BUS | 8 | 4.75 | 5 | 10 | 5 | 14 | 6 | 15 | 12 | 12 | 12 | 12 |  |  |  |
| SPIDI | SPI-DATA | BUS | 1 | 4.75 | 5 | 10 | 5 | 14 | 6 | 15 | 12 | 12 | 12 | 12 |  |  |  |
| SPIDI | SPI-DATA | BUS | 2 | 5 | 5 | 10 | 5 | 14 | 6 | 15 | 12 | 12 | 12 | 12 |  |  |  |
| SPIDI | SPI-DATA | BUS | 3 | 5 | 5 | 10 | 5 | 14 | 6 | 15 | 12 | 12 | 12 | 12 |  |  |  |
| SPIDI | SPI-DATA | BUS | 4 | 5 | 5 | 10 | 5 | 14 | 6 | 15 | 12 | 12 | 12 | 12 |  |  |  |
| SPIDI | SPI-DATA | BUS | 5 | 5 | 5 | 10 | 5 | 14 | 6 | 15 | 12 | 12 | 12 | 12 |  |  |  |
| SPIDI | SPI-DATA | BUS | 6 | 5 | 5 | 10 | 5 | 14 | 6 | 15 | 12 | 12 | 12 | 12 |  |  |  |
| SPIDI | SPI-DATA | BUS | 7 | 5 | 5 | 10 | 5 | 14 | 6 | 15 | 12 | 12 | 12 | 12 |  |  |  |
| SPIDI | SPI-DATA | BUS | 8 | 4.75 | 5 | 10 | 5 | 14 | 6 | 15 | 12 | 12 | 12 | 12 |  |  |  |
| SPIDI_R | SPI-DATA | BUS | 1 | 4.75 | 5 | 10 | 5 | 14 | 6 | 15 | 12 | 12 | 12 | 12 |  |  |  |
| SPIDI_R | SPI-DATA | BUS | 2 | 5 | 5 | 10 | 5 | 14 | 6 | 15 | 12 | 12 | 12 | 12 |  |  |  |
| SPIDI_R | SPI-DATA | BUS | 3 | 5 | 5 | 10 | 5 | 14 | 6 | 15 | 12 | 12 | 12 | 12 |  |  |  |
| SPIDI_R | SPI-DATA | BUS | 4 | 5 | 5 | 10 | 5 | 14 | 6 | 15 | 12 | 12 | 12 | 12 |  |  |  |
| SPIDI_R | SPI-DATA | BUS | 5 | 5 | 5 | 10 | 5 | 14 | 6 | 15 | 12 | 12 | 12 | 12 |  |  |  |
| SPIDI_R | SPI-DATA | BUS | 6 | 5 | 5 | 10 | 5 | 14 | 6 | 15 | 12 | 12 | 12 | 12 |  |  |  |
| SPIDI_R | SPI-DATA | BUS | 7 | 5 | 5 | 10 | 5 | 14 | 6 | 15 | 12 | 12 | 12 | 12 |  |  |  |
| SPIDI_R | SPI-DATA | BUS | 8 | 4.75 | 5 | 10 | 5 | 14 | 6 | 15 | 12 | 12 | 12 | 12 |  |  |  |
| SPIDO | SPI-DATA | BUS | 1 | 4.75 | 5 | 10 | 5 | 14 | 6 | 15 | 12 | 12 | 12 | 12 |  |  |  |
| SPIDO | SPI-DATA | BUS | 2 | 5 | 5 | 10 | 5 | 14 | 6 | 15 | 12 | 12 | 12 | 12 |  |  |  |
| SPIDO | SPI-DATA | BUS | 3 | 5 | 5 | 10 | 5 | 14 | 6 | 15 | 12 | 12 | 12 | 12 |  |  |  |
| SPIDO | SPI-DATA | BUS | 4 | 5 | 5 | 10 | 5 | 14 | 6 | 15 | 12 | 12 | 12 | 12 |  |  |  |
| SPIDO | SPI-DATA | BUS | 5 | 5 | 5 | 10 | 5 | 14 | 6 | 15 | 12 | 12 | 12 | 12 |  |  |  |
| SPIDO | SPI-DATA | BUS | 6 | 5 | 5 | 10 | 5 | 14 | 6 | 15 | 12 | 12 | 12 | 12 |  |  |  |
| SPIDO | SPI-DATA | BUS | 7 | 5 | 5 | 10 | 5 | 14 | 6 | 15 | 12 | 12 | 12 | 12 |  |  |  |
| SPIDO | SPI-DATA | BUS | 8 | 4.75 | 5 | 10 | 5 | 14 | 6 | 15 | 12 | 12 | 12 | 12 |  |  |  |
| SPIDO_R | SPI-DATA | BUS | 1 | 4.75 | 5 | 10 | 5 | 14 | 6 | 15 | 12 | 12 | 12 | 12 |  |  |  |
| SPIDO_R | SPI-DATA | BUS | 2 | 5 | 5 | 10 | 5 | 14 | 6 | 15 | 12 | 12 | 12 | 12 |  |  |  |
| SPIDO_R | SPI-DATA | BUS | 3 | 5 | 5 | 10 | 5 | 14 | 6 | 15 | 12 | 12 | 12 | 12 |  |  |  |
| SPIDO_R | SPI-DATA | BUS | 4 | 5 | 5 | 10 | 5 | 14 | 6 | 15 | 12 | 12 | 12 | 12 |  |  |  |
| SPIDO_R | SPI-DATA | BUS | 5 | 5 | 5 | 10 | 5 | 14 | 6 | 15 | 12 | 12 | 12 | 12 |  |  |  |
| SPIDO_R | SPI-DATA | BUS | 6 | 5 | 5 | 10 | 5 | 14 | 6 | 15 | 12 | 12 | 12 | 12 |  |  |  |
| SPIDO_R | SPI-DATA | BUS | 7 | 5 | 5 | 10 | 5 | 14 | 6 | 15 | 12 | 12 | 12 | 12 |  |  |  |
| SPIDO_R | SPI-DATA | BUS | 8 | 4.75 | 5 | 10 | 5 | 14 | 6 | 15 | 12 | 12 | 12 | 12 |  |  |  |
| TEMP_SENSOR_C | THERMAL | BUS | 1 | 6 | 5 | 10 | 5 | 14 | 6 | 6 | 12 | 12 | 12 | 12 |  |  |  |
| TEMP_SENSOR_DXN | THERMAL | BUS | 1 | 6 | 5 | 10 | 5 | 14 | 6 | 6 | 12 | 12 | 12 | 12 |  |  |  |
| TEMP_SENSOR_DXN_BJT | THERMAL | BUS | 1 | 6 | 5 | 10 | 5 | 14 | 6 | 6 | 12 | 12 | 12 | 12 |  |  |  |
| TEMP_SENSOR_DXP | THERMAL | BUS | 1 | 6 | 5 | 10 | 5 | 14 | 6 | 6 | 12 | 12 | 12 | 12 |  |  |  |
| TEMP_SENSOR_DXP_R | THERMAL | BUS | 1 | 6 | 5 | 10 | 5 | 14 | 6 | 6 | 12 | 12 | 12 | 12 |  |  |  |
| THERM_BASE | THERMAL | BUS | 1 | 6 | 5 | 10 | 5 | 14 | 6 | 6 | 12 | 12 | 12 | 12 |  |  |  |
| THERM_EMIT | THERMAL | BUS | 1 | 6 | 5 | 10 | 5 | 14 | 6 | 6 | 12 | 12 | 12 | 12 |  |  |  |
| BMC_R_RXD5 | UART | BUS | 1 | 4.75 | 5 | 10 | 5 | 14 | 6 | 15 | 12 | 12 | 12 | 12 |  |  |  |
| BMC_R_RXD5 | UART | BUS | 2 | 5 | 5 | 10 | 5 | 14 | 6 | 15 | 12 | 12 | 12 | 12 |  |  |  |
| BMC_R_RXD5 | UART | BUS | 3 | 5 | 5 | 10 | 5 | 14 | 6 | 15 | 12 | 12 | 12 | 12 |  |  |  |
| BMC_R_RXD5 | UART | BUS | 4 | 5 | 5 | 10 | 5 | 14 | 6 | 15 | 12 | 12 | 12 | 12 |  |  |  |
| BMC_R_RXD5 | UART | BUS | 5 | 5 | 5 | 10 | 5 | 14 | 6 | 15 | 12 | 12 | 12 | 12 |  |  |  |
| BMC_R_RXD5 | UART | BUS | 6 | 5 | 5 | 10 | 5 | 14 | 6 | 15 | 12 | 12 | 12 | 12 |  |  |  |
| BMC_R_RXD5 | UART | BUS | 7 | 5 | 5 | 10 | 5 | 14 | 6 | 15 | 12 | 12 | 12 | 12 |  |  |  |
| BMC_R_RXD5 | UART | BUS | 8 | 4.75 | 5 | 10 | 5 | 14 | 6 | 15 | 12 | 12 | 12 | 12 |  |  |  |
| BMC_R_TXD5 | UART | BUS | 1 | 4.75 | 5 | 10 | 5 | 14 | 6 | 15 | 12 | 12 | 12 | 12 |  |  |  |
| BMC_R_TXD5 | UART | BUS | 2 | 5 | 5 | 10 | 5 | 14 | 6 | 15 | 12 | 12 | 12 | 12 |  |  |  |
| BMC_R_TXD5 | UART | BUS | 3 | 5 | 5 | 10 | 5 | 14 | 6 | 15 | 12 | 12 | 12 | 12 |  |  |  |
| BMC_R_TXD5 | UART | BUS | 4 | 5 | 5 | 10 | 5 | 14 | 6 | 15 | 12 | 12 | 12 | 12 |  |  |  |
| BMC_R_TXD5 | UART | BUS | 5 | 5 | 5 | 10 | 5 | 14 | 6 | 15 | 12 | 12 | 12 | 12 |  |  |  |
| BMC_R_TXD5 | UART | BUS | 6 | 5 | 5 | 10 | 5 | 14 | 6 | 15 | 12 | 12 | 12 | 12 |  |  |  |
| BMC_R_TXD5 | UART | BUS | 7 | 5 | 5 | 10 | 5 | 14 | 6 | 15 | 12 | 12 | 12 | 12 |  |  |  |
| BMC_R_TXD5 | UART | BUS | 8 | 4.75 | 5 | 10 | 5 | 14 | 6 | 15 | 12 | 12 | 12 | 12 |  |  |  |
| BMC_RXD5 | UART | BUS | 1 | 4.75 | 5 | 10 | 5 | 14 | 6 | 15 | 12 | 12 | 12 | 12 |  |  |  |
| BMC_RXD5 | UART | BUS | 2 | 5 | 5 | 10 | 5 | 14 | 6 | 15 | 12 | 12 | 12 | 12 |  |  |  |
| BMC_RXD5 | UART | BUS | 3 | 5 | 5 | 10 | 5 | 14 | 6 | 15 | 12 | 12 | 12 | 12 |  |  |  |
| BMC_RXD5 | UART | BUS | 4 | 5 | 5 | 10 | 5 | 14 | 6 | 15 | 12 | 12 | 12 | 12 |  |  |  |
| BMC_RXD5 | UART | BUS | 5 | 5 | 5 | 10 | 5 | 14 | 6 | 15 | 12 | 12 | 12 | 12 |  |  |  |
| BMC_RXD5 | UART | BUS | 6 | 5 | 5 | 10 | 5 | 14 | 6 | 15 | 12 | 12 | 12 | 12 |  |  |  |
| BMC_RXD5 | UART | BUS | 7 | 5 | 5 | 10 | 5 | 14 | 6 | 15 | 12 | 12 | 12 | 12 |  |  |  |
| BMC_RXD5 | UART | BUS | 8 | 4.75 | 5 | 10 | 5 | 14 | 6 | 15 | 12 | 12 | 12 | 12 |  |  |  |
| BMC_RXD5_R | UART | BUS | 1 | 4.75 | 5 | 10 | 5 | 14 | 6 | 15 | 12 | 12 | 12 | 12 |  |  |  |
| BMC_RXD5_R | UART | BUS | 2 | 5 | 5 | 10 | 5 | 14 | 6 | 15 | 12 | 12 | 12 | 12 |  |  |  |
| BMC_RXD5_R | UART | BUS | 3 | 5 | 5 | 10 | 5 | 14 | 6 | 15 | 12 | 12 | 12 | 12 |  |  |  |
| BMC_RXD5_R | UART | BUS | 4 | 5 | 5 | 10 | 5 | 14 | 6 | 15 | 12 | 12 | 12 | 12 |  |  |  |
| BMC_RXD5_R | UART | BUS | 5 | 5 | 5 | 10 | 5 | 14 | 6 | 15 | 12 | 12 | 12 | 12 |  |  |  |
| BMC_RXD5_R | UART | BUS | 6 | 5 | 5 | 10 | 5 | 14 | 6 | 15 | 12 | 12 | 12 | 12 |  |  |  |
| BMC_RXD5_R | UART | BUS | 7 | 5 | 5 | 10 | 5 | 14 | 6 | 15 | 12 | 12 | 12 | 12 |  |  |  |
| BMC_RXD5_R | UART | BUS | 8 | 4.75 | 5 | 10 | 5 | 14 | 6 | 15 | 12 | 12 | 12 | 12 |  |  |  |
| BMC_TXD5 | UART | BUS | 1 | 4.75 | 5 | 10 | 5 | 14 | 6 | 15 | 12 | 12 | 12 | 12 |  |  |  |
| BMC_TXD5 | UART | BUS | 2 | 5 | 5 | 10 | 5 | 14 | 6 | 15 | 12 | 12 | 12 | 12 |  |  |  |
| BMC_TXD5 | UART | BUS | 3 | 5 | 5 | 10 | 5 | 14 | 6 | 15 | 12 | 12 | 12 | 12 |  |  |  |
| BMC_TXD5 | UART | BUS | 4 | 5 | 5 | 10 | 5 | 14 | 6 | 15 | 12 | 12 | 12 | 12 |  |  |  |
| BMC_TXD5 | UART | BUS | 5 | 5 | 5 | 10 | 5 | 14 | 6 | 15 | 12 | 12 | 12 | 12 |  |  |  |
| BMC_TXD5 | UART | BUS | 6 | 5 | 5 | 10 | 5 | 14 | 6 | 15 | 12 | 12 | 12 | 12 |  |  |  |
| BMC_TXD5 | UART | BUS | 7 | 5 | 5 | 10 | 5 | 14 | 6 | 15 | 12 | 12 | 12 | 12 |  |  |  |
| BMC_TXD5 | UART | BUS | 8 | 4.75 | 5 | 10 | 5 | 14 | 6 | 15 | 12 | 12 | 12 | 12 |  |  |  |
| BMC_TXD5_R | UART | BUS | 1 | 4.75 | 5 | 10 | 5 | 14 | 6 | 15 | 12 | 12 | 12 | 12 |  |  |  |
| BMC_TXD5_R | UART | BUS | 2 | 5 | 5 | 10 | 5 | 14 | 6 | 15 | 12 | 12 | 12 | 12 |  |  |  |
| BMC_TXD5_R | UART | BUS | 3 | 5 | 5 | 10 | 5 | 14 | 6 | 15 | 12 | 12 | 12 | 12 |  |  |  |
| BMC_TXD5_R | UART | BUS | 4 | 5 | 5 | 10 | 5 | 14 | 6 | 15 | 12 | 12 | 12 | 12 |  |  |  |
| BMC_TXD5_R | UART | BUS | 5 | 5 | 5 | 10 | 5 | 14 | 6 | 15 | 12 | 12 | 12 | 12 |  |  |  |
| BMC_TXD5_R | UART | BUS | 6 | 5 | 5 | 10 | 5 | 14 | 6 | 15 | 12 | 12 | 12 | 12 |  |  |  |
| BMC_TXD5_R | UART | BUS | 7 | 5 | 5 | 10 | 5 | 14 | 6 | 15 | 12 | 12 | 12 | 12 |  |  |  |
| BMC_TXD5_R | UART | BUS | 8 | 4.75 | 5 | 10 | 5 | 14 | 6 | 15 | 12 | 12 | 12 | 12 |  |  |  |
| DEBUG_CARD_RX | UART | BUS | 1 | 4.75 | 5 | 10 | 5 | 14 | 6 | 15 | 12 | 12 | 12 | 12 |  |  |  |
| DEBUG_CARD_RX | UART | BUS | 2 | 5 | 5 | 10 | 5 | 14 | 6 | 15 | 12 | 12 | 12 | 12 |  |  |  |
| DEBUG_CARD_RX | UART | BUS | 3 | 5 | 5 | 10 | 5 | 14 | 6 | 15 | 12 | 12 | 12 | 12 |  |  |  |
| DEBUG_CARD_RX | UART | BUS | 4 | 5 | 5 | 10 | 5 | 14 | 6 | 15 | 12 | 12 | 12 | 12 |  |  |  |
| DEBUG_CARD_RX | UART | BUS | 5 | 5 | 5 | 10 | 5 | 14 | 6 | 15 | 12 | 12 | 12 | 12 |  |  |  |
| DEBUG_CARD_RX | UART | BUS | 6 | 5 | 5 | 10 | 5 | 14 | 6 | 15 | 12 | 12 | 12 | 12 |  |  |  |
| DEBUG_CARD_RX | UART | BUS | 7 | 5 | 5 | 10 | 5 | 14 | 6 | 15 | 12 | 12 | 12 | 12 |  |  |  |
| DEBUG_CARD_RX | UART | BUS | 8 | 4.75 | 5 | 10 | 5 | 14 | 6 | 15 | 12 | 12 | 12 | 12 |  |  |  |
| DEBUG_CARD_TX | UART | BUS | 1 | 4.75 | 5 | 10 | 5 | 14 | 6 | 15 | 12 | 12 | 12 | 12 |  |  |  |
| DEBUG_CARD_TX | UART | BUS | 2 | 5 | 5 | 10 | 5 | 14 | 6 | 15 | 12 | 12 | 12 | 12 |  |  |  |
| DEBUG_CARD_TX | UART | BUS | 3 | 5 | 5 | 10 | 5 | 14 | 6 | 15 | 12 | 12 | 12 | 12 |  |  |  |
| DEBUG_CARD_TX | UART | BUS | 4 | 5 | 5 | 10 | 5 | 14 | 6 | 15 | 12 | 12 | 12 | 12 |  |  |  |
| DEBUG_CARD_TX | UART | BUS | 5 | 5 | 5 | 10 | 5 | 14 | 6 | 15 | 12 | 12 | 12 | 12 |  |  |  |
| DEBUG_CARD_TX | UART | BUS | 6 | 5 | 5 | 10 | 5 | 14 | 6 | 15 | 12 | 12 | 12 | 12 |  |  |  |
| DEBUG_CARD_TX | UART | BUS | 7 | 5 | 5 | 10 | 5 | 14 | 6 | 15 | 12 | 12 | 12 | 12 |  |  |  |
| DEBUG_CARD_TX | UART | BUS | 8 | 4.75 | 5 | 10 | 5 | 14 | 6 | 15 | 12 | 12 | 12 | 12 |  |  |  |
| EXP_SMART_RX | UART | BUS | 1 | 4.75 | 5 | 10 | 5 | 14 | 6 | 15 | 12 | 12 | 12 | 12 |  |  |  |
| EXP_SMART_RX | UART | BUS | 2 | 5 | 5 | 10 | 5 | 14 | 6 | 15 | 12 | 12 | 12 | 12 |  |  |  |
| EXP_SMART_RX | UART | BUS | 3 | 5 | 5 | 10 | 5 | 14 | 6 | 15 | 12 | 12 | 12 | 12 |  |  |  |
| EXP_SMART_RX | UART | BUS | 4 | 5 | 5 | 10 | 5 | 14 | 6 | 15 | 12 | 12 | 12 | 12 |  |  |  |
| EXP_SMART_RX | UART | BUS | 5 | 5 | 5 | 10 | 5 | 14 | 6 | 15 | 12 | 12 | 12 | 12 |  |  |  |
| EXP_SMART_RX | UART | BUS | 6 | 5 | 5 | 10 | 5 | 14 | 6 | 15 | 12 | 12 | 12 | 12 |  |  |  |
| EXP_SMART_RX | UART | BUS | 7 | 5 | 5 | 10 | 5 | 14 | 6 | 15 | 12 | 12 | 12 | 12 |  |  |  |
| EXP_SMART_RX | UART | BUS | 8 | 4.75 | 5 | 10 | 5 | 14 | 6 | 15 | 12 | 12 | 12 | 12 |  |  |  |
| EXP_SMART_RX_R | UART | BUS | 1 | 4.75 | 5 | 10 | 5 | 14 | 6 | 15 | 12 | 12 | 12 | 12 |  |  |  |
| EXP_SMART_RX_R | UART | BUS | 2 | 5 | 5 | 10 | 5 | 14 | 6 | 15 | 12 | 12 | 12 | 12 |  |  |  |
| EXP_SMART_RX_R | UART | BUS | 3 | 5 | 5 | 10 | 5 | 14 | 6 | 15 | 12 | 12 | 12 | 12 |  |  |  |
| EXP_SMART_RX_R | UART | BUS | 4 | 5 | 5 | 10 | 5 | 14 | 6 | 15 | 12 | 12 | 12 | 12 |  |  |  |
| EXP_SMART_RX_R | UART | BUS | 5 | 5 | 5 | 10 | 5 | 14 | 6 | 15 | 12 | 12 | 12 | 12 |  |  |  |
| EXP_SMART_RX_R | UART | BUS | 6 | 5 | 5 | 10 | 5 | 14 | 6 | 15 | 12 | 12 | 12 | 12 |  |  |  |
| EXP_SMART_RX_R | UART | BUS | 7 | 5 | 5 | 10 | 5 | 14 | 6 | 15 | 12 | 12 | 12 | 12 |  |  |  |
| EXP_SMART_RX_R | UART | BUS | 8 | 4.75 | 5 | 10 | 5 | 14 | 6 | 15 | 12 | 12 | 12 | 12 |  |  |  |
| EXP_SMART_TX | UART | BUS | 1 | 4.75 | 5 | 10 | 5 | 14 | 6 | 15 | 12 | 12 | 12 | 12 |  |  |  |
| EXP_SMART_TX | UART | BUS | 2 | 5 | 5 | 10 | 5 | 14 | 6 | 15 | 12 | 12 | 12 | 12 |  |  |  |
| EXP_SMART_TX | UART | BUS | 3 | 5 | 5 | 10 | 5 | 14 | 6 | 15 | 12 | 12 | 12 | 12 |  |  |  |
| EXP_SMART_TX | UART | BUS | 4 | 5 | 5 | 10 | 5 | 14 | 6 | 15 | 12 | 12 | 12 | 12 |  |  |  |
| EXP_SMART_TX | UART | BUS | 5 | 5 | 5 | 10 | 5 | 14 | 6 | 15 | 12 | 12 | 12 | 12 |  |  |  |
| EXP_SMART_TX | UART | BUS | 6 | 5 | 5 | 10 | 5 | 14 | 6 | 15 | 12 | 12 | 12 | 12 |  |  |  |
| EXP_SMART_TX | UART | BUS | 7 | 5 | 5 | 10 | 5 | 14 | 6 | 15 | 12 | 12 | 12 | 12 |  |  |  |
| EXP_SMART_TX | UART | BUS | 8 | 4.75 | 5 | 10 | 5 | 14 | 6 | 15 | 12 | 12 | 12 | 12 |  |  |  |
| EXP_SMART_TX_R | UART | BUS | 1 | 4.75 | 5 | 10 | 5 | 14 | 6 | 15 | 12 | 12 | 12 | 12 |  |  |  |
| EXP_SMART_TX_R | UART | BUS | 2 | 5 | 5 | 10 | 5 | 14 | 6 | 15 | 12 | 12 | 12 | 12 |  |  |  |
| EXP_SMART_TX_R | UART | BUS | 3 | 5 | 5 | 10 | 5 | 14 | 6 | 15 | 12 | 12 | 12 | 12 |  |  |  |
| EXP_SMART_TX_R | UART | BUS | 4 | 5 | 5 | 10 | 5 | 14 | 6 | 15 | 12 | 12 | 12 | 12 |  |  |  |
| EXP_SMART_TX_R | UART | BUS | 5 | 5 | 5 | 10 | 5 | 14 | 6 | 15 | 12 | 12 | 12 | 12 |  |  |  |
| EXP_SMART_TX_R | UART | BUS | 6 | 5 | 5 | 10 | 5 | 14 | 6 | 15 | 12 | 12 | 12 | 12 |  |  |  |
| EXP_SMART_TX_R | UART | BUS | 7 | 5 | 5 | 10 | 5 | 14 | 6 | 15 | 12 | 12 | 12 | 12 |  |  |  |
| EXP_SMART_TX_R | UART | BUS | 8 | 4.75 | 5 | 10 | 5 | 14 | 6 | 15 | 12 | 12 | 12 | 12 |  |  |  |
| EXP_UART_RX_R | UART | BUS | 1 | 4.75 | 5 | 10 | 5 | 14 | 6 | 15 | 12 | 12 | 12 | 12 |  |  |  |
| EXP_UART_RX_R | UART | BUS | 2 | 5 | 5 | 10 | 5 | 14 | 6 | 15 | 12 | 12 | 12 | 12 |  |  |  |
| EXP_UART_RX_R | UART | BUS | 3 | 5 | 5 | 10 | 5 | 14 | 6 | 15 | 12 | 12 | 12 | 12 |  |  |  |
| EXP_UART_RX_R | UART | BUS | 4 | 5 | 5 | 10 | 5 | 14 | 6 | 15 | 12 | 12 | 12 | 12 |  |  |  |
| EXP_UART_RX_R | UART | BUS | 5 | 5 | 5 | 10 | 5 | 14 | 6 | 15 | 12 | 12 | 12 | 12 |  |  |  |
| EXP_UART_RX_R | UART | BUS | 6 | 5 | 5 | 10 | 5 | 14 | 6 | 15 | 12 | 12 | 12 | 12 |  |  |  |
| EXP_UART_RX_R | UART | BUS | 7 | 5 | 5 | 10 | 5 | 14 | 6 | 15 | 12 | 12 | 12 | 12 |  |  |  |
| EXP_UART_RX_R | UART | BUS | 8 | 4.75 | 5 | 10 | 5 | 14 | 6 | 15 | 12 | 12 | 12 | 12 |  |  |  |
| EXP_UART_TX_R | UART | BUS | 1 | 4.75 | 5 | 10 | 5 | 14 | 6 | 15 | 12 | 12 | 12 | 12 |  |  |  |
| EXP_UART_TX_R | UART | BUS | 2 | 5 | 5 | 10 | 5 | 14 | 6 | 15 | 12 | 12 | 12 | 12 |  |  |  |
| EXP_UART_TX_R | UART | BUS | 3 | 5 | 5 | 10 | 5 | 14 | 6 | 15 | 12 | 12 | 12 | 12 |  |  |  |
| EXP_UART_TX_R | UART | BUS | 4 | 5 | 5 | 10 | 5 | 14 | 6 | 15 | 12 | 12 | 12 | 12 |  |  |  |
| EXP_UART_TX_R | UART | BUS | 5 | 5 | 5 | 10 | 5 | 14 | 6 | 15 | 12 | 12 | 12 | 12 |  |  |  |
| EXP_UART_TX_R | UART | BUS | 6 | 5 | 5 | 10 | 5 | 14 | 6 | 15 | 12 | 12 | 12 | 12 |  |  |  |
| EXP_UART_TX_R | UART | BUS | 7 | 5 | 5 | 10 | 5 | 14 | 6 | 15 | 12 | 12 | 12 | 12 |  |  |  |
| EXP_UART_TX_R | UART | BUS | 8 | 4.75 | 5 | 10 | 5 | 14 | 6 | 15 | 12 | 12 | 12 | 12 |  |  |  |
| MBP_UART_RX | UART | BUS | 1 | 4.75 | 5 | 10 | 5 | 14 | 6 | 15 | 12 | 12 | 12 | 12 |  |  |  |
| MBP_UART_RX | UART | BUS | 2 | 5 | 5 | 10 | 5 | 14 | 6 | 15 | 12 | 12 | 12 | 12 |  |  |  |
| MBP_UART_RX | UART | BUS | 3 | 5 | 5 | 10 | 5 | 14 | 6 | 15 | 12 | 12 | 12 | 12 |  |  |  |
| MBP_UART_RX | UART | BUS | 4 | 5 | 5 | 10 | 5 | 14 | 6 | 15 | 12 | 12 | 12 | 12 |  |  |  |
| MBP_UART_RX | UART | BUS | 5 | 5 | 5 | 10 | 5 | 14 | 6 | 15 | 12 | 12 | 12 | 12 |  |  |  |
| MBP_UART_RX | UART | BUS | 6 | 5 | 5 | 10 | 5 | 14 | 6 | 15 | 12 | 12 | 12 | 12 |  |  |  |
| MBP_UART_RX | UART | BUS | 7 | 5 | 5 | 10 | 5 | 14 | 6 | 15 | 12 | 12 | 12 | 12 |  |  |  |
| MBP_UART_RX | UART | BUS | 8 | 4.75 | 5 | 10 | 5 | 14 | 6 | 15 | 12 | 12 | 12 | 12 |  |  |  |
| MBP_UART_TX | UART | BUS | 1 | 4.75 | 5 | 10 | 5 | 14 | 6 | 15 | 12 | 12 | 12 | 12 |  |  |  |
| MBP_UART_TX | UART | BUS | 2 | 5 | 5 | 10 | 5 | 14 | 6 | 15 | 12 | 12 | 12 | 12 |  |  |  |
| MBP_UART_TX | UART | BUS | 3 | 5 | 5 | 10 | 5 | 14 | 6 | 15 | 12 | 12 | 12 | 12 |  |  |  |
| MBP_UART_TX | UART | BUS | 4 | 5 | 5 | 10 | 5 | 14 | 6 | 15 | 12 | 12 | 12 | 12 |  |  |  |
| MBP_UART_TX | UART | BUS | 5 | 5 | 5 | 10 | 5 | 14 | 6 | 15 | 12 | 12 | 12 | 12 |  |  |  |
| MBP_UART_TX | UART | BUS | 6 | 5 | 5 | 10 | 5 | 14 | 6 | 15 | 12 | 12 | 12 | 12 |  |  |  |
| MBP_UART_TX | UART | BUS | 7 | 5 | 5 | 10 | 5 | 14 | 6 | 15 | 12 | 12 | 12 | 12 |  |  |  |
| MBP_UART_TX | UART | BUS | 8 | 4.75 | 5 | 10 | 5 | 14 | 6 | 15 | 12 | 12 | 12 | 12 |  |  |  |
| BMC_PETXN | BMC_PETX-DIFF1 | PAIR | 1 | 5.38 | 5 | 10 | 5 | 12 | 6 | 33 | 12 | 12 | 12 | 12 | 6.62 | 85 Ohms | TOP=L2:L3=L2/L4:L6=L5/L7:BOTTOM=L7 |
| BMC_PETXN | BMC_PETX-DIFF1 | PAIR | 2 | 5.5 | 5 | 10 | 5 | 12 | 6 | 20 | 12 | 12 | 12 | 12 | 7.5 | 85 Ohms | TOP=L2:L3=L2/L4:L6=L5/L7:BOTTOM=L7 |
| BMC_PETXN | BMC_PETX-DIFF1 | PAIR | 3 | 5.5 | 5 | 10 | 5 | 12 | 6 | 20 | 12 | 12 | 12 | 12 | 7.5 | 85 Ohms | TOP=L2:L3=L2/L4:L6=L5/L7:BOTTOM=L7 |
| BMC_PETXN | BMC_PETX-DIFF1 | PAIR | 4 | 5.5 | 5 | 10 | 5 | 12 | 6 | 20 | 12 | 12 | 12 | 12 | 7.5 | 85 Ohms | TOP=L2:L3=L2/L4:L6=L5/L7:BOTTOM=L7 |
| BMC_PETXN | BMC_PETX-DIFF1 | PAIR | 5 | 5.5 | 5 | 10 | 5 | 12 | 6 | 20 | 12 | 12 | 12 | 12 | 7.5 | 85 Ohms | TOP=L2:L3=L2/L4:L6=L5/L7:BOTTOM=L7 |
| BMC_PETXN | BMC_PETX-DIFF1 | PAIR | 6 | 5.5 | 5 | 10 | 5 | 12 | 6 | 20 | 12 | 12 | 12 | 12 | 7.5 | 85 Ohms | TOP=L2:L3=L2/L4:L6=L5/L7:BOTTOM=L7 |
| BMC_PETXN | BMC_PETX-DIFF1 | PAIR | 7 | 5.5 | 5 | 10 | 5 | 12 | 6 | 20 | 12 | 12 | 12 | 12 | 7.5 | 85 Ohms | TOP=L2:L3=L2/L4:L6=L5/L7:BOTTOM=L7 |
| BMC_PETXN | BMC_PETX-DIFF1 | PAIR | 8 | 5.38 | 5 | 10 | 5 | 12 | 6 | 33 | 12 | 12 | 12 | 12 | 6.62 | 85 Ohms | TOP=L2:L3=L2/L4:L6=L5/L7:BOTTOM=L7 |
| BMC_PETXP | BMC_PETX-DIFF1 | PAIR | 1 | 5.38 | 5 | 10 | 5 | 12 | 6 | 33 | 12 | 12 | 12 | 12 | 6.62 | 85 Ohms | TOP=L2:L3=L2/L4:L6=L5/L7:BOTTOM=L7 |
| BMC_PETXP | BMC_PETX-DIFF1 | PAIR | 2 | 5.5 | 5 | 10 | 5 | 12 | 6 | 20 | 12 | 12 | 12 | 12 | 7.5 | 85 Ohms | TOP=L2:L3=L2/L4:L6=L5/L7:BOTTOM=L7 |
| BMC_PETXP | BMC_PETX-DIFF1 | PAIR | 3 | 5.5 | 5 | 10 | 5 | 12 | 6 | 20 | 12 | 12 | 12 | 12 | 7.5 | 85 Ohms | TOP=L2:L3=L2/L4:L6=L5/L7:BOTTOM=L7 |
| BMC_PETXP | BMC_PETX-DIFF1 | PAIR | 4 | 5.5 | 5 | 10 | 5 | 12 | 6 | 20 | 12 | 12 | 12 | 12 | 7.5 | 85 Ohms | TOP=L2:L3=L2/L4:L6=L5/L7:BOTTOM=L7 |
| BMC_PETXP | BMC_PETX-DIFF1 | PAIR | 5 | 5.5 | 5 | 10 | 5 | 12 | 6 | 20 | 12 | 12 | 12 | 12 | 7.5 | 85 Ohms | TOP=L2:L3=L2/L4:L6=L5/L7:BOTTOM=L7 |
| BMC_PETXP | BMC_PETX-DIFF1 | PAIR | 6 | 5.5 | 5 | 10 | 5 | 12 | 6 | 20 | 12 | 12 | 12 | 12 | 7.5 | 85 Ohms | TOP=L2:L3=L2/L4:L6=L5/L7:BOTTOM=L7 |
| BMC_PETXP | BMC_PETX-DIFF1 | PAIR | 7 | 5.5 | 5 | 10 | 5 | 12 | 6 | 20 | 12 | 12 | 12 | 12 | 7.5 | 85 Ohms | TOP=L2:L3=L2/L4:L6=L5/L7:BOTTOM=L7 |
| BMC_PETXP | BMC_PETX-DIFF1 | PAIR | 8 | 5.38 | 5 | 10 | 5 | 12 | 6 | 33 | 12 | 12 | 12 | 12 | 6.62 | 85 Ohms | TOP=L2:L3=L2/L4:L6=L5/L7:BOTTOM=L7 |
| PCIE_REFCLK_D_N | CLK01-DIFF1 | PAIR | 1 | 5.38 | 5 | 10 | 5 | 12 | 6 | 33 | 12 | 12 | 12 | 12 | 6.62 | 85 Ohms | TOP=L2:L3=L2/L4:L6=L5/L7:BOTTOM=L7 |
| PCIE_REFCLK_D_N | CLK01-DIFF1 | PAIR | 2 | 5.5 | 5 | 10 | 5 | 12 | 6 | 20 | 12 | 12 | 12 | 12 | 7.5 | 85 Ohms | TOP=L2:L3=L2/L4:L6=L5/L7:BOTTOM=L7 |
| PCIE_REFCLK_D_N | CLK01-DIFF1 | PAIR | 3 | 5.5 | 5 | 10 | 5 | 12 | 6 | 20 | 12 | 12 | 12 | 12 | 7.5 | 85 Ohms | TOP=L2:L3=L2/L4:L6=L5/L7:BOTTOM=L7 |
| PCIE_REFCLK_D_N | CLK01-DIFF1 | PAIR | 4 | 5.5 | 5 | 10 | 5 | 12 | 6 | 20 | 12 | 12 | 12 | 12 | 7.5 | 85 Ohms | TOP=L2:L3=L2/L4:L6=L5/L7:BOTTOM=L7 |
| PCIE_REFCLK_D_N | CLK01-DIFF1 | PAIR | 5 | 5.5 | 5 | 10 | 5 | 12 | 6 | 20 | 12 | 12 | 12 | 12 | 7.5 | 85 Ohms | TOP=L2:L3=L2/L4:L6=L5/L7:BOTTOM=L7 |
| PCIE_REFCLK_D_N | CLK01-DIFF1 | PAIR | 6 | 5.5 | 5 | 10 | 5 | 12 | 6 | 20 | 12 | 12 | 12 | 12 | 7.5 | 85 Ohms | TOP=L2:L3=L2/L4:L6=L5/L7:BOTTOM=L7 |
| PCIE_REFCLK_D_N | CLK01-DIFF1 | PAIR | 7 | 5.5 | 5 | 10 | 5 | 12 | 6 | 20 | 12 | 12 | 12 | 12 | 7.5 | 85 Ohms | TOP=L2:L3=L2/L4:L6=L5/L7:BOTTOM=L7 |
| PCIE_REFCLK_D_N | CLK01-DIFF1 | PAIR | 8 | 5.38 | 5 | 10 | 5 | 12 | 6 | 33 | 12 | 12 | 12 | 12 | 6.62 | 85 Ohms | TOP=L2:L3=L2/L4:L6=L5/L7:BOTTOM=L7 |
| PCIE_REFCLK_D_P | CLK01-DIFF1 | PAIR | 1 | 5.38 | 5 | 10 | 5 | 12 | 6 | 33 | 12 | 12 | 12 | 12 | 6.62 | 85 Ohms | TOP=L2:L3=L2/L4:L6=L5/L7:BOTTOM=L7 |
| PCIE_REFCLK_D_P | CLK01-DIFF1 | PAIR | 2 | 5.5 | 5 | 10 | 5 | 12 | 6 | 20 | 12 | 12 | 12 | 12 | 7.5 | 85 Ohms | TOP=L2:L3=L2/L4:L6=L5/L7:BOTTOM=L7 |
| PCIE_REFCLK_D_P | CLK01-DIFF1 | PAIR | 3 | 5.5 | 5 | 10 | 5 | 12 | 6 | 20 | 12 | 12 | 12 | 12 | 7.5 | 85 Ohms | TOP=L2:L3=L2/L4:L6=L5/L7:BOTTOM=L7 |
| PCIE_REFCLK_D_P | CLK01-DIFF1 | PAIR | 4 | 5.5 | 5 | 10 | 5 | 12 | 6 | 20 | 12 | 12 | 12 | 12 | 7.5 | 85 Ohms | TOP=L2:L3=L2/L4:L6=L5/L7:BOTTOM=L7 |
| PCIE_REFCLK_D_P | CLK01-DIFF1 | PAIR | 5 | 5.5 | 5 | 10 | 5 | 12 | 6 | 20 | 12 | 12 | 12 | 12 | 7.5 | 85 Ohms | TOP=L2:L3=L2/L4:L6=L5/L7:BOTTOM=L7 |
| PCIE_REFCLK_D_P | CLK01-DIFF1 | PAIR | 6 | 5.5 | 5 | 10 | 5 | 12 | 6 | 20 | 12 | 12 | 12 | 12 | 7.5 | 85 Ohms | TOP=L2:L3=L2/L4:L6=L5/L7:BOTTOM=L7 |
| PCIE_REFCLK_D_P | CLK01-DIFF1 | PAIR | 7 | 5.5 | 5 | 10 | 5 | 12 | 6 | 20 | 12 | 12 | 12 | 12 | 7.5 | 85 Ohms | TOP=L2:L3=L2/L4:L6=L5/L7:BOTTOM=L7 |
| PCIE_REFCLK_D_P | CLK01-DIFF1 | PAIR | 8 | 5.38 | 5 | 10 | 5 | 12 | 6 | 33 | 12 | 12 | 12 | 12 | 6.62 | 85 Ohms | TOP=L2:L3=L2/L4:L6=L5/L7:BOTTOM=L7 |
| PCIE_REFCLK_D_N_R | CLK02-DIFF1 | PAIR | 1 | 5.38 | 5 | 10 | 5 | 12 | 6 | 33 | 12 | 12 | 12 | 12 | 6.62 | 85 Ohms | TOP=L2:L3=L2/L4:L6=L5/L7:BOTTOM=L7 |
| PCIE_REFCLK_D_N_R | CLK02-DIFF1 | PAIR | 2 | 5.5 | 5 | 10 | 5 | 12 | 6 | 20 | 12 | 12 | 12 | 12 | 7.5 | 85 Ohms | TOP=L2:L3=L2/L4:L6=L5/L7:BOTTOM=L7 |
| PCIE_REFCLK_D_N_R | CLK02-DIFF1 | PAIR | 3 | 5.5 | 5 | 10 | 5 | 12 | 6 | 20 | 12 | 12 | 12 | 12 | 7.5 | 85 Ohms | TOP=L2:L3=L2/L4:L6=L5/L7:BOTTOM=L7 |
| PCIE_REFCLK_D_N_R | CLK02-DIFF1 | PAIR | 4 | 5.5 | 5 | 10 | 5 | 12 | 6 | 20 | 12 | 12 | 12 | 12 | 7.5 | 85 Ohms | TOP=L2:L3=L2/L4:L6=L5/L7:BOTTOM=L7 |
| PCIE_REFCLK_D_N_R | CLK02-DIFF1 | PAIR | 5 | 5.5 | 5 | 10 | 5 | 12 | 6 | 20 | 12 | 12 | 12 | 12 | 7.5 | 85 Ohms | TOP=L2:L3=L2/L4:L6=L5/L7:BOTTOM=L7 |
| PCIE_REFCLK_D_N_R | CLK02-DIFF1 | PAIR | 6 | 5.5 | 5 | 10 | 5 | 12 | 6 | 20 | 12 | 12 | 12 | 12 | 7.5 | 85 Ohms | TOP=L2:L3=L2/L4:L6=L5/L7:BOTTOM=L7 |
| PCIE_REFCLK_D_N_R | CLK02-DIFF1 | PAIR | 7 | 5.5 | 5 | 10 | 5 | 12 | 6 | 20 | 12 | 12 | 12 | 12 | 7.5 | 85 Ohms | TOP=L2:L3=L2/L4:L6=L5/L7:BOTTOM=L7 |
| PCIE_REFCLK_D_N_R | CLK02-DIFF1 | PAIR | 8 | 5.38 | 5 | 10 | 5 | 12 | 6 | 33 | 12 | 12 | 12 | 12 | 6.62 | 85 Ohms | TOP=L2:L3=L2/L4:L6=L5/L7:BOTTOM=L7 |
| PCIE_REFCLK_D_P_R | CLK02-DIFF1 | PAIR | 1 | 5.38 | 5 | 10 | 5 | 12 | 6 | 33 | 12 | 12 | 12 | 12 | 6.62 | 85 Ohms | TOP=L2:L3=L2/L4:L6=L5/L7:BOTTOM=L7 |
| PCIE_REFCLK_D_P_R | CLK02-DIFF1 | PAIR | 2 | 5.5 | 5 | 10 | 5 | 12 | 6 | 20 | 12 | 12 | 12 | 12 | 7.5 | 85 Ohms | TOP=L2:L3=L2/L4:L6=L5/L7:BOTTOM=L7 |
| PCIE_REFCLK_D_P_R | CLK02-DIFF1 | PAIR | 3 | 5.5 | 5 | 10 | 5 | 12 | 6 | 20 | 12 | 12 | 12 | 12 | 7.5 | 85 Ohms | TOP=L2:L3=L2/L4:L6=L5/L7:BOTTOM=L7 |
| PCIE_REFCLK_D_P_R | CLK02-DIFF1 | PAIR | 4 | 5.5 | 5 | 10 | 5 | 12 | 6 | 20 | 12 | 12 | 12 | 12 | 7.5 | 85 Ohms | TOP=L2:L3=L2/L4:L6=L5/L7:BOTTOM=L7 |
| PCIE_REFCLK_D_P_R | CLK02-DIFF1 | PAIR | 5 | 5.5 | 5 | 10 | 5 | 12 | 6 | 20 | 12 | 12 | 12 | 12 | 7.5 | 85 Ohms | TOP=L2:L3=L2/L4:L6=L5/L7:BOTTOM=L7 |
| PCIE_REFCLK_D_P_R | CLK02-DIFF1 | PAIR | 6 | 5.5 | 5 | 10 | 5 | 12 | 6 | 20 | 12 | 12 | 12 | 12 | 7.5 | 85 Ohms | TOP=L2:L3=L2/L4:L6=L5/L7:BOTTOM=L7 |
| PCIE_REFCLK_D_P_R | CLK02-DIFF1 | PAIR | 7 | 5.5 | 5 | 10 | 5 | 12 | 6 | 20 | 12 | 12 | 12 | 12 | 7.5 | 85 Ohms | TOP=L2:L3=L2/L4:L6=L5/L7:BOTTOM=L7 |
| PCIE_REFCLK_D_P_R | CLK02-DIFF1 | PAIR | 8 | 5.38 | 5 | 10 | 5 | 12 | 6 | 33 | 12 | 12 | 12 | 12 | 6.62 | 85 Ohms | TOP=L2:L3=L2/L4:L6=L5/L7:BOTTOM=L7 |
| PCIE_REFCLK_H0_N | CLK03-DIFF1 | PAIR | 1 | 5.38 | 5 | 10 | 5 | 12 | 6 | 33 | 12 | 12 | 12 | 12 | 6.62 | 85 Ohms | TOP=L2:L3=L2/L4:L6=L5/L7:BOTTOM=L7 |
| PCIE_REFCLK_H0_N | CLK03-DIFF1 | PAIR | 2 | 5.5 | 5 | 10 | 5 | 12 | 6 | 20 | 12 | 12 | 12 | 12 | 7.5 | 85 Ohms | TOP=L2:L3=L2/L4:L6=L5/L7:BOTTOM=L7 |
| PCIE_REFCLK_H0_N | CLK03-DIFF1 | PAIR | 3 | 5.5 | 5 | 10 | 5 | 12 | 6 | 20 | 12 | 12 | 12 | 12 | 7.5 | 85 Ohms | TOP=L2:L3=L2/L4:L6=L5/L7:BOTTOM=L7 |
| PCIE_REFCLK_H0_N | CLK03-DIFF1 | PAIR | 4 | 5.5 | 5 | 10 | 5 | 12 | 6 | 20 | 12 | 12 | 12 | 12 | 7.5 | 85 Ohms | TOP=L2:L3=L2/L4:L6=L5/L7:BOTTOM=L7 |
| PCIE_REFCLK_H0_N | CLK03-DIFF1 | PAIR | 5 | 5.5 | 5 | 10 | 5 | 12 | 6 | 20 | 12 | 12 | 12 | 12 | 7.5 | 85 Ohms | TOP=L2:L3=L2/L4:L6=L5/L7:BOTTOM=L7 |
| PCIE_REFCLK_H0_N | CLK03-DIFF1 | PAIR | 6 | 5.5 | 5 | 10 | 5 | 12 | 6 | 20 | 12 | 12 | 12 | 12 | 7.5 | 85 Ohms | TOP=L2:L3=L2/L4:L6=L5/L7:BOTTOM=L7 |
| PCIE_REFCLK_H0_N | CLK03-DIFF1 | PAIR | 7 | 5.5 | 5 | 10 | 5 | 12 | 6 | 20 | 12 | 12 | 12 | 12 | 7.5 | 85 Ohms | TOP=L2:L3=L2/L4:L6=L5/L7:BOTTOM=L7 |
| PCIE_REFCLK_H0_N | CLK03-DIFF1 | PAIR | 8 | 5.38 | 5 | 10 | 5 | 12 | 6 | 33 | 12 | 12 | 12 | 12 | 6.62 | 85 Ohms | TOP=L2:L3=L2/L4:L6=L5/L7:BOTTOM=L7 |
| PCIE_REFCLK_H0_P | CLK03-DIFF1 | PAIR | 1 | 5.38 | 5 | 10 | 5 | 12 | 6 | 33 | 12 | 12 | 12 | 12 | 6.62 | 85 Ohms | TOP=L2:L3=L2/L4:L6=L5/L7:BOTTOM=L7 |
| PCIE_REFCLK_H0_P | CLK03-DIFF1 | PAIR | 2 | 5.5 | 5 | 10 | 5 | 12 | 6 | 20 | 12 | 12 | 12 | 12 | 7.5 | 85 Ohms | TOP=L2:L3=L2/L4:L6=L5/L7:BOTTOM=L7 |
| PCIE_REFCLK_H0_P | CLK03-DIFF1 | PAIR | 3 | 5.5 | 5 | 10 | 5 | 12 | 6 | 20 | 12 | 12 | 12 | 12 | 7.5 | 85 Ohms | TOP=L2:L3=L2/L4:L6=L5/L7:BOTTOM=L7 |
| PCIE_REFCLK_H0_P | CLK03-DIFF1 | PAIR | 4 | 5.5 | 5 | 10 | 5 | 12 | 6 | 20 | 12 | 12 | 12 | 12 | 7.5 | 85 Ohms | TOP=L2:L3=L2/L4:L6=L5/L7:BOTTOM=L7 |
| PCIE_REFCLK_H0_P | CLK03-DIFF1 | PAIR | 5 | 5.5 | 5 | 10 | 5 | 12 | 6 | 20 | 12 | 12 | 12 | 12 | 7.5 | 85 Ohms | TOP=L2:L3=L2/L4:L6=L5/L7:BOTTOM=L7 |
| PCIE_REFCLK_H0_P | CLK03-DIFF1 | PAIR | 6 | 5.5 | 5 | 10 | 5 | 12 | 6 | 20 | 12 | 12 | 12 | 12 | 7.5 | 85 Ohms | TOP=L2:L3=L2/L4:L6=L5/L7:BOTTOM=L7 |
| PCIE_REFCLK_H0_P | CLK03-DIFF1 | PAIR | 7 | 5.5 | 5 | 10 | 5 | 12 | 6 | 20 | 12 | 12 | 12 | 12 | 7.5 | 85 Ohms | TOP=L2:L3=L2/L4:L6=L5/L7:BOTTOM=L7 |
| PCIE_REFCLK_H0_P | CLK03-DIFF1 | PAIR | 8 | 5.38 | 5 | 10 | 5 | 12 | 6 | 33 | 12 | 12 | 12 | 12 | 6.62 | 85 Ohms | TOP=L2:L3=L2/L4:L6=L5/L7:BOTTOM=L7 |
| PCIE_REFCLK_H1_N | CLK04-DIFF1 | PAIR | 1 | 5.38 | 5 | 10 | 5 | 12 | 6 | 33 | 12 | 12 | 12 | 12 | 6.62 | 85 Ohms | TOP=L2:L3=L2/L4:L6=L5/L7:BOTTOM=L7 |
| PCIE_REFCLK_H1_N | CLK04-DIFF1 | PAIR | 2 | 5.5 | 5 | 10 | 5 | 12 | 6 | 20 | 12 | 12 | 12 | 12 | 7.5 | 85 Ohms | TOP=L2:L3=L2/L4:L6=L5/L7:BOTTOM=L7 |
| PCIE_REFCLK_H1_N | CLK04-DIFF1 | PAIR | 3 | 5.5 | 5 | 10 | 5 | 12 | 6 | 20 | 12 | 12 | 12 | 12 | 7.5 | 85 Ohms | TOP=L2:L3=L2/L4:L6=L5/L7:BOTTOM=L7 |
| PCIE_REFCLK_H1_N | CLK04-DIFF1 | PAIR | 4 | 5.5 | 5 | 10 | 5 | 12 | 6 | 20 | 12 | 12 | 12 | 12 | 7.5 | 85 Ohms | TOP=L2:L3=L2/L4:L6=L5/L7:BOTTOM=L7 |
| PCIE_REFCLK_H1_N | CLK04-DIFF1 | PAIR | 5 | 5.5 | 5 | 10 | 5 | 12 | 6 | 20 | 12 | 12 | 12 | 12 | 7.5 | 85 Ohms | TOP=L2:L3=L2/L4:L6=L5/L7:BOTTOM=L7 |
| PCIE_REFCLK_H1_N | CLK04-DIFF1 | PAIR | 6 | 5.5 | 5 | 10 | 5 | 12 | 6 | 20 | 12 | 12 | 12 | 12 | 7.5 | 85 Ohms | TOP=L2:L3=L2/L4:L6=L5/L7:BOTTOM=L7 |
| PCIE_REFCLK_H1_N | CLK04-DIFF1 | PAIR | 7 | 5.5 | 5 | 10 | 5 | 12 | 6 | 20 | 12 | 12 | 12 | 12 | 7.5 | 85 Ohms | TOP=L2:L3=L2/L4:L6=L5/L7:BOTTOM=L7 |
| PCIE_REFCLK_H1_N | CLK04-DIFF1 | PAIR | 8 | 5.38 | 5 | 10 | 5 | 12 | 6 | 33 | 12 | 12 | 12 | 12 | 6.62 | 85 Ohms | TOP=L2:L3=L2/L4:L6=L5/L7:BOTTOM=L7 |
| PCIE_REFCLK_H1_P | CLK04-DIFF1 | PAIR | 1 | 5.38 | 5 | 10 | 5 | 12 | 6 | 33 | 12 | 12 | 12 | 12 | 6.62 | 85 Ohms | TOP=L2:L3=L2/L4:L6=L5/L7:BOTTOM=L7 |
| PCIE_REFCLK_H1_P | CLK04-DIFF1 | PAIR | 2 | 5.5 | 5 | 10 | 5 | 12 | 6 | 20 | 12 | 12 | 12 | 12 | 7.5 | 85 Ohms | TOP=L2:L3=L2/L4:L6=L5/L7:BOTTOM=L7 |
| PCIE_REFCLK_H1_P | CLK04-DIFF1 | PAIR | 3 | 5.5 | 5 | 10 | 5 | 12 | 6 | 20 | 12 | 12 | 12 | 12 | 7.5 | 85 Ohms | TOP=L2:L3=L2/L4:L6=L5/L7:BOTTOM=L7 |
| PCIE_REFCLK_H1_P | CLK04-DIFF1 | PAIR | 4 | 5.5 | 5 | 10 | 5 | 12 | 6 | 20 | 12 | 12 | 12 | 12 | 7.5 | 85 Ohms | TOP=L2:L3=L2/L4:L6=L5/L7:BOTTOM=L7 |
| PCIE_REFCLK_H1_P | CLK04-DIFF1 | PAIR | 5 | 5.5 | 5 | 10 | 5 | 12 | 6 | 20 | 12 | 12 | 12 | 12 | 7.5 | 85 Ohms | TOP=L2:L3=L2/L4:L6=L5/L7:BOTTOM=L7 |
| PCIE_REFCLK_H1_P | CLK04-DIFF1 | PAIR | 6 | 5.5 | 5 | 10 | 5 | 12 | 6 | 20 | 12 | 12 | 12 | 12 | 7.5 | 85 Ohms | TOP=L2:L3=L2/L4:L6=L5/L7:BOTTOM=L7 |
| PCIE_REFCLK_H1_P | CLK04-DIFF1 | PAIR | 7 | 5.5 | 5 | 10 | 5 | 12 | 6 | 20 | 12 | 12 | 12 | 12 | 7.5 | 85 Ohms | TOP=L2:L3=L2/L4:L6=L5/L7:BOTTOM=L7 |
| PCIE_REFCLK_H1_P | CLK04-DIFF1 | PAIR | 8 | 5.38 | 5 | 10 | 5 | 12 | 6 | 33 | 12 | 12 | 12 | 12 | 6.62 | 85 Ohms | TOP=L2:L3=L2/L4:L6=L5/L7:BOTTOM=L7 |
| PCIE_REFCLK_H2_N | CLK05-DIFF1 | PAIR | 1 | 5.38 | 5 | 10 | 5 | 12 | 6 | 33 | 12 | 12 | 12 | 12 | 6.62 | 85 Ohms | TOP=L2:L3=L2/L4:L6=L5/L7:BOTTOM=L7 |
| PCIE_REFCLK_H2_N | CLK05-DIFF1 | PAIR | 2 | 5.5 | 5 | 10 | 5 | 12 | 6 | 20 | 12 | 12 | 12 | 12 | 7.5 | 85 Ohms | TOP=L2:L3=L2/L4:L6=L5/L7:BOTTOM=L7 |
| PCIE_REFCLK_H2_N | CLK05-DIFF1 | PAIR | 3 | 5.5 | 5 | 10 | 5 | 12 | 6 | 20 | 12 | 12 | 12 | 12 | 7.5 | 85 Ohms | TOP=L2:L3=L2/L4:L6=L5/L7:BOTTOM=L7 |
| PCIE_REFCLK_H2_N | CLK05-DIFF1 | PAIR | 4 | 5.5 | 5 | 10 | 5 | 12 | 6 | 20 | 12 | 12 | 12 | 12 | 7.5 | 85 Ohms | TOP=L2:L3=L2/L4:L6=L5/L7:BOTTOM=L7 |
| PCIE_REFCLK_H2_N | CLK05-DIFF1 | PAIR | 5 | 5.5 | 5 | 10 | 5 | 12 | 6 | 20 | 12 | 12 | 12 | 12 | 7.5 | 85 Ohms | TOP=L2:L3=L2/L4:L6=L5/L7:BOTTOM=L7 |
| PCIE_REFCLK_H2_N | CLK05-DIFF1 | PAIR | 6 | 5.5 | 5 | 10 | 5 | 12 | 6 | 20 | 12 | 12 | 12 | 12 | 7.5 | 85 Ohms | TOP=L2:L3=L2/L4:L6=L5/L7:BOTTOM=L7 |
| PCIE_REFCLK_H2_N | CLK05-DIFF1 | PAIR | 7 | 5.5 | 5 | 10 | 5 | 12 | 6 | 20 | 12 | 12 | 12 | 12 | 7.5 | 85 Ohms | TOP=L2:L3=L2/L4:L6=L5/L7:BOTTOM=L7 |
| PCIE_REFCLK_H2_N | CLK05-DIFF1 | PAIR | 8 | 5.38 | 5 | 10 | 5 | 12 | 6 | 33 | 12 | 12 | 12 | 12 | 6.62 | 85 Ohms | TOP=L2:L3=L2/L4:L6=L5/L7:BOTTOM=L7 |
| PCIE_REFCLK_H2_P | CLK05-DIFF1 | PAIR | 1 | 5.38 | 5 | 10 | 5 | 12 | 6 | 33 | 12 | 12 | 12 | 12 | 6.62 | 85 Ohms | TOP=L2:L3=L2/L4:L6=L5/L7:BOTTOM=L7 |
| PCIE_REFCLK_H2_P | CLK05-DIFF1 | PAIR | 2 | 5.5 | 5 | 10 | 5 | 12 | 6 | 20 | 12 | 12 | 12 | 12 | 7.5 | 85 Ohms | TOP=L2:L3=L2/L4:L6=L5/L7:BOTTOM=L7 |
| PCIE_REFCLK_H2_P | CLK05-DIFF1 | PAIR | 3 | 5.5 | 5 | 10 | 5 | 12 | 6 | 20 | 12 | 12 | 12 | 12 | 7.5 | 85 Ohms | TOP=L2:L3=L2/L4:L6=L5/L7:BOTTOM=L7 |
| PCIE_REFCLK_H2_P | CLK05-DIFF1 | PAIR | 4 | 5.5 | 5 | 10 | 5 | 12 | 6 | 20 | 12 | 12 | 12 | 12 | 7.5 | 85 Ohms | TOP=L2:L3=L2/L4:L6=L5/L7:BOTTOM=L7 |
| PCIE_REFCLK_H2_P | CLK05-DIFF1 | PAIR | 5 | 5.5 | 5 | 10 | 5 | 12 | 6 | 20 | 12 | 12 | 12 | 12 | 7.5 | 85 Ohms | TOP=L2:L3=L2/L4:L6=L5/L7:BOTTOM=L7 |
| PCIE_REFCLK_H2_P | CLK05-DIFF1 | PAIR | 6 | 5.5 | 5 | 10 | 5 | 12 | 6 | 20 | 12 | 12 | 12 | 12 | 7.5 | 85 Ohms | TOP=L2:L3=L2/L4:L6=L5/L7:BOTTOM=L7 |
| PCIE_REFCLK_H2_P | CLK05-DIFF1 | PAIR | 7 | 5.5 | 5 | 10 | 5 | 12 | 6 | 20 | 12 | 12 | 12 | 12 | 7.5 | 85 Ohms | TOP=L2:L3=L2/L4:L6=L5/L7:BOTTOM=L7 |
| PCIE_REFCLK_H2_P | CLK05-DIFF1 | PAIR | 8 | 5.38 | 5 | 10 | 5 | 12 | 6 | 33 | 12 | 12 | 12 | 12 | 6.62 | 85 Ohms | TOP=L2:L3=L2/L4:L6=L5/L7:BOTTOM=L7 |
| PCIE_REFCLK_H3_N | CLK06-DIFF1 | PAIR | 1 | 5.38 | 5 | 10 | 5 | 12 | 6 | 33 | 12 | 12 | 12 | 12 | 6.62 | 85 Ohms | TOP=L2:L3=L2/L4:L6=L5/L7:BOTTOM=L7 |
| PCIE_REFCLK_H3_N | CLK06-DIFF1 | PAIR | 2 | 5.5 | 5 | 10 | 5 | 12 | 6 | 20 | 12 | 12 | 12 | 12 | 7.5 | 85 Ohms | TOP=L2:L3=L2/L4:L6=L5/L7:BOTTOM=L7 |
| PCIE_REFCLK_H3_N | CLK06-DIFF1 | PAIR | 3 | 5.5 | 5 | 10 | 5 | 12 | 6 | 20 | 12 | 12 | 12 | 12 | 7.5 | 85 Ohms | TOP=L2:L3=L2/L4:L6=L5/L7:BOTTOM=L7 |
| PCIE_REFCLK_H3_N | CLK06-DIFF1 | PAIR | 4 | 5.5 | 5 | 10 | 5 | 12 | 6 | 20 | 12 | 12 | 12 | 12 | 7.5 | 85 Ohms | TOP=L2:L3=L2/L4:L6=L5/L7:BOTTOM=L7 |
| PCIE_REFCLK_H3_N | CLK06-DIFF1 | PAIR | 5 | 5.5 | 5 | 10 | 5 | 12 | 6 | 20 | 12 | 12 | 12 | 12 | 7.5 | 85 Ohms | TOP=L2:L3=L2/L4:L6=L5/L7:BOTTOM=L7 |
| PCIE_REFCLK_H3_N | CLK06-DIFF1 | PAIR | 6 | 5.5 | 5 | 10 | 5 | 12 | 6 | 20 | 12 | 12 | 12 | 12 | 7.5 | 85 Ohms | TOP=L2:L3=L2/L4:L6=L5/L7:BOTTOM=L7 |
| PCIE_REFCLK_H3_N | CLK06-DIFF1 | PAIR | 7 | 5.5 | 5 | 10 | 5 | 12 | 6 | 20 | 12 | 12 | 12 | 12 | 7.5 | 85 Ohms | TOP=L2:L3=L2/L4:L6=L5/L7:BOTTOM=L7 |
| PCIE_REFCLK_H3_N | CLK06-DIFF1 | PAIR | 8 | 5.38 | 5 | 10 | 5 | 12 | 6 | 33 | 12 | 12 | 12 | 12 | 6.62 | 85 Ohms | TOP=L2:L3=L2/L4:L6=L5/L7:BOTTOM=L7 |
| PCIE_REFCLK_H3_P | CLK06-DIFF1 | PAIR | 1 | 5.38 | 5 | 10 | 5 | 12 | 6 | 33 | 12 | 12 | 12 | 12 | 6.62 | 85 Ohms | TOP=L2:L3=L2/L4:L6=L5/L7:BOTTOM=L7 |
| PCIE_REFCLK_H3_P | CLK06-DIFF1 | PAIR | 2 | 5.5 | 5 | 10 | 5 | 12 | 6 | 20 | 12 | 12 | 12 | 12 | 7.5 | 85 Ohms | TOP=L2:L3=L2/L4:L6=L5/L7:BOTTOM=L7 |
| PCIE_REFCLK_H3_P | CLK06-DIFF1 | PAIR | 3 | 5.5 | 5 | 10 | 5 | 12 | 6 | 20 | 12 | 12 | 12 | 12 | 7.5 | 85 Ohms | TOP=L2:L3=L2/L4:L6=L5/L7:BOTTOM=L7 |
| PCIE_REFCLK_H3_P | CLK06-DIFF1 | PAIR | 4 | 5.5 | 5 | 10 | 5 | 12 | 6 | 20 | 12 | 12 | 12 | 12 | 7.5 | 85 Ohms | TOP=L2:L3=L2/L4:L6=L5/L7:BOTTOM=L7 |
| PCIE_REFCLK_H3_P | CLK06-DIFF1 | PAIR | 5 | 5.5 | 5 | 10 | 5 | 12 | 6 | 20 | 12 | 12 | 12 | 12 | 7.5 | 85 Ohms | TOP=L2:L3=L2/L4:L6=L5/L7:BOTTOM=L7 |
| PCIE_REFCLK_H3_P | CLK06-DIFF1 | PAIR | 6 | 5.5 | 5 | 10 | 5 | 12 | 6 | 20 | 12 | 12 | 12 | 12 | 7.5 | 85 Ohms | TOP=L2:L3=L2/L4:L6=L5/L7:BOTTOM=L7 |
| PCIE_REFCLK_H3_P | CLK06-DIFF1 | PAIR | 7 | 5.5 | 5 | 10 | 5 | 12 | 6 | 20 | 12 | 12 | 12 | 12 | 7.5 | 85 Ohms | TOP=L2:L3=L2/L4:L6=L5/L7:BOTTOM=L7 |
| PCIE_REFCLK_H3_P | CLK06-DIFF1 | PAIR | 8 | 5.38 | 5 | 10 | 5 | 12 | 6 | 33 | 12 | 12 | 12 | 12 | 6.62 | 85 Ohms | TOP=L2:L3=L2/L4:L6=L5/L7:BOTTOM=L7 |
| PCIE_REFCLK_S1_N | CLK08-DIFF1 | PAIR | 1 | 5.38 | 5 | 10 | 5 | 12 | 6 | 33 | 12 | 12 | 12 | 12 | 6.62 | 85 Ohms | TOP=L2:L3=L2/L4:L6=L5/L7:BOTTOM=L7 |
| PCIE_REFCLK_S1_N | CLK08-DIFF1 | PAIR | 2 | 5.5 | 5 | 10 | 5 | 12 | 6 | 20 | 12 | 12 | 12 | 12 | 7.5 | 85 Ohms | TOP=L2:L3=L2/L4:L6=L5/L7:BOTTOM=L7 |
| PCIE_REFCLK_S1_N | CLK08-DIFF1 | PAIR | 3 | 5.5 | 5 | 10 | 5 | 12 | 6 | 20 | 12 | 12 | 12 | 12 | 7.5 | 85 Ohms | TOP=L2:L3=L2/L4:L6=L5/L7:BOTTOM=L7 |
| PCIE_REFCLK_S1_N | CLK08-DIFF1 | PAIR | 4 | 5.5 | 5 | 10 | 5 | 12 | 6 | 20 | 12 | 12 | 12 | 12 | 7.5 | 85 Ohms | TOP=L2:L3=L2/L4:L6=L5/L7:BOTTOM=L7 |
| PCIE_REFCLK_S1_N | CLK08-DIFF1 | PAIR | 5 | 5.5 | 5 | 10 | 5 | 12 | 6 | 20 | 12 | 12 | 12 | 12 | 7.5 | 85 Ohms | TOP=L2:L3=L2/L4:L6=L5/L7:BOTTOM=L7 |
| PCIE_REFCLK_S1_N | CLK08-DIFF1 | PAIR | 6 | 5.5 | 5 | 10 | 5 | 12 | 6 | 20 | 12 | 12 | 12 | 12 | 7.5 | 85 Ohms | TOP=L2:L3=L2/L4:L6=L5/L7:BOTTOM=L7 |
| PCIE_REFCLK_S1_N | CLK08-DIFF1 | PAIR | 7 | 5.5 | 5 | 10 | 5 | 12 | 6 | 20 | 12 | 12 | 12 | 12 | 7.5 | 85 Ohms | TOP=L2:L3=L2/L4:L6=L5/L7:BOTTOM=L7 |
| PCIE_REFCLK_S1_N | CLK08-DIFF1 | PAIR | 8 | 5.38 | 5 | 10 | 5 | 12 | 6 | 33 | 12 | 12 | 12 | 12 | 6.62 | 85 Ohms | TOP=L2:L3=L2/L4:L6=L5/L7:BOTTOM=L7 |
| PCIE_REFCLK_S1_P | CLK08-DIFF1 | PAIR | 1 | 5.38 | 5 | 10 | 5 | 12 | 6 | 33 | 12 | 12 | 12 | 12 | 6.62 | 85 Ohms | TOP=L2:L3=L2/L4:L6=L5/L7:BOTTOM=L7 |
| PCIE_REFCLK_S1_P | CLK08-DIFF1 | PAIR | 2 | 5.5 | 5 | 10 | 5 | 12 | 6 | 20 | 12 | 12 | 12 | 12 | 7.5 | 85 Ohms | TOP=L2:L3=L2/L4:L6=L5/L7:BOTTOM=L7 |
| PCIE_REFCLK_S1_P | CLK08-DIFF1 | PAIR | 3 | 5.5 | 5 | 10 | 5 | 12 | 6 | 20 | 12 | 12 | 12 | 12 | 7.5 | 85 Ohms | TOP=L2:L3=L2/L4:L6=L5/L7:BOTTOM=L7 |
| PCIE_REFCLK_S1_P | CLK08-DIFF1 | PAIR | 4 | 5.5 | 5 | 10 | 5 | 12 | 6 | 20 | 12 | 12 | 12 | 12 | 7.5 | 85 Ohms | TOP=L2:L3=L2/L4:L6=L5/L7:BOTTOM=L7 |
| PCIE_REFCLK_S1_P | CLK08-DIFF1 | PAIR | 5 | 5.5 | 5 | 10 | 5 | 12 | 6 | 20 | 12 | 12 | 12 | 12 | 7.5 | 85 Ohms | TOP=L2:L3=L2/L4:L6=L5/L7:BOTTOM=L7 |
| PCIE_REFCLK_S1_P | CLK08-DIFF1 | PAIR | 6 | 5.5 | 5 | 10 | 5 | 12 | 6 | 20 | 12 | 12 | 12 | 12 | 7.5 | 85 Ohms | TOP=L2:L3=L2/L4:L6=L5/L7:BOTTOM=L7 |
| PCIE_REFCLK_S1_P | CLK08-DIFF1 | PAIR | 7 | 5.5 | 5 | 10 | 5 | 12 | 6 | 20 | 12 | 12 | 12 | 12 | 7.5 | 85 Ohms | TOP=L2:L3=L2/L4:L6=L5/L7:BOTTOM=L7 |
| PCIE_REFCLK_S1_P | CLK08-DIFF1 | PAIR | 8 | 5.38 | 5 | 10 | 5 | 12 | 6 | 33 | 12 | 12 | 12 | 12 | 6.62 | 85 Ohms | TOP=L2:L3=L2/L4:L6=L5/L7:BOTTOM=L7 |
| PCIE_REFCLK_S2_N | CLK09-DIFF1 | PAIR | 1 | 5.38 | 5 | 10 | 5 | 12 | 6 | 33 | 12 | 12 | 12 | 12 | 6.62 | 85 Ohms | TOP=L2:L3=L2/L4:L6=L5/L7:BOTTOM=L7 |
| PCIE_REFCLK_S2_N | CLK09-DIFF1 | PAIR | 2 | 5.5 | 5 | 10 | 5 | 12 | 6 | 20 | 12 | 12 | 12 | 12 | 7.5 | 85 Ohms | TOP=L2:L3=L2/L4:L6=L5/L7:BOTTOM=L7 |
| PCIE_REFCLK_S2_N | CLK09-DIFF1 | PAIR | 3 | 5.5 | 5 | 10 | 5 | 12 | 6 | 20 | 12 | 12 | 12 | 12 | 7.5 | 85 Ohms | TOP=L2:L3=L2/L4:L6=L5/L7:BOTTOM=L7 |
| PCIE_REFCLK_S2_N | CLK09-DIFF1 | PAIR | 4 | 5.5 | 5 | 10 | 5 | 12 | 6 | 20 | 12 | 12 | 12 | 12 | 7.5 | 85 Ohms | TOP=L2:L3=L2/L4:L6=L5/L7:BOTTOM=L7 |
| PCIE_REFCLK_S2_N | CLK09-DIFF1 | PAIR | 5 | 5.5 | 5 | 10 | 5 | 12 | 6 | 20 | 12 | 12 | 12 | 12 | 7.5 | 85 Ohms | TOP=L2:L3=L2/L4:L6=L5/L7:BOTTOM=L7 |
| PCIE_REFCLK_S2_N | CLK09-DIFF1 | PAIR | 6 | 5.5 | 5 | 10 | 5 | 12 | 6 | 20 | 12 | 12 | 12 | 12 | 7.5 | 85 Ohms | TOP=L2:L3=L2/L4:L6=L5/L7:BOTTOM=L7 |
| PCIE_REFCLK_S2_N | CLK09-DIFF1 | PAIR | 7 | 5.5 | 5 | 10 | 5 | 12 | 6 | 20 | 12 | 12 | 12 | 12 | 7.5 | 85 Ohms | TOP=L2:L3=L2/L4:L6=L5/L7:BOTTOM=L7 |
| PCIE_REFCLK_S2_N | CLK09-DIFF1 | PAIR | 8 | 5.38 | 5 | 10 | 5 | 12 | 6 | 33 | 12 | 12 | 12 | 12 | 6.62 | 85 Ohms | TOP=L2:L3=L2/L4:L6=L5/L7:BOTTOM=L7 |
| PCIE_REFCLK_S2_P | CLK09-DIFF1 | PAIR | 1 | 5.38 | 5 | 10 | 5 | 12 | 6 | 33 | 12 | 12 | 12 | 12 | 6.62 | 85 Ohms | TOP=L2:L3=L2/L4:L6=L5/L7:BOTTOM=L7 |
| PCIE_REFCLK_S2_P | CLK09-DIFF1 | PAIR | 2 | 5.5 | 5 | 10 | 5 | 12 | 6 | 20 | 12 | 12 | 12 | 12 | 7.5 | 85 Ohms | TOP=L2:L3=L2/L4:L6=L5/L7:BOTTOM=L7 |
| PCIE_REFCLK_S2_P | CLK09-DIFF1 | PAIR | 3 | 5.5 | 5 | 10 | 5 | 12 | 6 | 20 | 12 | 12 | 12 | 12 | 7.5 | 85 Ohms | TOP=L2:L3=L2/L4:L6=L5/L7:BOTTOM=L7 |
| PCIE_REFCLK_S2_P | CLK09-DIFF1 | PAIR | 4 | 5.5 | 5 | 10 | 5 | 12 | 6 | 20 | 12 | 12 | 12 | 12 | 7.5 | 85 Ohms | TOP=L2:L3=L2/L4:L6=L5/L7:BOTTOM=L7 |
| PCIE_REFCLK_S2_P | CLK09-DIFF1 | PAIR | 5 | 5.5 | 5 | 10 | 5 | 12 | 6 | 20 | 12 | 12 | 12 | 12 | 7.5 | 85 Ohms | TOP=L2:L3=L2/L4:L6=L5/L7:BOTTOM=L7 |
| PCIE_REFCLK_S2_P | CLK09-DIFF1 | PAIR | 6 | 5.5 | 5 | 10 | 5 | 12 | 6 | 20 | 12 | 12 | 12 | 12 | 7.5 | 85 Ohms | TOP=L2:L3=L2/L4:L6=L5/L7:BOTTOM=L7 |
| PCIE_REFCLK_S2_P | CLK09-DIFF1 | PAIR | 7 | 5.5 | 5 | 10 | 5 | 12 | 6 | 20 | 12 | 12 | 12 | 12 | 7.5 | 85 Ohms | TOP=L2:L3=L2/L4:L6=L5/L7:BOTTOM=L7 |
| PCIE_REFCLK_S2_P | CLK09-DIFF1 | PAIR | 8 | 5.38 | 5 | 10 | 5 | 12 | 6 | 33 | 12 | 12 | 12 | 12 | 6.62 | 85 Ohms | TOP=L2:L3=L2/L4:L6=L5/L7:BOTTOM=L7 |
| PCIE_REFCLK_S3_N | CLK10-DIFF1 | PAIR | 1 | 5.38 | 5 | 10 | 5 | 12 | 6 | 33 | 12 | 12 | 12 | 12 | 6.62 | 85 Ohms | TOP=L2:L3=L2/L4:L6=L5/L7:BOTTOM=L7 |
| PCIE_REFCLK_S3_N | CLK10-DIFF1 | PAIR | 2 | 5.5 | 5 | 10 | 5 | 12 | 6 | 20 | 12 | 12 | 12 | 12 | 7.5 | 85 Ohms | TOP=L2:L3=L2/L4:L6=L5/L7:BOTTOM=L7 |
| PCIE_REFCLK_S3_N | CLK10-DIFF1 | PAIR | 3 | 5.5 | 5 | 10 | 5 | 12 | 6 | 20 | 12 | 12 | 12 | 12 | 7.5 | 85 Ohms | TOP=L2:L3=L2/L4:L6=L5/L7:BOTTOM=L7 |
| PCIE_REFCLK_S3_N | CLK10-DIFF1 | PAIR | 4 | 5.5 | 5 | 10 | 5 | 12 | 6 | 20 | 12 | 12 | 12 | 12 | 7.5 | 85 Ohms | TOP=L2:L3=L2/L4:L6=L5/L7:BOTTOM=L7 |
| PCIE_REFCLK_S3_N | CLK10-DIFF1 | PAIR | 5 | 5.5 | 5 | 10 | 5 | 12 | 6 | 20 | 12 | 12 | 12 | 12 | 7.5 | 85 Ohms | TOP=L2:L3=L2/L4:L6=L5/L7:BOTTOM=L7 |
| PCIE_REFCLK_S3_N | CLK10-DIFF1 | PAIR | 6 | 5.5 | 5 | 10 | 5 | 12 | 6 | 20 | 12 | 12 | 12 | 12 | 7.5 | 85 Ohms | TOP=L2:L3=L2/L4:L6=L5/L7:BOTTOM=L7 |
| PCIE_REFCLK_S3_N | CLK10-DIFF1 | PAIR | 7 | 5.5 | 5 | 10 | 5 | 12 | 6 | 20 | 12 | 12 | 12 | 12 | 7.5 | 85 Ohms | TOP=L2:L3=L2/L4:L6=L5/L7:BOTTOM=L7 |
| PCIE_REFCLK_S3_N | CLK10-DIFF1 | PAIR | 8 | 5.38 | 5 | 10 | 5 | 12 | 6 | 33 | 12 | 12 | 12 | 12 | 6.62 | 85 Ohms | TOP=L2:L3=L2/L4:L6=L5/L7:BOTTOM=L7 |
| PCIE_REFCLK_S3_P | CLK10-DIFF1 | PAIR | 1 | 5.38 | 5 | 10 | 5 | 12 | 6 | 33 | 12 | 12 | 12 | 12 | 6.62 | 85 Ohms | TOP=L2:L3=L2/L4:L6=L5/L7:BOTTOM=L7 |
| PCIE_REFCLK_S3_P | CLK10-DIFF1 | PAIR | 2 | 5.5 | 5 | 10 | 5 | 12 | 6 | 20 | 12 | 12 | 12 | 12 | 7.5 | 85 Ohms | TOP=L2:L3=L2/L4:L6=L5/L7:BOTTOM=L7 |
| PCIE_REFCLK_S3_P | CLK10-DIFF1 | PAIR | 3 | 5.5 | 5 | 10 | 5 | 12 | 6 | 20 | 12 | 12 | 12 | 12 | 7.5 | 85 Ohms | TOP=L2:L3=L2/L4:L6=L5/L7:BOTTOM=L7 |
| PCIE_REFCLK_S3_P | CLK10-DIFF1 | PAIR | 4 | 5.5 | 5 | 10 | 5 | 12 | 6 | 20 | 12 | 12 | 12 | 12 | 7.5 | 85 Ohms | TOP=L2:L3=L2/L4:L6=L5/L7:BOTTOM=L7 |
| PCIE_REFCLK_S3_P | CLK10-DIFF1 | PAIR | 5 | 5.5 | 5 | 10 | 5 | 12 | 6 | 20 | 12 | 12 | 12 | 12 | 7.5 | 85 Ohms | TOP=L2:L3=L2/L4:L6=L5/L7:BOTTOM=L7 |
| PCIE_REFCLK_S3_P | CLK10-DIFF1 | PAIR | 6 | 5.5 | 5 | 10 | 5 | 12 | 6 | 20 | 12 | 12 | 12 | 12 | 7.5 | 85 Ohms | TOP=L2:L3=L2/L4:L6=L5/L7:BOTTOM=L7 |
| PCIE_REFCLK_S3_P | CLK10-DIFF1 | PAIR | 7 | 5.5 | 5 | 10 | 5 | 12 | 6 | 20 | 12 | 12 | 12 | 12 | 7.5 | 85 Ohms | TOP=L2:L3=L2/L4:L6=L5/L7:BOTTOM=L7 |
| PCIE_REFCLK_S3_P | CLK10-DIFF1 | PAIR | 8 | 5.38 | 5 | 10 | 5 | 12 | 6 | 33 | 12 | 12 | 12 | 12 | 6.62 | 85 Ohms | TOP=L2:L3=L2/L4:L6=L5/L7:BOTTOM=L7 |
| PCIE_REFCLK_S4_N | CLK11-DIFF1 | PAIR | 1 | 5.38 | 5 | 10 | 5 | 12 | 6 | 33 | 12 | 12 | 12 | 12 | 6.62 | 85 Ohms | TOP=L2:L3=L2/L4:L6=L5/L7:BOTTOM=L7 |
| PCIE_REFCLK_S4_N | CLK11-DIFF1 | PAIR | 2 | 5.5 | 5 | 10 | 5 | 12 | 6 | 20 | 12 | 12 | 12 | 12 | 7.5 | 85 Ohms | TOP=L2:L3=L2/L4:L6=L5/L7:BOTTOM=L7 |
| PCIE_REFCLK_S4_N | CLK11-DIFF1 | PAIR | 3 | 5.5 | 5 | 10 | 5 | 12 | 6 | 20 | 12 | 12 | 12 | 12 | 7.5 | 85 Ohms | TOP=L2:L3=L2/L4:L6=L5/L7:BOTTOM=L7 |
| PCIE_REFCLK_S4_N | CLK11-DIFF1 | PAIR | 4 | 5.5 | 5 | 10 | 5 | 12 | 6 | 20 | 12 | 12 | 12 | 12 | 7.5 | 85 Ohms | TOP=L2:L3=L2/L4:L6=L5/L7:BOTTOM=L7 |
| PCIE_REFCLK_S4_N | CLK11-DIFF1 | PAIR | 5 | 5.5 | 5 | 10 | 5 | 12 | 6 | 20 | 12 | 12 | 12 | 12 | 7.5 | 85 Ohms | TOP=L2:L3=L2/L4:L6=L5/L7:BOTTOM=L7 |
| PCIE_REFCLK_S4_N | CLK11-DIFF1 | PAIR | 6 | 5.5 | 5 | 10 | 5 | 12 | 6 | 20 | 12 | 12 | 12 | 12 | 7.5 | 85 Ohms | TOP=L2:L3=L2/L4:L6=L5/L7:BOTTOM=L7 |
| PCIE_REFCLK_S4_N | CLK11-DIFF1 | PAIR | 7 | 5.5 | 5 | 10 | 5 | 12 | 6 | 20 | 12 | 12 | 12 | 12 | 7.5 | 85 Ohms | TOP=L2:L3=L2/L4:L6=L5/L7:BOTTOM=L7 |
| PCIE_REFCLK_S4_N | CLK11-DIFF1 | PAIR | 8 | 5.38 | 5 | 10 | 5 | 12 | 6 | 33 | 12 | 12 | 12 | 12 | 6.62 | 85 Ohms | TOP=L2:L3=L2/L4:L6=L5/L7:BOTTOM=L7 |
| PCIE_REFCLK_S4_P | CLK11-DIFF1 | PAIR | 1 | 5.38 | 5 | 10 | 5 | 12 | 6 | 33 | 12 | 12 | 12 | 12 | 6.62 | 85 Ohms | TOP=L2:L3=L2/L4:L6=L5/L7:BOTTOM=L7 |
| PCIE_REFCLK_S4_P | CLK11-DIFF1 | PAIR | 2 | 5.5 | 5 | 10 | 5 | 12 | 6 | 20 | 12 | 12 | 12 | 12 | 7.5 | 85 Ohms | TOP=L2:L3=L2/L4:L6=L5/L7:BOTTOM=L7 |
| PCIE_REFCLK_S4_P | CLK11-DIFF1 | PAIR | 3 | 5.5 | 5 | 10 | 5 | 12 | 6 | 20 | 12 | 12 | 12 | 12 | 7.5 | 85 Ohms | TOP=L2:L3=L2/L4:L6=L5/L7:BOTTOM=L7 |
| PCIE_REFCLK_S4_P | CLK11-DIFF1 | PAIR | 4 | 5.5 | 5 | 10 | 5 | 12 | 6 | 20 | 12 | 12 | 12 | 12 | 7.5 | 85 Ohms | TOP=L2:L3=L2/L4:L6=L5/L7:BOTTOM=L7 |
| PCIE_REFCLK_S4_P | CLK11-DIFF1 | PAIR | 5 | 5.5 | 5 | 10 | 5 | 12 | 6 | 20 | 12 | 12 | 12 | 12 | 7.5 | 85 Ohms | TOP=L2:L3=L2/L4:L6=L5/L7:BOTTOM=L7 |
| PCIE_REFCLK_S4_P | CLK11-DIFF1 | PAIR | 6 | 5.5 | 5 | 10 | 5 | 12 | 6 | 20 | 12 | 12 | 12 | 12 | 7.5 | 85 Ohms | TOP=L2:L3=L2/L4:L6=L5/L7:BOTTOM=L7 |
| PCIE_REFCLK_S4_P | CLK11-DIFF1 | PAIR | 7 | 5.5 | 5 | 10 | 5 | 12 | 6 | 20 | 12 | 12 | 12 | 12 | 7.5 | 85 Ohms | TOP=L2:L3=L2/L4:L6=L5/L7:BOTTOM=L7 |
| PCIE_REFCLK_S4_P | CLK11-DIFF1 | PAIR | 8 | 5.38 | 5 | 10 | 5 | 12 | 6 | 33 | 12 | 12 | 12 | 12 | 6.62 | 85 Ohms | TOP=L2:L3=L2/L4:L6=L5/L7:BOTTOM=L7 |
| PCIE_REFCLK_S5_N | CLK12-DIFF1 | PAIR | 1 | 5.38 | 5 | 10 | 5 | 12 | 6 | 33 | 12 | 12 | 12 | 12 | 6.62 | 85 Ohms | TOP=L2:L3=L2/L4:L6=L5/L7:BOTTOM=L7 |
| PCIE_REFCLK_S5_N | CLK12-DIFF1 | PAIR | 2 | 5.5 | 5 | 10 | 5 | 12 | 6 | 20 | 12 | 12 | 12 | 12 | 7.5 | 85 Ohms | TOP=L2:L3=L2/L4:L6=L5/L7:BOTTOM=L7 |
| PCIE_REFCLK_S5_N | CLK12-DIFF1 | PAIR | 3 | 5.5 | 5 | 10 | 5 | 12 | 6 | 20 | 12 | 12 | 12 | 12 | 7.5 | 85 Ohms | TOP=L2:L3=L2/L4:L6=L5/L7:BOTTOM=L7 |
| PCIE_REFCLK_S5_N | CLK12-DIFF1 | PAIR | 4 | 5.5 | 5 | 10 | 5 | 12 | 6 | 20 | 12 | 12 | 12 | 12 | 7.5 | 85 Ohms | TOP=L2:L3=L2/L4:L6=L5/L7:BOTTOM=L7 |
| PCIE_REFCLK_S5_N | CLK12-DIFF1 | PAIR | 5 | 5.5 | 5 | 10 | 5 | 12 | 6 | 20 | 12 | 12 | 12 | 12 | 7.5 | 85 Ohms | TOP=L2:L3=L2/L4:L6=L5/L7:BOTTOM=L7 |
| PCIE_REFCLK_S5_N | CLK12-DIFF1 | PAIR | 6 | 5.5 | 5 | 10 | 5 | 12 | 6 | 20 | 12 | 12 | 12 | 12 | 7.5 | 85 Ohms | TOP=L2:L3=L2/L4:L6=L5/L7:BOTTOM=L7 |
| PCIE_REFCLK_S5_N | CLK12-DIFF1 | PAIR | 7 | 5.5 | 5 | 10 | 5 | 12 | 6 | 20 | 12 | 12 | 12 | 12 | 7.5 | 85 Ohms | TOP=L2:L3=L2/L4:L6=L5/L7:BOTTOM=L7 |
| PCIE_REFCLK_S5_N | CLK12-DIFF1 | PAIR | 8 | 5.38 | 5 | 10 | 5 | 12 | 6 | 33 | 12 | 12 | 12 | 12 | 6.62 | 85 Ohms | TOP=L2:L3=L2/L4:L6=L5/L7:BOTTOM=L7 |
| PCIE_REFCLK_S5_P | CLK12-DIFF1 | PAIR | 1 | 5.38 | 5 | 10 | 5 | 12 | 6 | 33 | 12 | 12 | 12 | 12 | 6.62 | 85 Ohms | TOP=L2:L3=L2/L4:L6=L5/L7:BOTTOM=L7 |
| PCIE_REFCLK_S5_P | CLK12-DIFF1 | PAIR | 2 | 5.5 | 5 | 10 | 5 | 12 | 6 | 20 | 12 | 12 | 12 | 12 | 7.5 | 85 Ohms | TOP=L2:L3=L2/L4:L6=L5/L7:BOTTOM=L7 |
| PCIE_REFCLK_S5_P | CLK12-DIFF1 | PAIR | 3 | 5.5 | 5 | 10 | 5 | 12 | 6 | 20 | 12 | 12 | 12 | 12 | 7.5 | 85 Ohms | TOP=L2:L3=L2/L4:L6=L5/L7:BOTTOM=L7 |
| PCIE_REFCLK_S5_P | CLK12-DIFF1 | PAIR | 4 | 5.5 | 5 | 10 | 5 | 12 | 6 | 20 | 12 | 12 | 12 | 12 | 7.5 | 85 Ohms | TOP=L2:L3=L2/L4:L6=L5/L7:BOTTOM=L7 |
| PCIE_REFCLK_S5_P | CLK12-DIFF1 | PAIR | 5 | 5.5 | 5 | 10 | 5 | 12 | 6 | 20 | 12 | 12 | 12 | 12 | 7.5 | 85 Ohms | TOP=L2:L3=L2/L4:L6=L5/L7:BOTTOM=L7 |
| PCIE_REFCLK_S5_P | CLK12-DIFF1 | PAIR | 6 | 5.5 | 5 | 10 | 5 | 12 | 6 | 20 | 12 | 12 | 12 | 12 | 7.5 | 85 Ohms | TOP=L2:L3=L2/L4:L6=L5/L7:BOTTOM=L7 |
| PCIE_REFCLK_S5_P | CLK12-DIFF1 | PAIR | 7 | 5.5 | 5 | 10 | 5 | 12 | 6 | 20 | 12 | 12 | 12 | 12 | 7.5 | 85 Ohms | TOP=L2:L3=L2/L4:L6=L5/L7:BOTTOM=L7 |
| PCIE_REFCLK_S5_P | CLK12-DIFF1 | PAIR | 8 | 5.38 | 5 | 10 | 5 | 12 | 6 | 33 | 12 | 12 | 12 | 12 | 6.62 | 85 Ohms | TOP=L2:L3=L2/L4:L6=L5/L7:BOTTOM=L7 |
| PCIE_REFCLK_H2_N_R | CLK13-DIFF1 | PAIR | 1 | 5.38 | 5 | 10 | 5 | 12 | 6 | 33 | 12 | 12 | 12 | 12 | 6.62 | 85 Ohms | TOP=L2:L3=L2/L4:L6=L5/L7:BOTTOM=L7 |
| PCIE_REFCLK_H2_N_R | CLK13-DIFF1 | PAIR | 2 | 5.5 | 5 | 10 | 5 | 12 | 6 | 20 | 12 | 12 | 12 | 12 | 7.5 | 85 Ohms | TOP=L2:L3=L2/L4:L6=L5/L7:BOTTOM=L7 |
| PCIE_REFCLK_H2_N_R | CLK13-DIFF1 | PAIR | 3 | 5.5 | 5 | 10 | 5 | 12 | 6 | 20 | 12 | 12 | 12 | 12 | 7.5 | 85 Ohms | TOP=L2:L3=L2/L4:L6=L5/L7:BOTTOM=L7 |
| PCIE_REFCLK_H2_N_R | CLK13-DIFF1 | PAIR | 4 | 5.5 | 5 | 10 | 5 | 12 | 6 | 20 | 12 | 12 | 12 | 12 | 7.5 | 85 Ohms | TOP=L2:L3=L2/L4:L6=L5/L7:BOTTOM=L7 |
| PCIE_REFCLK_H2_N_R | CLK13-DIFF1 | PAIR | 5 | 5.5 | 5 | 10 | 5 | 12 | 6 | 20 | 12 | 12 | 12 | 12 | 7.5 | 85 Ohms | TOP=L2:L3=L2/L4:L6=L5/L7:BOTTOM=L7 |
| PCIE_REFCLK_H2_N_R | CLK13-DIFF1 | PAIR | 6 | 5.5 | 5 | 10 | 5 | 12 | 6 | 20 | 12 | 12 | 12 | 12 | 7.5 | 85 Ohms | TOP=L2:L3=L2/L4:L6=L5/L7:BOTTOM=L7 |
| PCIE_REFCLK_H2_N_R | CLK13-DIFF1 | PAIR | 7 | 5.5 | 5 | 10 | 5 | 12 | 6 | 20 | 12 | 12 | 12 | 12 | 7.5 | 85 Ohms | TOP=L2:L3=L2/L4:L6=L5/L7:BOTTOM=L7 |
| PCIE_REFCLK_H2_N_R | CLK13-DIFF1 | PAIR | 8 | 5.38 | 5 | 10 | 5 | 12 | 6 | 33 | 12 | 12 | 12 | 12 | 6.62 | 85 Ohms | TOP=L2:L3=L2/L4:L6=L5/L7:BOTTOM=L7 |
| PCIE_REFCLK_H2_P_R | CLK13-DIFF1 | PAIR | 1 | 5.38 | 5 | 10 | 5 | 12 | 6 | 33 | 12 | 12 | 12 | 12 | 6.62 | 85 Ohms | TOP=L2:L3=L2/L4:L6=L5/L7:BOTTOM=L7 |
| PCIE_REFCLK_H2_P_R | CLK13-DIFF1 | PAIR | 2 | 5.5 | 5 | 10 | 5 | 12 | 6 | 20 | 12 | 12 | 12 | 12 | 7.5 | 85 Ohms | TOP=L2:L3=L2/L4:L6=L5/L7:BOTTOM=L7 |
| PCIE_REFCLK_H2_P_R | CLK13-DIFF1 | PAIR | 3 | 5.5 | 5 | 10 | 5 | 12 | 6 | 20 | 12 | 12 | 12 | 12 | 7.5 | 85 Ohms | TOP=L2:L3=L2/L4:L6=L5/L7:BOTTOM=L7 |
| PCIE_REFCLK_H2_P_R | CLK13-DIFF1 | PAIR | 4 | 5.5 | 5 | 10 | 5 | 12 | 6 | 20 | 12 | 12 | 12 | 12 | 7.5 | 85 Ohms | TOP=L2:L3=L2/L4:L6=L5/L7:BOTTOM=L7 |
| PCIE_REFCLK_H2_P_R | CLK13-DIFF1 | PAIR | 5 | 5.5 | 5 | 10 | 5 | 12 | 6 | 20 | 12 | 12 | 12 | 12 | 7.5 | 85 Ohms | TOP=L2:L3=L2/L4:L6=L5/L7:BOTTOM=L7 |
| PCIE_REFCLK_H2_P_R | CLK13-DIFF1 | PAIR | 6 | 5.5 | 5 | 10 | 5 | 12 | 6 | 20 | 12 | 12 | 12 | 12 | 7.5 | 85 Ohms | TOP=L2:L3=L2/L4:L6=L5/L7:BOTTOM=L7 |
| PCIE_REFCLK_H2_P_R | CLK13-DIFF1 | PAIR | 7 | 5.5 | 5 | 10 | 5 | 12 | 6 | 20 | 12 | 12 | 12 | 12 | 7.5 | 85 Ohms | TOP=L2:L3=L2/L4:L6=L5/L7:BOTTOM=L7 |
| PCIE_REFCLK_H2_P_R | CLK13-DIFF1 | PAIR | 8 | 5.38 | 5 | 10 | 5 | 12 | 6 | 33 | 12 | 12 | 12 | 12 | 6.62 | 85 Ohms | TOP=L2:L3=L2/L4:L6=L5/L7:BOTTOM=L7 |
| CLKGEN_N1_R | CLK14-DIFF1 | PAIR | 1 | 5.38 | 5 | 10 | 5 | 12 | 6 | 33 | 12 | 12 | 12 | 12 | 6.62 | 85 Ohms | TOP=L2:L3=L2/L4:L6=L5/L7:BOTTOM=L7 |
| CLKGEN_N1_R | CLK14-DIFF1 | PAIR | 2 | 5.5 | 5 | 10 | 5 | 12 | 6 | 20 | 12 | 12 | 12 | 12 | 7.5 | 85 Ohms | TOP=L2:L3=L2/L4:L6=L5/L7:BOTTOM=L7 |
| CLKGEN_N1_R | CLK14-DIFF1 | PAIR | 3 | 5.5 | 5 | 10 | 5 | 12 | 6 | 20 | 12 | 12 | 12 | 12 | 7.5 | 85 Ohms | TOP=L2:L3=L2/L4:L6=L5/L7:BOTTOM=L7 |
| CLKGEN_N1_R | CLK14-DIFF1 | PAIR | 4 | 5.5 | 5 | 10 | 5 | 12 | 6 | 20 | 12 | 12 | 12 | 12 | 7.5 | 85 Ohms | TOP=L2:L3=L2/L4:L6=L5/L7:BOTTOM=L7 |
| CLKGEN_N1_R | CLK14-DIFF1 | PAIR | 5 | 5.5 | 5 | 10 | 5 | 12 | 6 | 20 | 12 | 12 | 12 | 12 | 7.5 | 85 Ohms | TOP=L2:L3=L2/L4:L6=L5/L7:BOTTOM=L7 |
| CLKGEN_N1_R | CLK14-DIFF1 | PAIR | 6 | 5.5 | 5 | 10 | 5 | 12 | 6 | 20 | 12 | 12 | 12 | 12 | 7.5 | 85 Ohms | TOP=L2:L3=L2/L4:L6=L5/L7:BOTTOM=L7 |
| CLKGEN_N1_R | CLK14-DIFF1 | PAIR | 7 | 5.5 | 5 | 10 | 5 | 12 | 6 | 20 | 12 | 12 | 12 | 12 | 7.5 | 85 Ohms | TOP=L2:L3=L2/L4:L6=L5/L7:BOTTOM=L7 |
| CLKGEN_N1_R | CLK14-DIFF1 | PAIR | 8 | 5.38 | 5 | 10 | 5 | 12 | 6 | 33 | 12 | 12 | 12 | 12 | 6.62 | 85 Ohms | TOP=L2:L3=L2/L4:L6=L5/L7:BOTTOM=L7 |
| CLKGEN_P1_R | CLK14-DIFF1 | PAIR | 1 | 5.38 | 5 | 10 | 5 | 12 | 6 | 33 | 12 | 12 | 12 | 12 | 6.62 | 85 Ohms | TOP=L2:L3=L2/L4:L6=L5/L7:BOTTOM=L7 |
| CLKGEN_P1_R | CLK14-DIFF1 | PAIR | 2 | 5.5 | 5 | 10 | 5 | 12 | 6 | 20 | 12 | 12 | 12 | 12 | 7.5 | 85 Ohms | TOP=L2:L3=L2/L4:L6=L5/L7:BOTTOM=L7 |
| CLKGEN_P1_R | CLK14-DIFF1 | PAIR | 3 | 5.5 | 5 | 10 | 5 | 12 | 6 | 20 | 12 | 12 | 12 | 12 | 7.5 | 85 Ohms | TOP=L2:L3=L2/L4:L6=L5/L7:BOTTOM=L7 |
| CLKGEN_P1_R | CLK14-DIFF1 | PAIR | 4 | 5.5 | 5 | 10 | 5 | 12 | 6 | 20 | 12 | 12 | 12 | 12 | 7.5 | 85 Ohms | TOP=L2:L3=L2/L4:L6=L5/L7:BOTTOM=L7 |
| CLKGEN_P1_R | CLK14-DIFF1 | PAIR | 5 | 5.5 | 5 | 10 | 5 | 12 | 6 | 20 | 12 | 12 | 12 | 12 | 7.5 | 85 Ohms | TOP=L2:L3=L2/L4:L6=L5/L7:BOTTOM=L7 |
| CLKGEN_P1_R | CLK14-DIFF1 | PAIR | 6 | 5.5 | 5 | 10 | 5 | 12 | 6 | 20 | 12 | 12 | 12 | 12 | 7.5 | 85 Ohms | TOP=L2:L3=L2/L4:L6=L5/L7:BOTTOM=L7 |
| CLKGEN_P1_R | CLK14-DIFF1 | PAIR | 7 | 5.5 | 5 | 10 | 5 | 12 | 6 | 20 | 12 | 12 | 12 | 12 | 7.5 | 85 Ohms | TOP=L2:L3=L2/L4:L6=L5/L7:BOTTOM=L7 |
| CLKGEN_P1_R | CLK14-DIFF1 | PAIR | 8 | 5.38 | 5 | 10 | 5 | 12 | 6 | 33 | 12 | 12 | 12 | 12 | 6.62 | 85 Ohms | TOP=L2:L3=L2/L4:L6=L5/L7:BOTTOM=L7 |
| CLKGEN_N2 | CLK15-DIFF1 | PAIR | 1 | 5.38 | 5 | 10 | 5 | 12 | 6 | 33 | 12 | 12 | 12 | 12 | 6.62 | 85 Ohms | TOP=L2:L3=L2/L4:L6=L5/L7:BOTTOM=L7 |
| CLKGEN_N2 | CLK15-DIFF1 | PAIR | 2 | 5.5 | 5 | 10 | 5 | 12 | 6 | 20 | 12 | 12 | 12 | 12 | 7.5 | 85 Ohms | TOP=L2:L3=L2/L4:L6=L5/L7:BOTTOM=L7 |
| CLKGEN_N2 | CLK15-DIFF1 | PAIR | 3 | 5.5 | 5 | 10 | 5 | 12 | 6 | 20 | 12 | 12 | 12 | 12 | 7.5 | 85 Ohms | TOP=L2:L3=L2/L4:L6=L5/L7:BOTTOM=L7 |
| CLKGEN_N2 | CLK15-DIFF1 | PAIR | 4 | 5.5 | 5 | 10 | 5 | 12 | 6 | 20 | 12 | 12 | 12 | 12 | 7.5 | 85 Ohms | TOP=L2:L3=L2/L4:L6=L5/L7:BOTTOM=L7 |
| CLKGEN_N2 | CLK15-DIFF1 | PAIR | 5 | 5.5 | 5 | 10 | 5 | 12 | 6 | 20 | 12 | 12 | 12 | 12 | 7.5 | 85 Ohms | TOP=L2:L3=L2/L4:L6=L5/L7:BOTTOM=L7 |
| CLKGEN_N2 | CLK15-DIFF1 | PAIR | 6 | 5.5 | 5 | 10 | 5 | 12 | 6 | 20 | 12 | 12 | 12 | 12 | 7.5 | 85 Ohms | TOP=L2:L3=L2/L4:L6=L5/L7:BOTTOM=L7 |
| CLKGEN_N2 | CLK15-DIFF1 | PAIR | 7 | 5.5 | 5 | 10 | 5 | 12 | 6 | 20 | 12 | 12 | 12 | 12 | 7.5 | 85 Ohms | TOP=L2:L3=L2/L4:L6=L5/L7:BOTTOM=L7 |
| CLKGEN_N2 | CLK15-DIFF1 | PAIR | 8 | 5.38 | 5 | 10 | 5 | 12 | 6 | 33 | 12 | 12 | 12 | 12 | 6.62 | 85 Ohms | TOP=L2:L3=L2/L4:L6=L5/L7:BOTTOM=L7 |
| CLKGEN_P2 | CLK15-DIFF1 | PAIR | 1 | 5.38 | 5 | 10 | 5 | 12 | 6 | 33 | 12 | 12 | 12 | 12 | 6.62 | 85 Ohms | TOP=L2:L3=L2/L4:L6=L5/L7:BOTTOM=L7 |
| CLKGEN_P2 | CLK15-DIFF1 | PAIR | 2 | 5.5 | 5 | 10 | 5 | 12 | 6 | 20 | 12 | 12 | 12 | 12 | 7.5 | 85 Ohms | TOP=L2:L3=L2/L4:L6=L5/L7:BOTTOM=L7 |
| CLKGEN_P2 | CLK15-DIFF1 | PAIR | 3 | 5.5 | 5 | 10 | 5 | 12 | 6 | 20 | 12 | 12 | 12 | 12 | 7.5 | 85 Ohms | TOP=L2:L3=L2/L4:L6=L5/L7:BOTTOM=L7 |
| CLKGEN_P2 | CLK15-DIFF1 | PAIR | 4 | 5.5 | 5 | 10 | 5 | 12 | 6 | 20 | 12 | 12 | 12 | 12 | 7.5 | 85 Ohms | TOP=L2:L3=L2/L4:L6=L5/L7:BOTTOM=L7 |
| CLKGEN_P2 | CLK15-DIFF1 | PAIR | 5 | 5.5 | 5 | 10 | 5 | 12 | 6 | 20 | 12 | 12 | 12 | 12 | 7.5 | 85 Ohms | TOP=L2:L3=L2/L4:L6=L5/L7:BOTTOM=L7 |
| CLKGEN_P2 | CLK15-DIFF1 | PAIR | 6 | 5.5 | 5 | 10 | 5 | 12 | 6 | 20 | 12 | 12 | 12 | 12 | 7.5 | 85 Ohms | TOP=L2:L3=L2/L4:L6=L5/L7:BOTTOM=L7 |
| CLKGEN_P2 | CLK15-DIFF1 | PAIR | 7 | 5.5 | 5 | 10 | 5 | 12 | 6 | 20 | 12 | 12 | 12 | 12 | 7.5 | 85 Ohms | TOP=L2:L3=L2/L4:L6=L5/L7:BOTTOM=L7 |
| CLKGEN_P2 | CLK15-DIFF1 | PAIR | 8 | 5.38 | 5 | 10 | 5 | 12 | 6 | 33 | 12 | 12 | 12 | 12 | 6.62 | 85 Ohms | TOP=L2:L3=L2/L4:L6=L5/L7:BOTTOM=L7 |
| CLKGEN_N2_R | CLK16-DIFF1 | PAIR | 1 | 5.38 | 5 | 10 | 5 | 12 | 6 | 33 | 12 | 12 | 12 | 12 | 6.62 | 85 Ohms | TOP=L2:L3=L2/L4:L6=L5/L7:BOTTOM=L7 |
| CLKGEN_N2_R | CLK16-DIFF1 | PAIR | 2 | 5.5 | 5 | 10 | 5 | 12 | 6 | 20 | 12 | 12 | 12 | 12 | 7.5 | 85 Ohms | TOP=L2:L3=L2/L4:L6=L5/L7:BOTTOM=L7 |
| CLKGEN_N2_R | CLK16-DIFF1 | PAIR | 3 | 5.5 | 5 | 10 | 5 | 12 | 6 | 20 | 12 | 12 | 12 | 12 | 7.5 | 85 Ohms | TOP=L2:L3=L2/L4:L6=L5/L7:BOTTOM=L7 |
| CLKGEN_N2_R | CLK16-DIFF1 | PAIR | 4 | 5.5 | 5 | 10 | 5 | 12 | 6 | 20 | 12 | 12 | 12 | 12 | 7.5 | 85 Ohms | TOP=L2:L3=L2/L4:L6=L5/L7:BOTTOM=L7 |
| CLKGEN_N2_R | CLK16-DIFF1 | PAIR | 5 | 5.5 | 5 | 10 | 5 | 12 | 6 | 20 | 12 | 12 | 12 | 12 | 7.5 | 85 Ohms | TOP=L2:L3=L2/L4:L6=L5/L7:BOTTOM=L7 |
| CLKGEN_N2_R | CLK16-DIFF1 | PAIR | 6 | 5.5 | 5 | 10 | 5 | 12 | 6 | 20 | 12 | 12 | 12 | 12 | 7.5 | 85 Ohms | TOP=L2:L3=L2/L4:L6=L5/L7:BOTTOM=L7 |
| CLKGEN_N2_R | CLK16-DIFF1 | PAIR | 7 | 5.5 | 5 | 10 | 5 | 12 | 6 | 20 | 12 | 12 | 12 | 12 | 7.5 | 85 Ohms | TOP=L2:L3=L2/L4:L6=L5/L7:BOTTOM=L7 |
| CLKGEN_N2_R | CLK16-DIFF1 | PAIR | 8 | 5.38 | 5 | 10 | 5 | 12 | 6 | 33 | 12 | 12 | 12 | 12 | 6.62 | 85 Ohms | TOP=L2:L3=L2/L4:L6=L5/L7:BOTTOM=L7 |
| CLKGEN_P2_R | CLK16-DIFF1 | PAIR | 1 | 5.38 | 5 | 10 | 5 | 12 | 6 | 33 | 12 | 12 | 12 | 12 | 6.62 | 85 Ohms | TOP=L2:L3=L2/L4:L6=L5/L7:BOTTOM=L7 |
| CLKGEN_P2_R | CLK16-DIFF1 | PAIR | 2 | 5.5 | 5 | 10 | 5 | 12 | 6 | 20 | 12 | 12 | 12 | 12 | 7.5 | 85 Ohms | TOP=L2:L3=L2/L4:L6=L5/L7:BOTTOM=L7 |
| CLKGEN_P2_R | CLK16-DIFF1 | PAIR | 3 | 5.5 | 5 | 10 | 5 | 12 | 6 | 20 | 12 | 12 | 12 | 12 | 7.5 | 85 Ohms | TOP=L2:L3=L2/L4:L6=L5/L7:BOTTOM=L7 |
| CLKGEN_P2_R | CLK16-DIFF1 | PAIR | 4 | 5.5 | 5 | 10 | 5 | 12 | 6 | 20 | 12 | 12 | 12 | 12 | 7.5 | 85 Ohms | TOP=L2:L3=L2/L4:L6=L5/L7:BOTTOM=L7 |
| CLKGEN_P2_R | CLK16-DIFF1 | PAIR | 5 | 5.5 | 5 | 10 | 5 | 12 | 6 | 20 | 12 | 12 | 12 | 12 | 7.5 | 85 Ohms | TOP=L2:L3=L2/L4:L6=L5/L7:BOTTOM=L7 |
| CLKGEN_P2_R | CLK16-DIFF1 | PAIR | 6 | 5.5 | 5 | 10 | 5 | 12 | 6 | 20 | 12 | 12 | 12 | 12 | 7.5 | 85 Ohms | TOP=L2:L3=L2/L4:L6=L5/L7:BOTTOM=L7 |
| CLKGEN_P2_R | CLK16-DIFF1 | PAIR | 7 | 5.5 | 5 | 10 | 5 | 12 | 6 | 20 | 12 | 12 | 12 | 12 | 7.5 | 85 Ohms | TOP=L2:L3=L2/L4:L6=L5/L7:BOTTOM=L7 |
| CLKGEN_P2_R | CLK16-DIFF1 | PAIR | 8 | 5.38 | 5 | 10 | 5 | 12 | 6 | 33 | 12 | 12 | 12 | 12 | 6.62 | 85 Ohms | TOP=L2:L3=L2/L4:L6=L5/L7:BOTTOM=L7 |
| CLKGEN_N3 | CLK17-DIFF1 | PAIR | 1 | 5.38 | 5 | 10 | 5 | 12 | 6 | 33 | 12 | 12 | 12 | 12 | 6.62 | 85 Ohms | TOP=L2:L3=L2/L4:L6=L5/L7:BOTTOM=L7 |
| CLKGEN_N3 | CLK17-DIFF1 | PAIR | 2 | 5.5 | 5 | 10 | 5 | 12 | 6 | 20 | 12 | 12 | 12 | 12 | 7.5 | 85 Ohms | TOP=L2:L3=L2/L4:L6=L5/L7:BOTTOM=L7 |
| CLKGEN_N3 | CLK17-DIFF1 | PAIR | 3 | 5.5 | 5 | 10 | 5 | 12 | 6 | 20 | 12 | 12 | 12 | 12 | 7.5 | 85 Ohms | TOP=L2:L3=L2/L4:L6=L5/L7:BOTTOM=L7 |
| CLKGEN_N3 | CLK17-DIFF1 | PAIR | 4 | 5.5 | 5 | 10 | 5 | 12 | 6 | 20 | 12 | 12 | 12 | 12 | 7.5 | 85 Ohms | TOP=L2:L3=L2/L4:L6=L5/L7:BOTTOM=L7 |
| CLKGEN_N3 | CLK17-DIFF1 | PAIR | 5 | 5.5 | 5 | 10 | 5 | 12 | 6 | 20 | 12 | 12 | 12 | 12 | 7.5 | 85 Ohms | TOP=L2:L3=L2/L4:L6=L5/L7:BOTTOM=L7 |
| CLKGEN_N3 | CLK17-DIFF1 | PAIR | 6 | 5.5 | 5 | 10 | 5 | 12 | 6 | 20 | 12 | 12 | 12 | 12 | 7.5 | 85 Ohms | TOP=L2:L3=L2/L4:L6=L5/L7:BOTTOM=L7 |
| CLKGEN_N3 | CLK17-DIFF1 | PAIR | 7 | 5.5 | 5 | 10 | 5 | 12 | 6 | 20 | 12 | 12 | 12 | 12 | 7.5 | 85 Ohms | TOP=L2:L3=L2/L4:L6=L5/L7:BOTTOM=L7 |
| CLKGEN_N3 | CLK17-DIFF1 | PAIR | 8 | 5.38 | 5 | 10 | 5 | 12 | 6 | 33 | 12 | 12 | 12 | 12 | 6.62 | 85 Ohms | TOP=L2:L3=L2/L4:L6=L5/L7:BOTTOM=L7 |
| CLKGEN_P3 | CLK17-DIFF1 | PAIR | 1 | 5.38 | 5 | 10 | 5 | 12 | 6 | 33 | 12 | 12 | 12 | 12 | 6.62 | 85 Ohms | TOP=L2:L3=L2/L4:L6=L5/L7:BOTTOM=L7 |
| CLKGEN_P3 | CLK17-DIFF1 | PAIR | 2 | 5.5 | 5 | 10 | 5 | 12 | 6 | 20 | 12 | 12 | 12 | 12 | 7.5 | 85 Ohms | TOP=L2:L3=L2/L4:L6=L5/L7:BOTTOM=L7 |
| CLKGEN_P3 | CLK17-DIFF1 | PAIR | 3 | 5.5 | 5 | 10 | 5 | 12 | 6 | 20 | 12 | 12 | 12 | 12 | 7.5 | 85 Ohms | TOP=L2:L3=L2/L4:L6=L5/L7:BOTTOM=L7 |
| CLKGEN_P3 | CLK17-DIFF1 | PAIR | 4 | 5.5 | 5 | 10 | 5 | 12 | 6 | 20 | 12 | 12 | 12 | 12 | 7.5 | 85 Ohms | TOP=L2:L3=L2/L4:L6=L5/L7:BOTTOM=L7 |
| CLKGEN_P3 | CLK17-DIFF1 | PAIR | 5 | 5.5 | 5 | 10 | 5 | 12 | 6 | 20 | 12 | 12 | 12 | 12 | 7.5 | 85 Ohms | TOP=L2:L3=L2/L4:L6=L5/L7:BOTTOM=L7 |
| CLKGEN_P3 | CLK17-DIFF1 | PAIR | 6 | 5.5 | 5 | 10 | 5 | 12 | 6 | 20 | 12 | 12 | 12 | 12 | 7.5 | 85 Ohms | TOP=L2:L3=L2/L4:L6=L5/L7:BOTTOM=L7 |
| CLKGEN_P3 | CLK17-DIFF1 | PAIR | 7 | 5.5 | 5 | 10 | 5 | 12 | 6 | 20 | 12 | 12 | 12 | 12 | 7.5 | 85 Ohms | TOP=L2:L3=L2/L4:L6=L5/L7:BOTTOM=L7 |
| CLKGEN_P3 | CLK17-DIFF1 | PAIR | 8 | 5.38 | 5 | 10 | 5 | 12 | 6 | 33 | 12 | 12 | 12 | 12 | 6.62 | 85 Ohms | TOP=L2:L3=L2/L4:L6=L5/L7:BOTTOM=L7 |
| CLKGEN_N3_R | CLK18-DIFF1 | PAIR | 1 | 5.38 | 5 | 10 | 5 | 12 | 6 | 33 | 12 | 12 | 12 | 12 | 6.62 | 85 Ohms | TOP=L2:L3=L2/L4:L6=L5/L7:BOTTOM=L7 |
| CLKGEN_N3_R | CLK18-DIFF1 | PAIR | 2 | 5.5 | 5 | 10 | 5 | 12 | 6 | 20 | 12 | 12 | 12 | 12 | 7.5 | 85 Ohms | TOP=L2:L3=L2/L4:L6=L5/L7:BOTTOM=L7 |
| CLKGEN_N3_R | CLK18-DIFF1 | PAIR | 3 | 5.5 | 5 | 10 | 5 | 12 | 6 | 20 | 12 | 12 | 12 | 12 | 7.5 | 85 Ohms | TOP=L2:L3=L2/L4:L6=L5/L7:BOTTOM=L7 |
| CLKGEN_N3_R | CLK18-DIFF1 | PAIR | 4 | 5.5 | 5 | 10 | 5 | 12 | 6 | 20 | 12 | 12 | 12 | 12 | 7.5 | 85 Ohms | TOP=L2:L3=L2/L4:L6=L5/L7:BOTTOM=L7 |
| CLKGEN_N3_R | CLK18-DIFF1 | PAIR | 5 | 5.5 | 5 | 10 | 5 | 12 | 6 | 20 | 12 | 12 | 12 | 12 | 7.5 | 85 Ohms | TOP=L2:L3=L2/L4:L6=L5/L7:BOTTOM=L7 |
| CLKGEN_N3_R | CLK18-DIFF1 | PAIR | 6 | 5.5 | 5 | 10 | 5 | 12 | 6 | 20 | 12 | 12 | 12 | 12 | 7.5 | 85 Ohms | TOP=L2:L3=L2/L4:L6=L5/L7:BOTTOM=L7 |
| CLKGEN_N3_R | CLK18-DIFF1 | PAIR | 7 | 5.5 | 5 | 10 | 5 | 12 | 6 | 20 | 12 | 12 | 12 | 12 | 7.5 | 85 Ohms | TOP=L2:L3=L2/L4:L6=L5/L7:BOTTOM=L7 |
| CLKGEN_N3_R | CLK18-DIFF1 | PAIR | 8 | 5.38 | 5 | 10 | 5 | 12 | 6 | 33 | 12 | 12 | 12 | 12 | 6.62 | 85 Ohms | TOP=L2:L3=L2/L4:L6=L5/L7:BOTTOM=L7 |
| CLKGEN_P3_R | CLK18-DIFF1 | PAIR | 1 | 5.38 | 5 | 10 | 5 | 12 | 6 | 33 | 12 | 12 | 12 | 12 | 6.62 | 85 Ohms | TOP=L2:L3=L2/L4:L6=L5/L7:BOTTOM=L7 |
| CLKGEN_P3_R | CLK18-DIFF1 | PAIR | 2 | 5.5 | 5 | 10 | 5 | 12 | 6 | 20 | 12 | 12 | 12 | 12 | 7.5 | 85 Ohms | TOP=L2:L3=L2/L4:L6=L5/L7:BOTTOM=L7 |
| CLKGEN_P3_R | CLK18-DIFF1 | PAIR | 3 | 5.5 | 5 | 10 | 5 | 12 | 6 | 20 | 12 | 12 | 12 | 12 | 7.5 | 85 Ohms | TOP=L2:L3=L2/L4:L6=L5/L7:BOTTOM=L7 |
| CLKGEN_P3_R | CLK18-DIFF1 | PAIR | 4 | 5.5 | 5 | 10 | 5 | 12 | 6 | 20 | 12 | 12 | 12 | 12 | 7.5 | 85 Ohms | TOP=L2:L3=L2/L4:L6=L5/L7:BOTTOM=L7 |
| CLKGEN_P3_R | CLK18-DIFF1 | PAIR | 5 | 5.5 | 5 | 10 | 5 | 12 | 6 | 20 | 12 | 12 | 12 | 12 | 7.5 | 85 Ohms | TOP=L2:L3=L2/L4:L6=L5/L7:BOTTOM=L7 |
| CLKGEN_P3_R | CLK18-DIFF1 | PAIR | 6 | 5.5 | 5 | 10 | 5 | 12 | 6 | 20 | 12 | 12 | 12 | 12 | 7.5 | 85 Ohms | TOP=L2:L3=L2/L4:L6=L5/L7:BOTTOM=L7 |
| CLKGEN_P3_R | CLK18-DIFF1 | PAIR | 7 | 5.5 | 5 | 10 | 5 | 12 | 6 | 20 | 12 | 12 | 12 | 12 | 7.5 | 85 Ohms | TOP=L2:L3=L2/L4:L6=L5/L7:BOTTOM=L7 |
| CLKGEN_P3_R | CLK18-DIFF1 | PAIR | 8 | 5.38 | 5 | 10 | 5 | 12 | 6 | 33 | 12 | 12 | 12 | 12 | 6.62 | 85 Ohms | TOP=L2:L3=L2/L4:L6=L5/L7:BOTTOM=L7 |
| CLK_N_6 | CLK19-DIFF1 | PAIR | 1 | 5.38 | 5 | 10 | 5 | 12 | 6 | 33 | 12 | 12 | 12 | 12 | 6.62 | 85 Ohms | TOP=L2:L3=L2/L4:L6=L5/L7:BOTTOM=L7 |
| CLK_N_6 | CLK19-DIFF1 | PAIR | 2 | 5.5 | 5 | 10 | 5 | 12 | 6 | 20 | 12 | 12 | 12 | 12 | 7.5 | 85 Ohms | TOP=L2:L3=L2/L4:L6=L5/L7:BOTTOM=L7 |
| CLK_N_6 | CLK19-DIFF1 | PAIR | 3 | 5.5 | 5 | 10 | 5 | 12 | 6 | 20 | 12 | 12 | 12 | 12 | 7.5 | 85 Ohms | TOP=L2:L3=L2/L4:L6=L5/L7:BOTTOM=L7 |
| CLK_N_6 | CLK19-DIFF1 | PAIR | 4 | 5.5 | 5 | 10 | 5 | 12 | 6 | 20 | 12 | 12 | 12 | 12 | 7.5 | 85 Ohms | TOP=L2:L3=L2/L4:L6=L5/L7:BOTTOM=L7 |
| CLK_N_6 | CLK19-DIFF1 | PAIR | 5 | 5.5 | 5 | 10 | 5 | 12 | 6 | 20 | 12 | 12 | 12 | 12 | 7.5 | 85 Ohms | TOP=L2:L3=L2/L4:L6=L5/L7:BOTTOM=L7 |
| CLK_N_6 | CLK19-DIFF1 | PAIR | 6 | 5.5 | 5 | 10 | 5 | 12 | 6 | 20 | 12 | 12 | 12 | 12 | 7.5 | 85 Ohms | TOP=L2:L3=L2/L4:L6=L5/L7:BOTTOM=L7 |
| CLK_N_6 | CLK19-DIFF1 | PAIR | 7 | 5.5 | 5 | 10 | 5 | 12 | 6 | 20 | 12 | 12 | 12 | 12 | 7.5 | 85 Ohms | TOP=L2:L3=L2/L4:L6=L5/L7:BOTTOM=L7 |
| CLK_N_6 | CLK19-DIFF1 | PAIR | 8 | 5.38 | 5 | 10 | 5 | 12 | 6 | 33 | 12 | 12 | 12 | 12 | 6.62 | 85 Ohms | TOP=L2:L3=L2/L4:L6=L5/L7:BOTTOM=L7 |
| CLK_P_6 | CLK19-DIFF1 | PAIR | 1 | 5.38 | 5 | 10 | 5 | 12 | 6 | 33 | 12 | 12 | 12 | 12 | 6.62 | 85 Ohms | TOP=L2:L3=L2/L4:L6=L5/L7:BOTTOM=L7 |
| CLK_P_6 | CLK19-DIFF1 | PAIR | 2 | 5.5 | 5 | 10 | 5 | 12 | 6 | 20 | 12 | 12 | 12 | 12 | 7.5 | 85 Ohms | TOP=L2:L3=L2/L4:L6=L5/L7:BOTTOM=L7 |
| CLK_P_6 | CLK19-DIFF1 | PAIR | 3 | 5.5 | 5 | 10 | 5 | 12 | 6 | 20 | 12 | 12 | 12 | 12 | 7.5 | 85 Ohms | TOP=L2:L3=L2/L4:L6=L5/L7:BOTTOM=L7 |
| CLK_P_6 | CLK19-DIFF1 | PAIR | 4 | 5.5 | 5 | 10 | 5 | 12 | 6 | 20 | 12 | 12 | 12 | 12 | 7.5 | 85 Ohms | TOP=L2:L3=L2/L4:L6=L5/L7:BOTTOM=L7 |
| CLK_P_6 | CLK19-DIFF1 | PAIR | 5 | 5.5 | 5 | 10 | 5 | 12 | 6 | 20 | 12 | 12 | 12 | 12 | 7.5 | 85 Ohms | TOP=L2:L3=L2/L4:L6=L5/L7:BOTTOM=L7 |
| CLK_P_6 | CLK19-DIFF1 | PAIR | 6 | 5.5 | 5 | 10 | 5 | 12 | 6 | 20 | 12 | 12 | 12 | 12 | 7.5 | 85 Ohms | TOP=L2:L3=L2/L4:L6=L5/L7:BOTTOM=L7 |
| CLK_P_6 | CLK19-DIFF1 | PAIR | 7 | 5.5 | 5 | 10 | 5 | 12 | 6 | 20 | 12 | 12 | 12 | 12 | 7.5 | 85 Ohms | TOP=L2:L3=L2/L4:L6=L5/L7:BOTTOM=L7 |
| CLK_P_6 | CLK19-DIFF1 | PAIR | 8 | 5.38 | 5 | 10 | 5 | 12 | 6 | 33 | 12 | 12 | 12 | 12 | 6.62 | 85 Ohms | TOP=L2:L3=L2/L4:L6=L5/L7:BOTTOM=L7 |
| CLK_N_2 | CLK20-DIFF1 | PAIR | 1 | 5.38 | 5 | 10 | 5 | 12 | 6 | 33 | 12 | 12 | 12 | 12 | 6.62 | 85 Ohms | TOP=L2:L3=L2/L4:L6=L5/L7:BOTTOM=L7 |
| CLK_N_2 | CLK20-DIFF1 | PAIR | 2 | 5.5 | 5 | 10 | 5 | 12 | 6 | 20 | 12 | 12 | 12 | 12 | 7.5 | 85 Ohms | TOP=L2:L3=L2/L4:L6=L5/L7:BOTTOM=L7 |
| CLK_N_2 | CLK20-DIFF1 | PAIR | 3 | 5.5 | 5 | 10 | 5 | 12 | 6 | 20 | 12 | 12 | 12 | 12 | 7.5 | 85 Ohms | TOP=L2:L3=L2/L4:L6=L5/L7:BOTTOM=L7 |
| CLK_N_2 | CLK20-DIFF1 | PAIR | 4 | 5.5 | 5 | 10 | 5 | 12 | 6 | 20 | 12 | 12 | 12 | 12 | 7.5 | 85 Ohms | TOP=L2:L3=L2/L4:L6=L5/L7:BOTTOM=L7 |
| CLK_N_2 | CLK20-DIFF1 | PAIR | 5 | 5.5 | 5 | 10 | 5 | 12 | 6 | 20 | 12 | 12 | 12 | 12 | 7.5 | 85 Ohms | TOP=L2:L3=L2/L4:L6=L5/L7:BOTTOM=L7 |
| CLK_N_2 | CLK20-DIFF1 | PAIR | 6 | 5.5 | 5 | 10 | 5 | 12 | 6 | 20 | 12 | 12 | 12 | 12 | 7.5 | 85 Ohms | TOP=L2:L3=L2/L4:L6=L5/L7:BOTTOM=L7 |
| CLK_N_2 | CLK20-DIFF1 | PAIR | 7 | 5.5 | 5 | 10 | 5 | 12 | 6 | 20 | 12 | 12 | 12 | 12 | 7.5 | 85 Ohms | TOP=L2:L3=L2/L4:L6=L5/L7:BOTTOM=L7 |
| CLK_N_2 | CLK20-DIFF1 | PAIR | 8 | 5.38 | 5 | 10 | 5 | 12 | 6 | 33 | 12 | 12 | 12 | 12 | 6.62 | 85 Ohms | TOP=L2:L3=L2/L4:L6=L5/L7:BOTTOM=L7 |
| CLK_P_2 | CLK20-DIFF1 | PAIR | 1 | 5.38 | 5 | 10 | 5 | 12 | 6 | 33 | 12 | 12 | 12 | 12 | 6.62 | 85 Ohms | TOP=L2:L3=L2/L4:L6=L5/L7:BOTTOM=L7 |
| CLK_P_2 | CLK20-DIFF1 | PAIR | 2 | 5.5 | 5 | 10 | 5 | 12 | 6 | 20 | 12 | 12 | 12 | 12 | 7.5 | 85 Ohms | TOP=L2:L3=L2/L4:L6=L5/L7:BOTTOM=L7 |
| CLK_P_2 | CLK20-DIFF1 | PAIR | 3 | 5.5 | 5 | 10 | 5 | 12 | 6 | 20 | 12 | 12 | 12 | 12 | 7.5 | 85 Ohms | TOP=L2:L3=L2/L4:L6=L5/L7:BOTTOM=L7 |
| CLK_P_2 | CLK20-DIFF1 | PAIR | 4 | 5.5 | 5 | 10 | 5 | 12 | 6 | 20 | 12 | 12 | 12 | 12 | 7.5 | 85 Ohms | TOP=L2:L3=L2/L4:L6=L5/L7:BOTTOM=L7 |
| CLK_P_2 | CLK20-DIFF1 | PAIR | 5 | 5.5 | 5 | 10 | 5 | 12 | 6 | 20 | 12 | 12 | 12 | 12 | 7.5 | 85 Ohms | TOP=L2:L3=L2/L4:L6=L5/L7:BOTTOM=L7 |
| CLK_P_2 | CLK20-DIFF1 | PAIR | 6 | 5.5 | 5 | 10 | 5 | 12 | 6 | 20 | 12 | 12 | 12 | 12 | 7.5 | 85 Ohms | TOP=L2:L3=L2/L4:L6=L5/L7:BOTTOM=L7 |
| CLK_P_2 | CLK20-DIFF1 | PAIR | 7 | 5.5 | 5 | 10 | 5 | 12 | 6 | 20 | 12 | 12 | 12 | 12 | 7.5 | 85 Ohms | TOP=L2:L3=L2/L4:L6=L5/L7:BOTTOM=L7 |
| CLK_P_2 | CLK20-DIFF1 | PAIR | 8 | 5.38 | 5 | 10 | 5 | 12 | 6 | 33 | 12 | 12 | 12 | 12 | 6.62 | 85 Ohms | TOP=L2:L3=L2/L4:L6=L5/L7:BOTTOM=L7 |
| CLK_N_8 | CLK21-DIFF1 | PAIR | 1 | 5.38 | 5 | 10 | 5 | 12 | 6 | 33 | 12 | 12 | 12 | 12 | 6.62 | 85 Ohms | TOP=L2:L3=L2/L4:L6=L5/L7:BOTTOM=L7 |
| CLK_N_8 | CLK21-DIFF1 | PAIR | 2 | 5.5 | 5 | 10 | 5 | 12 | 6 | 20 | 12 | 12 | 12 | 12 | 7.5 | 85 Ohms | TOP=L2:L3=L2/L4:L6=L5/L7:BOTTOM=L7 |
| CLK_N_8 | CLK21-DIFF1 | PAIR | 3 | 5.5 | 5 | 10 | 5 | 12 | 6 | 20 | 12 | 12 | 12 | 12 | 7.5 | 85 Ohms | TOP=L2:L3=L2/L4:L6=L5/L7:BOTTOM=L7 |
| CLK_N_8 | CLK21-DIFF1 | PAIR | 4 | 5.5 | 5 | 10 | 5 | 12 | 6 | 20 | 12 | 12 | 12 | 12 | 7.5 | 85 Ohms | TOP=L2:L3=L2/L4:L6=L5/L7:BOTTOM=L7 |
| CLK_N_8 | CLK21-DIFF1 | PAIR | 5 | 5.5 | 5 | 10 | 5 | 12 | 6 | 20 | 12 | 12 | 12 | 12 | 7.5 | 85 Ohms | TOP=L2:L3=L2/L4:L6=L5/L7:BOTTOM=L7 |
| CLK_N_8 | CLK21-DIFF1 | PAIR | 6 | 5.5 | 5 | 10 | 5 | 12 | 6 | 20 | 12 | 12 | 12 | 12 | 7.5 | 85 Ohms | TOP=L2:L3=L2/L4:L6=L5/L7:BOTTOM=L7 |
| CLK_N_8 | CLK21-DIFF1 | PAIR | 7 | 5.5 | 5 | 10 | 5 | 12 | 6 | 20 | 12 | 12 | 12 | 12 | 7.5 | 85 Ohms | TOP=L2:L3=L2/L4:L6=L5/L7:BOTTOM=L7 |
| CLK_N_8 | CLK21-DIFF1 | PAIR | 8 | 5.38 | 5 | 10 | 5 | 12 | 6 | 33 | 12 | 12 | 12 | 12 | 6.62 | 85 Ohms | TOP=L2:L3=L2/L4:L6=L5/L7:BOTTOM=L7 |
| CLK_P_8 | CLK21-DIFF1 | PAIR | 1 | 5.38 | 5 | 10 | 5 | 12 | 6 | 33 | 12 | 12 | 12 | 12 | 6.62 | 85 Ohms | TOP=L2:L3=L2/L4:L6=L5/L7:BOTTOM=L7 |
| CLK_P_8 | CLK21-DIFF1 | PAIR | 2 | 5.5 | 5 | 10 | 5 | 12 | 6 | 20 | 12 | 12 | 12 | 12 | 7.5 | 85 Ohms | TOP=L2:L3=L2/L4:L6=L5/L7:BOTTOM=L7 |
| CLK_P_8 | CLK21-DIFF1 | PAIR | 3 | 5.5 | 5 | 10 | 5 | 12 | 6 | 20 | 12 | 12 | 12 | 12 | 7.5 | 85 Ohms | TOP=L2:L3=L2/L4:L6=L5/L7:BOTTOM=L7 |
| CLK_P_8 | CLK21-DIFF1 | PAIR | 4 | 5.5 | 5 | 10 | 5 | 12 | 6 | 20 | 12 | 12 | 12 | 12 | 7.5 | 85 Ohms | TOP=L2:L3=L2/L4:L6=L5/L7:BOTTOM=L7 |
| CLK_P_8 | CLK21-DIFF1 | PAIR | 5 | 5.5 | 5 | 10 | 5 | 12 | 6 | 20 | 12 | 12 | 12 | 12 | 7.5 | 85 Ohms | TOP=L2:L3=L2/L4:L6=L5/L7:BOTTOM=L7 |
| CLK_P_8 | CLK21-DIFF1 | PAIR | 6 | 5.5 | 5 | 10 | 5 | 12 | 6 | 20 | 12 | 12 | 12 | 12 | 7.5 | 85 Ohms | TOP=L2:L3=L2/L4:L6=L5/L7:BOTTOM=L7 |
| CLK_P_8 | CLK21-DIFF1 | PAIR | 7 | 5.5 | 5 | 10 | 5 | 12 | 6 | 20 | 12 | 12 | 12 | 12 | 7.5 | 85 Ohms | TOP=L2:L3=L2/L4:L6=L5/L7:BOTTOM=L7 |
| CLK_P_8 | CLK21-DIFF1 | PAIR | 8 | 5.38 | 5 | 10 | 5 | 12 | 6 | 33 | 12 | 12 | 12 | 12 | 6.62 | 85 Ohms | TOP=L2:L3=L2/L4:L6=L5/L7:BOTTOM=L7 |
| CLK_N_4 | CLK21-DIFF2 | PAIR | 1 | 5.38 | 5 | 10 | 5 | 12 | 6 | 33 | 12 | 12 | 12 | 12 | 6.62 | 85 Ohms | TOP=L2:L3=L2/L4:L6=L5/L7:BOTTOM=L7 |
| CLK_N_4 | CLK21-DIFF2 | PAIR | 2 | 5.5 | 5 | 10 | 5 | 12 | 6 | 20 | 12 | 12 | 12 | 12 | 7.5 | 85 Ohms | TOP=L2:L3=L2/L4:L6=L5/L7:BOTTOM=L7 |
| CLK_N_4 | CLK21-DIFF2 | PAIR | 3 | 5.5 | 5 | 10 | 5 | 12 | 6 | 20 | 12 | 12 | 12 | 12 | 7.5 | 85 Ohms | TOP=L2:L3=L2/L4:L6=L5/L7:BOTTOM=L7 |
| CLK_N_4 | CLK21-DIFF2 | PAIR | 4 | 5.5 | 5 | 10 | 5 | 12 | 6 | 20 | 12 | 12 | 12 | 12 | 7.5 | 85 Ohms | TOP=L2:L3=L2/L4:L6=L5/L7:BOTTOM=L7 |
| CLK_N_4 | CLK21-DIFF2 | PAIR | 5 | 5.5 | 5 | 10 | 5 | 12 | 6 | 20 | 12 | 12 | 12 | 12 | 7.5 | 85 Ohms | TOP=L2:L3=L2/L4:L6=L5/L7:BOTTOM=L7 |
| CLK_N_4 | CLK21-DIFF2 | PAIR | 6 | 5.5 | 5 | 10 | 5 | 12 | 6 | 20 | 12 | 12 | 12 | 12 | 7.5 | 85 Ohms | TOP=L2:L3=L2/L4:L6=L5/L7:BOTTOM=L7 |
| CLK_N_4 | CLK21-DIFF2 | PAIR | 7 | 5.5 | 5 | 10 | 5 | 12 | 6 | 20 | 12 | 12 | 12 | 12 | 7.5 | 85 Ohms | TOP=L2:L3=L2/L4:L6=L5/L7:BOTTOM=L7 |
| CLK_N_4 | CLK21-DIFF2 | PAIR | 8 | 5.38 | 5 | 10 | 5 | 12 | 6 | 33 | 12 | 12 | 12 | 12 | 6.62 | 85 Ohms | TOP=L2:L3=L2/L4:L6=L5/L7:BOTTOM=L7 |
| CLK_P_4 | CLK21-DIFF2 | PAIR | 1 | 5.38 | 5 | 10 | 5 | 12 | 6 | 33 | 12 | 12 | 12 | 12 | 6.62 | 85 Ohms | TOP=L2:L3=L2/L4:L6=L5/L7:BOTTOM=L7 |
| CLK_P_4 | CLK21-DIFF2 | PAIR | 2 | 5.5 | 5 | 10 | 5 | 12 | 6 | 20 | 12 | 12 | 12 | 12 | 7.5 | 85 Ohms | TOP=L2:L3=L2/L4:L6=L5/L7:BOTTOM=L7 |
| CLK_P_4 | CLK21-DIFF2 | PAIR | 3 | 5.5 | 5 | 10 | 5 | 12 | 6 | 20 | 12 | 12 | 12 | 12 | 7.5 | 85 Ohms | TOP=L2:L3=L2/L4:L6=L5/L7:BOTTOM=L7 |
| CLK_P_4 | CLK21-DIFF2 | PAIR | 4 | 5.5 | 5 | 10 | 5 | 12 | 6 | 20 | 12 | 12 | 12 | 12 | 7.5 | 85 Ohms | TOP=L2:L3=L2/L4:L6=L5/L7:BOTTOM=L7 |
| CLK_P_4 | CLK21-DIFF2 | PAIR | 5 | 5.5 | 5 | 10 | 5 | 12 | 6 | 20 | 12 | 12 | 12 | 12 | 7.5 | 85 Ohms | TOP=L2:L3=L2/L4:L6=L5/L7:BOTTOM=L7 |
| CLK_P_4 | CLK21-DIFF2 | PAIR | 6 | 5.5 | 5 | 10 | 5 | 12 | 6 | 20 | 12 | 12 | 12 | 12 | 7.5 | 85 Ohms | TOP=L2:L3=L2/L4:L6=L5/L7:BOTTOM=L7 |
| CLK_P_4 | CLK21-DIFF2 | PAIR | 7 | 5.5 | 5 | 10 | 5 | 12 | 6 | 20 | 12 | 12 | 12 | 12 | 7.5 | 85 Ohms | TOP=L2:L3=L2/L4:L6=L5/L7:BOTTOM=L7 |
| CLK_P_4 | CLK21-DIFF2 | PAIR | 8 | 5.38 | 5 | 10 | 5 | 12 | 6 | 33 | 12 | 12 | 12 | 12 | 6.62 | 85 Ohms | TOP=L2:L3=L2/L4:L6=L5/L7:BOTTOM=L7 |
| PCIE_REFCLK_H3_N_R | CLK22-DIFF1 | PAIR | 1 | 5.38 | 5 | 10 | 5 | 12 | 6 | 33 | 12 | 12 | 12 | 12 | 6.62 | 85 Ohms | TOP=L2:L3=L2/L4:L6=L5/L7:BOTTOM=L7 |
| PCIE_REFCLK_H3_N_R | CLK22-DIFF1 | PAIR | 2 | 5.5 | 5 | 10 | 5 | 12 | 6 | 20 | 12 | 12 | 12 | 12 | 7.5 | 85 Ohms | TOP=L2:L3=L2/L4:L6=L5/L7:BOTTOM=L7 |
| PCIE_REFCLK_H3_N_R | CLK22-DIFF1 | PAIR | 3 | 5.5 | 5 | 10 | 5 | 12 | 6 | 20 | 12 | 12 | 12 | 12 | 7.5 | 85 Ohms | TOP=L2:L3=L2/L4:L6=L5/L7:BOTTOM=L7 |
| PCIE_REFCLK_H3_N_R | CLK22-DIFF1 | PAIR | 4 | 5.5 | 5 | 10 | 5 | 12 | 6 | 20 | 12 | 12 | 12 | 12 | 7.5 | 85 Ohms | TOP=L2:L3=L2/L4:L6=L5/L7:BOTTOM=L7 |
| PCIE_REFCLK_H3_N_R | CLK22-DIFF1 | PAIR | 5 | 5.5 | 5 | 10 | 5 | 12 | 6 | 20 | 12 | 12 | 12 | 12 | 7.5 | 85 Ohms | TOP=L2:L3=L2/L4:L6=L5/L7:BOTTOM=L7 |
| PCIE_REFCLK_H3_N_R | CLK22-DIFF1 | PAIR | 6 | 5.5 | 5 | 10 | 5 | 12 | 6 | 20 | 12 | 12 | 12 | 12 | 7.5 | 85 Ohms | TOP=L2:L3=L2/L4:L6=L5/L7:BOTTOM=L7 |
| PCIE_REFCLK_H3_N_R | CLK22-DIFF1 | PAIR | 7 | 5.5 | 5 | 10 | 5 | 12 | 6 | 20 | 12 | 12 | 12 | 12 | 7.5 | 85 Ohms | TOP=L2:L3=L2/L4:L6=L5/L7:BOTTOM=L7 |
| PCIE_REFCLK_H3_N_R | CLK22-DIFF1 | PAIR | 8 | 5.38 | 5 | 10 | 5 | 12 | 6 | 33 | 12 | 12 | 12 | 12 | 6.62 | 85 Ohms | TOP=L2:L3=L2/L4:L6=L5/L7:BOTTOM=L7 |
| PCIE_REFCLK_H3_P_R | CLK22-DIFF1 | PAIR | 1 | 5.38 | 5 | 10 | 5 | 12 | 6 | 33 | 12 | 12 | 12 | 12 | 6.62 | 85 Ohms | TOP=L2:L3=L2/L4:L6=L5/L7:BOTTOM=L7 |
| PCIE_REFCLK_H3_P_R | CLK22-DIFF1 | PAIR | 2 | 5.5 | 5 | 10 | 5 | 12 | 6 | 20 | 12 | 12 | 12 | 12 | 7.5 | 85 Ohms | TOP=L2:L3=L2/L4:L6=L5/L7:BOTTOM=L7 |
| PCIE_REFCLK_H3_P_R | CLK22-DIFF1 | PAIR | 3 | 5.5 | 5 | 10 | 5 | 12 | 6 | 20 | 12 | 12 | 12 | 12 | 7.5 | 85 Ohms | TOP=L2:L3=L2/L4:L6=L5/L7:BOTTOM=L7 |
| PCIE_REFCLK_H3_P_R | CLK22-DIFF1 | PAIR | 4 | 5.5 | 5 | 10 | 5 | 12 | 6 | 20 | 12 | 12 | 12 | 12 | 7.5 | 85 Ohms | TOP=L2:L3=L2/L4:L6=L5/L7:BOTTOM=L7 |
| PCIE_REFCLK_H3_P_R | CLK22-DIFF1 | PAIR | 5 | 5.5 | 5 | 10 | 5 | 12 | 6 | 20 | 12 | 12 | 12 | 12 | 7.5 | 85 Ohms | TOP=L2:L3=L2/L4:L6=L5/L7:BOTTOM=L7 |
| PCIE_REFCLK_H3_P_R | CLK22-DIFF1 | PAIR | 6 | 5.5 | 5 | 10 | 5 | 12 | 6 | 20 | 12 | 12 | 12 | 12 | 7.5 | 85 Ohms | TOP=L2:L3=L2/L4:L6=L5/L7:BOTTOM=L7 |
| PCIE_REFCLK_H3_P_R | CLK22-DIFF1 | PAIR | 7 | 5.5 | 5 | 10 | 5 | 12 | 6 | 20 | 12 | 12 | 12 | 12 | 7.5 | 85 Ohms | TOP=L2:L3=L2/L4:L6=L5/L7:BOTTOM=L7 |
| PCIE_REFCLK_H3_P_R | CLK22-DIFF1 | PAIR | 8 | 5.38 | 5 | 10 | 5 | 12 | 6 | 33 | 12 | 12 | 12 | 12 | 6.62 | 85 Ohms | TOP=L2:L3=L2/L4:L6=L5/L7:BOTTOM=L7 |
| I210_REFCLK_D_N | CLK23-DIFF1 | PAIR | 1 | 5.38 | 5 | 10 | 5 | 12 | 6 | 33 | 12 | 12 | 12 | 12 | 6.62 | 85 Ohms | TOP=L2:L3=L2/L4:L6=L5/L7:BOTTOM=L7 |
| I210_REFCLK_D_N | CLK23-DIFF1 | PAIR | 2 | 5.5 | 5 | 10 | 5 | 12 | 6 | 20 | 12 | 12 | 12 | 12 | 7.5 | 85 Ohms | TOP=L2:L3=L2/L4:L6=L5/L7:BOTTOM=L7 |
| I210_REFCLK_D_N | CLK23-DIFF1 | PAIR | 3 | 5.5 | 5 | 10 | 5 | 12 | 6 | 20 | 12 | 12 | 12 | 12 | 7.5 | 85 Ohms | TOP=L2:L3=L2/L4:L6=L5/L7:BOTTOM=L7 |
| I210_REFCLK_D_N | CLK23-DIFF1 | PAIR | 4 | 5.5 | 5 | 10 | 5 | 12 | 6 | 20 | 12 | 12 | 12 | 12 | 7.5 | 85 Ohms | TOP=L2:L3=L2/L4:L6=L5/L7:BOTTOM=L7 |
| I210_REFCLK_D_N | CLK23-DIFF1 | PAIR | 5 | 5.5 | 5 | 10 | 5 | 12 | 6 | 20 | 12 | 12 | 12 | 12 | 7.5 | 85 Ohms | TOP=L2:L3=L2/L4:L6=L5/L7:BOTTOM=L7 |
| I210_REFCLK_D_N | CLK23-DIFF1 | PAIR | 6 | 5.5 | 5 | 10 | 5 | 12 | 6 | 20 | 12 | 12 | 12 | 12 | 7.5 | 85 Ohms | TOP=L2:L3=L2/L4:L6=L5/L7:BOTTOM=L7 |
| I210_REFCLK_D_N | CLK23-DIFF1 | PAIR | 7 | 5.5 | 5 | 10 | 5 | 12 | 6 | 20 | 12 | 12 | 12 | 12 | 7.5 | 85 Ohms | TOP=L2:L3=L2/L4:L6=L5/L7:BOTTOM=L7 |
| I210_REFCLK_D_N | CLK23-DIFF1 | PAIR | 8 | 5.38 | 5 | 10 | 5 | 12 | 6 | 33 | 12 | 12 | 12 | 12 | 6.62 | 85 Ohms | TOP=L2:L3=L2/L4:L6=L5/L7:BOTTOM=L7 |
| I210_REFCLK_D_P | CLK23-DIFF1 | PAIR | 1 | 5.38 | 5 | 10 | 5 | 12 | 6 | 33 | 12 | 12 | 12 | 12 | 6.62 | 85 Ohms | TOP=L2:L3=L2/L4:L6=L5/L7:BOTTOM=L7 |
| I210_REFCLK_D_P | CLK23-DIFF1 | PAIR | 2 | 5.5 | 5 | 10 | 5 | 12 | 6 | 20 | 12 | 12 | 12 | 12 | 7.5 | 85 Ohms | TOP=L2:L3=L2/L4:L6=L5/L7:BOTTOM=L7 |
| I210_REFCLK_D_P | CLK23-DIFF1 | PAIR | 3 | 5.5 | 5 | 10 | 5 | 12 | 6 | 20 | 12 | 12 | 12 | 12 | 7.5 | 85 Ohms | TOP=L2:L3=L2/L4:L6=L5/L7:BOTTOM=L7 |
| I210_REFCLK_D_P | CLK23-DIFF1 | PAIR | 4 | 5.5 | 5 | 10 | 5 | 12 | 6 | 20 | 12 | 12 | 12 | 12 | 7.5 | 85 Ohms | TOP=L2:L3=L2/L4:L6=L5/L7:BOTTOM=L7 |
| I210_REFCLK_D_P | CLK23-DIFF1 | PAIR | 5 | 5.5 | 5 | 10 | 5 | 12 | 6 | 20 | 12 | 12 | 12 | 12 | 7.5 | 85 Ohms | TOP=L2:L3=L2/L4:L6=L5/L7:BOTTOM=L7 |
| I210_REFCLK_D_P | CLK23-DIFF1 | PAIR | 6 | 5.5 | 5 | 10 | 5 | 12 | 6 | 20 | 12 | 12 | 12 | 12 | 7.5 | 85 Ohms | TOP=L2:L3=L2/L4:L6=L5/L7:BOTTOM=L7 |
| I210_REFCLK_D_P | CLK23-DIFF1 | PAIR | 7 | 5.5 | 5 | 10 | 5 | 12 | 6 | 20 | 12 | 12 | 12 | 12 | 7.5 | 85 Ohms | TOP=L2:L3=L2/L4:L6=L5/L7:BOTTOM=L7 |
| I210_REFCLK_D_P | CLK23-DIFF1 | PAIR | 8 | 5.38 | 5 | 10 | 5 | 12 | 6 | 33 | 12 | 12 | 12 | 12 | 6.62 | 85 Ohms | TOP=L2:L3=L2/L4:L6=L5/L7:BOTTOM=L7 |
| PCIE_REFCLK_H0_N_R | CLK24-DIFF1 | PAIR | 1 | 5.38 | 5 | 10 | 5 | 12 | 6 | 33 | 12 | 12 | 12 | 12 | 6.62 | 85 Ohms | TOP=L2:L3=L2/L4:L6=L5/L7:BOTTOM=L7 |
| PCIE_REFCLK_H0_N_R | CLK24-DIFF1 | PAIR | 2 | 5.5 | 5 | 10 | 5 | 12 | 6 | 20 | 12 | 12 | 12 | 12 | 7.5 | 85 Ohms | TOP=L2:L3=L2/L4:L6=L5/L7:BOTTOM=L7 |
| PCIE_REFCLK_H0_N_R | CLK24-DIFF1 | PAIR | 3 | 5.5 | 5 | 10 | 5 | 12 | 6 | 20 | 12 | 12 | 12 | 12 | 7.5 | 85 Ohms | TOP=L2:L3=L2/L4:L6=L5/L7:BOTTOM=L7 |
| PCIE_REFCLK_H0_N_R | CLK24-DIFF1 | PAIR | 4 | 5.5 | 5 | 10 | 5 | 12 | 6 | 20 | 12 | 12 | 12 | 12 | 7.5 | 85 Ohms | TOP=L2:L3=L2/L4:L6=L5/L7:BOTTOM=L7 |
| PCIE_REFCLK_H0_N_R | CLK24-DIFF1 | PAIR | 5 | 5.5 | 5 | 10 | 5 | 12 | 6 | 20 | 12 | 12 | 12 | 12 | 7.5 | 85 Ohms | TOP=L2:L3=L2/L4:L6=L5/L7:BOTTOM=L7 |
| PCIE_REFCLK_H0_N_R | CLK24-DIFF1 | PAIR | 6 | 5.5 | 5 | 10 | 5 | 12 | 6 | 20 | 12 | 12 | 12 | 12 | 7.5 | 85 Ohms | TOP=L2:L3=L2/L4:L6=L5/L7:BOTTOM=L7 |
| PCIE_REFCLK_H0_N_R | CLK24-DIFF1 | PAIR | 7 | 5.5 | 5 | 10 | 5 | 12 | 6 | 20 | 12 | 12 | 12 | 12 | 7.5 | 85 Ohms | TOP=L2:L3=L2/L4:L6=L5/L7:BOTTOM=L7 |
| PCIE_REFCLK_H0_N_R | CLK24-DIFF1 | PAIR | 8 | 5.38 | 5 | 10 | 5 | 12 | 6 | 33 | 12 | 12 | 12 | 12 | 6.62 | 85 Ohms | TOP=L2:L3=L2/L4:L6=L5/L7:BOTTOM=L7 |
| PCIE_REFCLK_H0_P_R | CLK24-DIFF1 | PAIR | 1 | 5.38 | 5 | 10 | 5 | 12 | 6 | 33 | 12 | 12 | 12 | 12 | 6.62 | 85 Ohms | TOP=L2:L3=L2/L4:L6=L5/L7:BOTTOM=L7 |
| PCIE_REFCLK_H0_P_R | CLK24-DIFF1 | PAIR | 2 | 5.5 | 5 | 10 | 5 | 12 | 6 | 20 | 12 | 12 | 12 | 12 | 7.5 | 85 Ohms | TOP=L2:L3=L2/L4:L6=L5/L7:BOTTOM=L7 |
| PCIE_REFCLK_H0_P_R | CLK24-DIFF1 | PAIR | 3 | 5.5 | 5 | 10 | 5 | 12 | 6 | 20 | 12 | 12 | 12 | 12 | 7.5 | 85 Ohms | TOP=L2:L3=L2/L4:L6=L5/L7:BOTTOM=L7 |
| PCIE_REFCLK_H0_P_R | CLK24-DIFF1 | PAIR | 4 | 5.5 | 5 | 10 | 5 | 12 | 6 | 20 | 12 | 12 | 12 | 12 | 7.5 | 85 Ohms | TOP=L2:L3=L2/L4:L6=L5/L7:BOTTOM=L7 |
| PCIE_REFCLK_H0_P_R | CLK24-DIFF1 | PAIR | 5 | 5.5 | 5 | 10 | 5 | 12 | 6 | 20 | 12 | 12 | 12 | 12 | 7.5 | 85 Ohms | TOP=L2:L3=L2/L4:L6=L5/L7:BOTTOM=L7 |
| PCIE_REFCLK_H0_P_R | CLK24-DIFF1 | PAIR | 6 | 5.5 | 5 | 10 | 5 | 12 | 6 | 20 | 12 | 12 | 12 | 12 | 7.5 | 85 Ohms | TOP=L2:L3=L2/L4:L6=L5/L7:BOTTOM=L7 |
| PCIE_REFCLK_H0_P_R | CLK24-DIFF1 | PAIR | 7 | 5.5 | 5 | 10 | 5 | 12 | 6 | 20 | 12 | 12 | 12 | 12 | 7.5 | 85 Ohms | TOP=L2:L3=L2/L4:L6=L5/L7:BOTTOM=L7 |
| PCIE_REFCLK_H0_P_R | CLK24-DIFF1 | PAIR | 8 | 5.38 | 5 | 10 | 5 | 12 | 6 | 33 | 12 | 12 | 12 | 12 | 6.62 | 85 Ohms | TOP=L2:L3=L2/L4:L6=L5/L7:BOTTOM=L7 |
| PCIE_REFCLK_H1_N_R | CLK25-DIFF1 | PAIR | 1 | 5.38 | 5 | 10 | 5 | 12 | 6 | 33 | 12 | 12 | 12 | 12 | 6.62 | 85 Ohms | TOP=L2:L3=L2/L4:L6=L5/L7:BOTTOM=L7 |
| PCIE_REFCLK_H1_N_R | CLK25-DIFF1 | PAIR | 2 | 5.5 | 5 | 10 | 5 | 12 | 6 | 20 | 12 | 12 | 12 | 12 | 7.5 | 85 Ohms | TOP=L2:L3=L2/L4:L6=L5/L7:BOTTOM=L7 |
| PCIE_REFCLK_H1_N_R | CLK25-DIFF1 | PAIR | 3 | 5.5 | 5 | 10 | 5 | 12 | 6 | 20 | 12 | 12 | 12 | 12 | 7.5 | 85 Ohms | TOP=L2:L3=L2/L4:L6=L5/L7:BOTTOM=L7 |
| PCIE_REFCLK_H1_N_R | CLK25-DIFF1 | PAIR | 4 | 5.5 | 5 | 10 | 5 | 12 | 6 | 20 | 12 | 12 | 12 | 12 | 7.5 | 85 Ohms | TOP=L2:L3=L2/L4:L6=L5/L7:BOTTOM=L7 |
| PCIE_REFCLK_H1_N_R | CLK25-DIFF1 | PAIR | 5 | 5.5 | 5 | 10 | 5 | 12 | 6 | 20 | 12 | 12 | 12 | 12 | 7.5 | 85 Ohms | TOP=L2:L3=L2/L4:L6=L5/L7:BOTTOM=L7 |
| PCIE_REFCLK_H1_N_R | CLK25-DIFF1 | PAIR | 6 | 5.5 | 5 | 10 | 5 | 12 | 6 | 20 | 12 | 12 | 12 | 12 | 7.5 | 85 Ohms | TOP=L2:L3=L2/L4:L6=L5/L7:BOTTOM=L7 |
| PCIE_REFCLK_H1_N_R | CLK25-DIFF1 | PAIR | 7 | 5.5 | 5 | 10 | 5 | 12 | 6 | 20 | 12 | 12 | 12 | 12 | 7.5 | 85 Ohms | TOP=L2:L3=L2/L4:L6=L5/L7:BOTTOM=L7 |
| PCIE_REFCLK_H1_N_R | CLK25-DIFF1 | PAIR | 8 | 5.38 | 5 | 10 | 5 | 12 | 6 | 33 | 12 | 12 | 12 | 12 | 6.62 | 85 Ohms | TOP=L2:L3=L2/L4:L6=L5/L7:BOTTOM=L7 |
| PCIE_REFCLK_H1_P_R | CLK25-DIFF1 | PAIR | 1 | 5.38 | 5 | 10 | 5 | 12 | 6 | 33 | 12 | 12 | 12 | 12 | 6.62 | 85 Ohms | TOP=L2:L3=L2/L4:L6=L5/L7:BOTTOM=L7 |
| PCIE_REFCLK_H1_P_R | CLK25-DIFF1 | PAIR | 2 | 5.5 | 5 | 10 | 5 | 12 | 6 | 20 | 12 | 12 | 12 | 12 | 7.5 | 85 Ohms | TOP=L2:L3=L2/L4:L6=L5/L7:BOTTOM=L7 |
| PCIE_REFCLK_H1_P_R | CLK25-DIFF1 | PAIR | 3 | 5.5 | 5 | 10 | 5 | 12 | 6 | 20 | 12 | 12 | 12 | 12 | 7.5 | 85 Ohms | TOP=L2:L3=L2/L4:L6=L5/L7:BOTTOM=L7 |
| PCIE_REFCLK_H1_P_R | CLK25-DIFF1 | PAIR | 4 | 5.5 | 5 | 10 | 5 | 12 | 6 | 20 | 12 | 12 | 12 | 12 | 7.5 | 85 Ohms | TOP=L2:L3=L2/L4:L6=L5/L7:BOTTOM=L7 |
| PCIE_REFCLK_H1_P_R | CLK25-DIFF1 | PAIR | 5 | 5.5 | 5 | 10 | 5 | 12 | 6 | 20 | 12 | 12 | 12 | 12 | 7.5 | 85 Ohms | TOP=L2:L3=L2/L4:L6=L5/L7:BOTTOM=L7 |
| PCIE_REFCLK_H1_P_R | CLK25-DIFF1 | PAIR | 6 | 5.5 | 5 | 10 | 5 | 12 | 6 | 20 | 12 | 12 | 12 | 12 | 7.5 | 85 Ohms | TOP=L2:L3=L2/L4:L6=L5/L7:BOTTOM=L7 |
| PCIE_REFCLK_H1_P_R | CLK25-DIFF1 | PAIR | 7 | 5.5 | 5 | 10 | 5 | 12 | 6 | 20 | 12 | 12 | 12 | 12 | 7.5 | 85 Ohms | TOP=L2:L3=L2/L4:L6=L5/L7:BOTTOM=L7 |
| PCIE_REFCLK_H1_P_R | CLK25-DIFF1 | PAIR | 8 | 5.38 | 5 | 10 | 5 | 12 | 6 | 33 | 12 | 12 | 12 | 12 | 6.62 | 85 Ohms | TOP=L2:L3=L2/L4:L6=L5/L7:BOTTOM=L7 |
| PCIE_RX_CAP_N78 | I210_TX-DIFF1 | PAIR | 1 | 5.38 | 5 | 10 | 5 | 12 | 6 | 33 | 12 | 12 | 12 | 12 | 6.62 | 85 Ohms | TOP=L2:L3=L2/L4:L6=L5/L7:BOTTOM=L7 |
| PCIE_RX_CAP_N78 | I210_TX-DIFF1 | PAIR | 2 | 5.5 | 5 | 10 | 5 | 12 | 6 | 20 | 12 | 12 | 12 | 12 | 7.5 | 85 Ohms | TOP=L2:L3=L2/L4:L6=L5/L7:BOTTOM=L7 |
| PCIE_RX_CAP_N78 | I210_TX-DIFF1 | PAIR | 3 | 5.5 | 5 | 10 | 5 | 12 | 6 | 20 | 12 | 12 | 12 | 12 | 7.5 | 85 Ohms | TOP=L2:L3=L2/L4:L6=L5/L7:BOTTOM=L7 |
| PCIE_RX_CAP_N78 | I210_TX-DIFF1 | PAIR | 4 | 5.5 | 5 | 10 | 5 | 12 | 6 | 20 | 12 | 12 | 12 | 12 | 7.5 | 85 Ohms | TOP=L2:L3=L2/L4:L6=L5/L7:BOTTOM=L7 |
| PCIE_RX_CAP_N78 | I210_TX-DIFF1 | PAIR | 5 | 5.5 | 5 | 10 | 5 | 12 | 6 | 20 | 12 | 12 | 12 | 12 | 7.5 | 85 Ohms | TOP=L2:L3=L2/L4:L6=L5/L7:BOTTOM=L7 |
| PCIE_RX_CAP_N78 | I210_TX-DIFF1 | PAIR | 6 | 5.5 | 5 | 10 | 5 | 12 | 6 | 20 | 12 | 12 | 12 | 12 | 7.5 | 85 Ohms | TOP=L2:L3=L2/L4:L6=L5/L7:BOTTOM=L7 |
| PCIE_RX_CAP_N78 | I210_TX-DIFF1 | PAIR | 7 | 5.5 | 5 | 10 | 5 | 12 | 6 | 20 | 12 | 12 | 12 | 12 | 7.5 | 85 Ohms | TOP=L2:L3=L2/L4:L6=L5/L7:BOTTOM=L7 |
| PCIE_RX_CAP_N78 | I210_TX-DIFF1 | PAIR | 8 | 5.38 | 5 | 10 | 5 | 12 | 6 | 33 | 12 | 12 | 12 | 12 | 6.62 | 85 Ohms | TOP=L2:L3=L2/L4:L6=L5/L7:BOTTOM=L7 |
| PCIE_RX_CAP_P78 | I210_TX-DIFF1 | PAIR | 1 | 5.38 | 5 | 10 | 5 | 12 | 6 | 33 | 12 | 12 | 12 | 12 | 6.62 | 85 Ohms | TOP=L2:L3=L2/L4:L6=L5/L7:BOTTOM=L7 |
| PCIE_RX_CAP_P78 | I210_TX-DIFF1 | PAIR | 2 | 5.5 | 5 | 10 | 5 | 12 | 6 | 20 | 12 | 12 | 12 | 12 | 7.5 | 85 Ohms | TOP=L2:L3=L2/L4:L6=L5/L7:BOTTOM=L7 |
| PCIE_RX_CAP_P78 | I210_TX-DIFF1 | PAIR | 3 | 5.5 | 5 | 10 | 5 | 12 | 6 | 20 | 12 | 12 | 12 | 12 | 7.5 | 85 Ohms | TOP=L2:L3=L2/L4:L6=L5/L7:BOTTOM=L7 |
| PCIE_RX_CAP_P78 | I210_TX-DIFF1 | PAIR | 4 | 5.5 | 5 | 10 | 5 | 12 | 6 | 20 | 12 | 12 | 12 | 12 | 7.5 | 85 Ohms | TOP=L2:L3=L2/L4:L6=L5/L7:BOTTOM=L7 |
| PCIE_RX_CAP_P78 | I210_TX-DIFF1 | PAIR | 5 | 5.5 | 5 | 10 | 5 | 12 | 6 | 20 | 12 | 12 | 12 | 12 | 7.5 | 85 Ohms | TOP=L2:L3=L2/L4:L6=L5/L7:BOTTOM=L7 |
| PCIE_RX_CAP_P78 | I210_TX-DIFF1 | PAIR | 6 | 5.5 | 5 | 10 | 5 | 12 | 6 | 20 | 12 | 12 | 12 | 12 | 7.5 | 85 Ohms | TOP=L2:L3=L2/L4:L6=L5/L7:BOTTOM=L7 |
| PCIE_RX_CAP_P78 | I210_TX-DIFF1 | PAIR | 7 | 5.5 | 5 | 10 | 5 | 12 | 6 | 20 | 12 | 12 | 12 | 12 | 7.5 | 85 Ohms | TOP=L2:L3=L2/L4:L6=L5/L7:BOTTOM=L7 |
| PCIE_RX_CAP_P78 | I210_TX-DIFF1 | PAIR | 8 | 5.38 | 5 | 10 | 5 | 12 | 6 | 33 | 12 | 12 | 12 | 12 | 6.62 | 85 Ohms | TOP=L2:L3=L2/L4:L6=L5/L7:BOTTOM=L7 |
| U55_SCL | I2C10-DIFF1 | PAIR | 1 | 4.75 | 5 | 10 | 5 | 14 | 6 | 9.5 | 12 | 12 | 12 | 12 | 15 |  |  |
| U55_SCL | I2C10-DIFF1 | PAIR | 2 | 5 | 5 | 10 | 5 | 14 | 6 | 10 | 12 | 12 | 12 | 12 | 15 |  |  |
| U55_SCL | I2C10-DIFF1 | PAIR | 3 | 5 | 5 | 10 | 5 | 14 | 6 | 10 | 12 | 12 | 12 | 12 | 15 |  |  |
| U55_SCL | I2C10-DIFF1 | PAIR | 4 | 5 | 5 | 10 | 5 | 14 | 6 | 10 | 12 | 12 | 12 | 12 | 15 |  |  |
| U55_SCL | I2C10-DIFF1 | PAIR | 5 | 5 | 5 | 10 | 5 | 14 | 6 | 10 | 12 | 12 | 12 | 12 | 15 |  |  |
| U55_SCL | I2C10-DIFF1 | PAIR | 6 | 5 | 5 | 10 | 5 | 14 | 6 | 10 | 12 | 12 | 12 | 12 | 15 |  |  |
| U55_SCL | I2C10-DIFF1 | PAIR | 7 | 5 | 5 | 10 | 5 | 14 | 6 | 10 | 12 | 12 | 12 | 12 | 15 |  |  |
| U55_SCL | I2C10-DIFF1 | PAIR | 8 | 4.75 | 5 | 10 | 5 | 14 | 6 | 9.5 | 12 | 12 | 12 | 12 | 15 |  |  |
| U55_SDA | I2C10-DIFF1 | PAIR | 1 | 4.75 | 5 | 10 | 5 | 14 | 6 | 9.5 | 12 | 12 | 12 | 12 | 15 |  |  |
| U55_SDA | I2C10-DIFF1 | PAIR | 2 | 5 | 5 | 10 | 5 | 14 | 6 | 10 | 12 | 12 | 12 | 12 | 15 |  |  |
| U55_SDA | I2C10-DIFF1 | PAIR | 3 | 5 | 5 | 10 | 5 | 14 | 6 | 10 | 12 | 12 | 12 | 12 | 15 |  |  |
| U55_SDA | I2C10-DIFF1 | PAIR | 4 | 5 | 5 | 10 | 5 | 14 | 6 | 10 | 12 | 12 | 12 | 12 | 15 |  |  |
| U55_SDA | I2C10-DIFF1 | PAIR | 5 | 5 | 5 | 10 | 5 | 14 | 6 | 10 | 12 | 12 | 12 | 12 | 15 |  |  |
| U55_SDA | I2C10-DIFF1 | PAIR | 6 | 5 | 5 | 10 | 5 | 14 | 6 | 10 | 12 | 12 | 12 | 12 | 15 |  |  |
| U55_SDA | I2C10-DIFF1 | PAIR | 7 | 5 | 5 | 10 | 5 | 14 | 6 | 10 | 12 | 12 | 12 | 12 | 15 |  |  |
| U55_SDA | I2C10-DIFF1 | PAIR | 8 | 4.75 | 5 | 10 | 5 | 14 | 6 | 9.5 | 12 | 12 | 12 | 12 | 15 |  |  |
| TWI_SCL0 | I2C11-DIFF1 | PAIR | 1 | 4.75 | 5 | 10 | 5 | 14 | 6 | 15 | 12 | 12 | 12 | 12 | 15 |  |  |
| TWI_SCL0 | I2C11-DIFF1 | PAIR | 2 | 5 | 5 | 10 | 5 | 14 | 6 | 15 | 12 | 12 | 12 | 12 | 15 |  |  |
| TWI_SCL0 | I2C11-DIFF1 | PAIR | 3 | 5 | 5 | 10 | 5 | 14 | 6 | 15 | 12 | 12 | 12 | 12 | 15 |  |  |
| TWI_SCL0 | I2C11-DIFF1 | PAIR | 4 | 5 | 5 | 10 | 5 | 14 | 6 | 15 | 12 | 12 | 12 | 12 | 15 |  |  |
| TWI_SCL0 | I2C11-DIFF1 | PAIR | 5 | 5 | 5 | 10 | 5 | 14 | 6 | 15 | 12 | 12 | 12 | 12 | 15 |  |  |
| TWI_SCL0 | I2C11-DIFF1 | PAIR | 6 | 5 | 5 | 10 | 5 | 14 | 6 | 15 | 12 | 12 | 12 | 12 | 15 |  |  |
| TWI_SCL0 | I2C11-DIFF1 | PAIR | 7 | 5 | 5 | 10 | 5 | 14 | 6 | 15 | 12 | 12 | 12 | 12 | 15 |  |  |
| TWI_SCL0 | I2C11-DIFF1 | PAIR | 8 | 4.75 | 5 | 10 | 5 | 14 | 6 | 15 | 12 | 12 | 12 | 12 | 15 |  |  |
| TWI_SDA0 | I2C11-DIFF1 | PAIR | 1 | 4.75 | 5 | 10 | 5 | 14 | 6 | 15 | 12 | 12 | 12 | 12 | 15 |  |  |
| TWI_SDA0 | I2C11-DIFF1 | PAIR | 2 | 5 | 5 | 10 | 5 | 14 | 6 | 15 | 12 | 12 | 12 | 12 | 15 |  |  |
| TWI_SDA0 | I2C11-DIFF1 | PAIR | 3 | 5 | 5 | 10 | 5 | 14 | 6 | 15 | 12 | 12 | 12 | 12 | 15 |  |  |
| TWI_SDA0 | I2C11-DIFF1 | PAIR | 4 | 5 | 5 | 10 | 5 | 14 | 6 | 15 | 12 | 12 | 12 | 12 | 15 |  |  |
| TWI_SDA0 | I2C11-DIFF1 | PAIR | 5 | 5 | 5 | 10 | 5 | 14 | 6 | 15 | 12 | 12 | 12 | 12 | 15 |  |  |
| TWI_SDA0 | I2C11-DIFF1 | PAIR | 6 | 5 | 5 | 10 | 5 | 14 | 6 | 15 | 12 | 12 | 12 | 12 | 15 |  |  |
| TWI_SDA0 | I2C11-DIFF1 | PAIR | 7 | 5 | 5 | 10 | 5 | 14 | 6 | 15 | 12 | 12 | 12 | 12 | 15 |  |  |
| TWI_SDA0 | I2C11-DIFF1 | PAIR | 8 | 4.75 | 5 | 10 | 5 | 14 | 6 | 15 | 12 | 12 | 12 | 12 | 15 |  |  |
| TWI_SCL1 | I2C12-DIFF1 | PAIR | 1 | 4.75 | 5 | 10 | 5 | 14 | 6 | 9.5 | 12 | 12 | 12 | 12 | 15 |  |  |
| TWI_SCL1 | I2C12-DIFF1 | PAIR | 2 | 5 | 5 | 10 | 5 | 14 | 6 | 10 | 12 | 12 | 12 | 12 | 15 |  |  |
| TWI_SCL1 | I2C12-DIFF1 | PAIR | 3 | 5 | 5 | 10 | 5 | 14 | 6 | 10 | 12 | 12 | 12 | 12 | 15 |  |  |
| TWI_SCL1 | I2C12-DIFF1 | PAIR | 4 | 5 | 5 | 10 | 5 | 14 | 6 | 10 | 12 | 12 | 12 | 12 | 15 |  |  |
| TWI_SCL1 | I2C12-DIFF1 | PAIR | 5 | 5 | 5 | 10 | 5 | 14 | 6 | 10 | 12 | 12 | 12 | 12 | 15 |  |  |
| TWI_SCL1 | I2C12-DIFF1 | PAIR | 6 | 5 | 5 | 10 | 5 | 14 | 6 | 10 | 12 | 12 | 12 | 12 | 15 |  |  |
| TWI_SCL1 | I2C12-DIFF1 | PAIR | 7 | 5 | 5 | 10 | 5 | 14 | 6 | 10 | 12 | 12 | 12 | 12 | 15 |  |  |
| TWI_SCL1 | I2C12-DIFF1 | PAIR | 8 | 4.75 | 5 | 10 | 5 | 14 | 6 | 9.5 | 12 | 12 | 12 | 12 | 15 |  |  |
| TWI_SDA1 | I2C12-DIFF1 | PAIR | 1 | 4.75 | 5 | 10 | 5 | 14 | 6 | 9.5 | 12 | 12 | 12 | 12 | 15 |  |  |
| TWI_SDA1 | I2C12-DIFF1 | PAIR | 2 | 5 | 5 | 10 | 5 | 14 | 6 | 10 | 12 | 12 | 12 | 12 | 15 |  |  |
| TWI_SDA1 | I2C12-DIFF1 | PAIR | 3 | 5 | 5 | 10 | 5 | 14 | 6 | 10 | 12 | 12 | 12 | 12 | 15 |  |  |
| TWI_SDA1 | I2C12-DIFF1 | PAIR | 4 | 5 | 5 | 10 | 5 | 14 | 6 | 10 | 12 | 12 | 12 | 12 | 15 |  |  |
| TWI_SDA1 | I2C12-DIFF1 | PAIR | 5 | 5 | 5 | 10 | 5 | 14 | 6 | 10 | 12 | 12 | 12 | 12 | 15 |  |  |
| TWI_SDA1 | I2C12-DIFF1 | PAIR | 6 | 5 | 5 | 10 | 5 | 14 | 6 | 10 | 12 | 12 | 12 | 12 | 15 |  |  |
| TWI_SDA1 | I2C12-DIFF1 | PAIR | 7 | 5 | 5 | 10 | 5 | 14 | 6 | 10 | 12 | 12 | 12 | 12 | 15 |  |  |
| TWI_SDA1 | I2C12-DIFF1 | PAIR | 8 | 4.75 | 5 | 10 | 5 | 14 | 6 | 9.5 | 12 | 12 | 12 | 12 | 15 |  |  |
| I2C_MAX6654_CLK | I2C13-DIFF1 | PAIR | 1 | 4.75 | 5 | 10 | 5 | 14 | 6 | 9.5 | 12 | 12 | 12 | 12 | 15 |  |  |
| I2C_MAX6654_CLK | I2C13-DIFF1 | PAIR | 2 | 5 | 5 | 10 | 5 | 14 | 6 | 10 | 12 | 12 | 12 | 12 | 15 |  |  |
| I2C_MAX6654_CLK | I2C13-DIFF1 | PAIR | 3 | 5 | 5 | 10 | 5 | 14 | 6 | 10 | 12 | 12 | 12 | 12 | 15 |  |  |
| I2C_MAX6654_CLK | I2C13-DIFF1 | PAIR | 4 | 5 | 5 | 10 | 5 | 14 | 6 | 10 | 12 | 12 | 12 | 12 | 15 |  |  |
| I2C_MAX6654_CLK | I2C13-DIFF1 | PAIR | 5 | 5 | 5 | 10 | 5 | 14 | 6 | 10 | 12 | 12 | 12 | 12 | 15 |  |  |
| I2C_MAX6654_CLK | I2C13-DIFF1 | PAIR | 6 | 5 | 5 | 10 | 5 | 14 | 6 | 10 | 12 | 12 | 12 | 12 | 15 |  |  |
| I2C_MAX6654_CLK | I2C13-DIFF1 | PAIR | 7 | 5 | 5 | 10 | 5 | 14 | 6 | 10 | 12 | 12 | 12 | 12 | 15 |  |  |
| I2C_MAX6654_CLK | I2C13-DIFF1 | PAIR | 8 | 4.75 | 5 | 10 | 5 | 14 | 6 | 9.5 | 12 | 12 | 12 | 12 | 15 |  |  |
| I2C_MAX6654_DAT | I2C13-DIFF1 | PAIR | 1 | 4.75 | 5 | 10 | 5 | 14 | 6 | 9.5 | 12 | 12 | 12 | 12 | 15 |  |  |
| I2C_MAX6654_DAT | I2C13-DIFF1 | PAIR | 2 | 5 | 5 | 10 | 5 | 14 | 6 | 10 | 12 | 12 | 12 | 12 | 15 |  |  |
| I2C_MAX6654_DAT | I2C13-DIFF1 | PAIR | 3 | 5 | 5 | 10 | 5 | 14 | 6 | 10 | 12 | 12 | 12 | 12 | 15 |  |  |
| I2C_MAX6654_DAT | I2C13-DIFF1 | PAIR | 4 | 5 | 5 | 10 | 5 | 14 | 6 | 10 | 12 | 12 | 12 | 12 | 15 |  |  |
| I2C_MAX6654_DAT | I2C13-DIFF1 | PAIR | 5 | 5 | 5 | 10 | 5 | 14 | 6 | 10 | 12 | 12 | 12 | 12 | 15 |  |  |
| I2C_MAX6654_DAT | I2C13-DIFF1 | PAIR | 6 | 5 | 5 | 10 | 5 | 14 | 6 | 10 | 12 | 12 | 12 | 12 | 15 |  |  |
| I2C_MAX6654_DAT | I2C13-DIFF1 | PAIR | 7 | 5 | 5 | 10 | 5 | 14 | 6 | 10 | 12 | 12 | 12 | 12 | 15 |  |  |
| I2C_MAX6654_DAT | I2C13-DIFF1 | PAIR | 8 | 4.75 | 5 | 10 | 5 | 14 | 6 | 9.5 | 12 | 12 | 12 | 12 | 15 |  |  |
| TWI_SCL4 | I2C14-DIFF1 | PAIR | 1 | 4.75 | 5 | 10 | 5 | 14 | 6 | 9.5 | 12 | 12 | 12 | 12 | 15 |  |  |
| TWI_SCL4 | I2C14-DIFF1 | PAIR | 2 | 5 | 5 | 10 | 5 | 14 | 6 | 10 | 12 | 12 | 12 | 12 | 15 |  |  |
| TWI_SCL4 | I2C14-DIFF1 | PAIR | 3 | 5 | 5 | 10 | 5 | 14 | 6 | 10 | 12 | 12 | 12 | 12 | 15 |  |  |
| TWI_SCL4 | I2C14-DIFF1 | PAIR | 4 | 5 | 5 | 10 | 5 | 14 | 6 | 10 | 12 | 12 | 12 | 12 | 15 |  |  |
| TWI_SCL4 | I2C14-DIFF1 | PAIR | 5 | 5 | 5 | 10 | 5 | 14 | 6 | 10 | 12 | 12 | 12 | 12 | 15 |  |  |
| TWI_SCL4 | I2C14-DIFF1 | PAIR | 6 | 5 | 5 | 10 | 5 | 14 | 6 | 10 | 12 | 12 | 12 | 12 | 15 |  |  |
| TWI_SCL4 | I2C14-DIFF1 | PAIR | 7 | 5 | 5 | 10 | 5 | 14 | 6 | 10 | 12 | 12 | 12 | 12 | 15 |  |  |
| TWI_SCL4 | I2C14-DIFF1 | PAIR | 8 | 4.75 | 5 | 10 | 5 | 14 | 6 | 9.5 | 12 | 12 | 12 | 12 | 15 |  |  |
| TWI_SDA4 | I2C14-DIFF1 | PAIR | 1 | 4.75 | 5 | 10 | 5 | 14 | 6 | 9.5 | 12 | 12 | 12 | 12 | 15 |  |  |
| TWI_SDA4 | I2C14-DIFF1 | PAIR | 2 | 5 | 5 | 10 | 5 | 14 | 6 | 10 | 12 | 12 | 12 | 12 | 15 |  |  |
| TWI_SDA4 | I2C14-DIFF1 | PAIR | 3 | 5 | 5 | 10 | 5 | 14 | 6 | 10 | 12 | 12 | 12 | 12 | 15 |  |  |
| TWI_SDA4 | I2C14-DIFF1 | PAIR | 4 | 5 | 5 | 10 | 5 | 14 | 6 | 10 | 12 | 12 | 12 | 12 | 15 |  |  |
| TWI_SDA4 | I2C14-DIFF1 | PAIR | 5 | 5 | 5 | 10 | 5 | 14 | 6 | 10 | 12 | 12 | 12 | 12 | 15 |  |  |
| TWI_SDA4 | I2C14-DIFF1 | PAIR | 6 | 5 | 5 | 10 | 5 | 14 | 6 | 10 | 12 | 12 | 12 | 12 | 15 |  |  |
| TWI_SDA4 | I2C14-DIFF1 | PAIR | 7 | 5 | 5 | 10 | 5 | 14 | 6 | 10 | 12 | 12 | 12 | 12 | 15 |  |  |
| TWI_SDA4 | I2C14-DIFF1 | PAIR | 8 | 4.75 | 5 | 10 | 5 | 14 | 6 | 9.5 | 12 | 12 | 12 | 12 | 15 |  |  |
| IPMB_CLK | I2C15-DIFF1 | PAIR | 1 | 4.75 | 5 | 10 | 5 | 14 | 6 | 9.5 | 12 | 12 | 12 | 12 | 15 |  |  |
| IPMB_CLK | I2C15-DIFF1 | PAIR | 2 | 5 | 5 | 10 | 5 | 14 | 6 | 10 | 12 | 12 | 12 | 12 | 15 |  |  |
| IPMB_CLK | I2C15-DIFF1 | PAIR | 3 | 5 | 5 | 10 | 5 | 14 | 6 | 10 | 12 | 12 | 12 | 12 | 15 |  |  |
| IPMB_CLK | I2C15-DIFF1 | PAIR | 4 | 5 | 5 | 10 | 5 | 14 | 6 | 10 | 12 | 12 | 12 | 12 | 15 |  |  |
| IPMB_CLK | I2C15-DIFF1 | PAIR | 5 | 5 | 5 | 10 | 5 | 14 | 6 | 10 | 12 | 12 | 12 | 12 | 15 |  |  |
| IPMB_CLK | I2C15-DIFF1 | PAIR | 6 | 5 | 5 | 10 | 5 | 14 | 6 | 10 | 12 | 12 | 12 | 12 | 15 |  |  |
| IPMB_CLK | I2C15-DIFF1 | PAIR | 7 | 5 | 5 | 10 | 5 | 14 | 6 | 10 | 12 | 12 | 12 | 12 | 15 |  |  |
| IPMB_CLK | I2C15-DIFF1 | PAIR | 8 | 4.75 | 5 | 10 | 5 | 14 | 6 | 9.5 | 12 | 12 | 12 | 12 | 15 |  |  |
| IPMB_DAT | I2C15-DIFF1 | PAIR | 1 | 4.75 | 5 | 10 | 5 | 14 | 6 | 9.5 | 12 | 12 | 12 | 12 | 15 |  |  |
| IPMB_DAT | I2C15-DIFF1 | PAIR | 2 | 5 | 5 | 10 | 5 | 14 | 6 | 10 | 12 | 12 | 12 | 12 | 15 |  |  |
| IPMB_DAT | I2C15-DIFF1 | PAIR | 3 | 5 | 5 | 10 | 5 | 14 | 6 | 10 | 12 | 12 | 12 | 12 | 15 |  |  |
| IPMB_DAT | I2C15-DIFF1 | PAIR | 4 | 5 | 5 | 10 | 5 | 14 | 6 | 10 | 12 | 12 | 12 | 12 | 15 |  |  |
| IPMB_DAT | I2C15-DIFF1 | PAIR | 5 | 5 | 5 | 10 | 5 | 14 | 6 | 10 | 12 | 12 | 12 | 12 | 15 |  |  |
| IPMB_DAT | I2C15-DIFF1 | PAIR | 6 | 5 | 5 | 10 | 5 | 14 | 6 | 10 | 12 | 12 | 12 | 12 | 15 |  |  |
| IPMB_DAT | I2C15-DIFF1 | PAIR | 7 | 5 | 5 | 10 | 5 | 14 | 6 | 10 | 12 | 12 | 12 | 12 | 15 |  |  |
| IPMB_DAT | I2C15-DIFF1 | PAIR | 8 | 4.75 | 5 | 10 | 5 | 14 | 6 | 9.5 | 12 | 12 | 12 | 12 | 15 |  |  |
| TWI_SCL10 | I2C20-DIFF1 | PAIR | 1 | 4.75 | 5 | 10 | 5 | 14 | 6 | 9.5 | 12 | 12 | 12 | 12 | 15 |  |  |
| TWI_SCL10 | I2C20-DIFF1 | PAIR | 2 | 5 | 5 | 10 | 5 | 14 | 6 | 10 | 12 | 12 | 12 | 12 | 15 |  |  |
| TWI_SCL10 | I2C20-DIFF1 | PAIR | 3 | 5 | 5 | 10 | 5 | 14 | 6 | 10 | 12 | 12 | 12 | 12 | 15 |  |  |
| TWI_SCL10 | I2C20-DIFF1 | PAIR | 4 | 5 | 5 | 10 | 5 | 14 | 6 | 10 | 12 | 12 | 12 | 12 | 15 |  |  |
| TWI_SCL10 | I2C20-DIFF1 | PAIR | 5 | 5 | 5 | 10 | 5 | 14 | 6 | 10 | 12 | 12 | 12 | 12 | 15 |  |  |
| TWI_SCL10 | I2C20-DIFF1 | PAIR | 6 | 5 | 5 | 10 | 5 | 14 | 6 | 10 | 12 | 12 | 12 | 12 | 15 |  |  |
| TWI_SCL10 | I2C20-DIFF1 | PAIR | 7 | 5 | 5 | 10 | 5 | 14 | 6 | 10 | 12 | 12 | 12 | 12 | 15 |  |  |
| TWI_SCL10 | I2C20-DIFF1 | PAIR | 8 | 4.75 | 5 | 10 | 5 | 14 | 6 | 9.5 | 12 | 12 | 12 | 12 | 15 |  |  |
| TWI_SDA10 | I2C20-DIFF1 | PAIR | 1 | 4.75 | 5 | 10 | 5 | 14 | 6 | 9.5 | 12 | 12 | 12 | 12 | 15 |  |  |
| TWI_SDA10 | I2C20-DIFF1 | PAIR | 2 | 5 | 5 | 10 | 5 | 14 | 6 | 10 | 12 | 12 | 12 | 12 | 15 |  |  |
| TWI_SDA10 | I2C20-DIFF1 | PAIR | 3 | 5 | 5 | 10 | 5 | 14 | 6 | 10 | 12 | 12 | 12 | 12 | 15 |  |  |
| TWI_SDA10 | I2C20-DIFF1 | PAIR | 4 | 5 | 5 | 10 | 5 | 14 | 6 | 10 | 12 | 12 | 12 | 12 | 15 |  |  |
| TWI_SDA10 | I2C20-DIFF1 | PAIR | 5 | 5 | 5 | 10 | 5 | 14 | 6 | 10 | 12 | 12 | 12 | 12 | 15 |  |  |
| TWI_SDA10 | I2C20-DIFF1 | PAIR | 6 | 5 | 5 | 10 | 5 | 14 | 6 | 10 | 12 | 12 | 12 | 12 | 15 |  |  |
| TWI_SDA10 | I2C20-DIFF1 | PAIR | 7 | 5 | 5 | 10 | 5 | 14 | 6 | 10 | 12 | 12 | 12 | 12 | 15 |  |  |
| TWI_SDA10 | I2C20-DIFF1 | PAIR | 8 | 4.75 | 5 | 10 | 5 | 14 | 6 | 9.5 | 12 | 12 | 12 | 12 | 15 |  |  |
| TEMP_1_SCL | I2C21-DIFF1 | PAIR | 1 | 4.75 | 5 | 10 | 5 | 14 | 6 | 9.5 | 12 | 12 | 12 | 12 | 15 |  |  |
| TEMP_1_SCL | I2C21-DIFF1 | PAIR | 2 | 5 | 5 | 10 | 5 | 14 | 6 | 10 | 12 | 12 | 12 | 12 | 15 |  |  |
| TEMP_1_SCL | I2C21-DIFF1 | PAIR | 3 | 5 | 5 | 10 | 5 | 14 | 6 | 10 | 12 | 12 | 12 | 12 | 15 |  |  |
| TEMP_1_SCL | I2C21-DIFF1 | PAIR | 4 | 5 | 5 | 10 | 5 | 14 | 6 | 10 | 12 | 12 | 12 | 12 | 15 |  |  |
| TEMP_1_SCL | I2C21-DIFF1 | PAIR | 5 | 5 | 5 | 10 | 5 | 14 | 6 | 10 | 12 | 12 | 12 | 12 | 15 |  |  |
| TEMP_1_SCL | I2C21-DIFF1 | PAIR | 6 | 5 | 5 | 10 | 5 | 14 | 6 | 10 | 12 | 12 | 12 | 12 | 15 |  |  |
| TEMP_1_SCL | I2C21-DIFF1 | PAIR | 7 | 5 | 5 | 10 | 5 | 14 | 6 | 10 | 12 | 12 | 12 | 12 | 15 |  |  |
| TEMP_1_SCL | I2C21-DIFF1 | PAIR | 8 | 4.75 | 5 | 10 | 5 | 14 | 6 | 9.5 | 12 | 12 | 12 | 12 | 15 |  |  |
| TEMP_1_SDA | I2C21-DIFF1 | PAIR | 1 | 4.75 | 5 | 10 | 5 | 14 | 6 | 9.5 | 12 | 12 | 12 | 12 | 15 |  |  |
| TEMP_1_SDA | I2C21-DIFF1 | PAIR | 2 | 5 | 5 | 10 | 5 | 14 | 6 | 10 | 12 | 12 | 12 | 12 | 15 |  |  |
| TEMP_1_SDA | I2C21-DIFF1 | PAIR | 3 | 5 | 5 | 10 | 5 | 14 | 6 | 10 | 12 | 12 | 12 | 12 | 15 |  |  |
| TEMP_1_SDA | I2C21-DIFF1 | PAIR | 4 | 5 | 5 | 10 | 5 | 14 | 6 | 10 | 12 | 12 | 12 | 12 | 15 |  |  |
| TEMP_1_SDA | I2C21-DIFF1 | PAIR | 5 | 5 | 5 | 10 | 5 | 14 | 6 | 10 | 12 | 12 | 12 | 12 | 15 |  |  |
| TEMP_1_SDA | I2C21-DIFF1 | PAIR | 6 | 5 | 5 | 10 | 5 | 14 | 6 | 10 | 12 | 12 | 12 | 12 | 15 |  |  |
| TEMP_1_SDA | I2C21-DIFF1 | PAIR | 7 | 5 | 5 | 10 | 5 | 14 | 6 | 10 | 12 | 12 | 12 | 12 | 15 |  |  |
| TEMP_1_SDA | I2C21-DIFF1 | PAIR | 8 | 4.75 | 5 | 10 | 5 | 14 | 6 | 9.5 | 12 | 12 | 12 | 12 | 15 |  |  |
| TEMP_2_SCL | I2C22-DIFF1 | PAIR | 1 | 4.75 | 5 | 10 | 5 | 14 | 6 | 9.5 | 12 | 12 | 12 | 12 | 15 |  |  |
| TEMP_2_SCL | I2C22-DIFF1 | PAIR | 2 | 5 | 5 | 10 | 5 | 14 | 6 | 10 | 12 | 12 | 12 | 12 | 15 |  |  |
| TEMP_2_SCL | I2C22-DIFF1 | PAIR | 3 | 5 | 5 | 10 | 5 | 14 | 6 | 10 | 12 | 12 | 12 | 12 | 15 |  |  |
| TEMP_2_SCL | I2C22-DIFF1 | PAIR | 4 | 5 | 5 | 10 | 5 | 14 | 6 | 10 | 12 | 12 | 12 | 12 | 15 |  |  |
| TEMP_2_SCL | I2C22-DIFF1 | PAIR | 5 | 5 | 5 | 10 | 5 | 14 | 6 | 10 | 12 | 12 | 12 | 12 | 15 |  |  |
| TEMP_2_SCL | I2C22-DIFF1 | PAIR | 6 | 5 | 5 | 10 | 5 | 14 | 6 | 10 | 12 | 12 | 12 | 12 | 15 |  |  |
| TEMP_2_SCL | I2C22-DIFF1 | PAIR | 7 | 5 | 5 | 10 | 5 | 14 | 6 | 10 | 12 | 12 | 12 | 12 | 15 |  |  |
| TEMP_2_SCL | I2C22-DIFF1 | PAIR | 8 | 4.75 | 5 | 10 | 5 | 14 | 6 | 9.5 | 12 | 12 | 12 | 12 | 15 |  |  |
| TEMP_2_SDA | I2C22-DIFF1 | PAIR | 1 | 4.75 | 5 | 10 | 5 | 14 | 6 | 9.5 | 12 | 12 | 12 | 12 | 15 |  |  |
| TEMP_2_SDA | I2C22-DIFF1 | PAIR | 2 | 5 | 5 | 10 | 5 | 14 | 6 | 10 | 12 | 12 | 12 | 12 | 15 |  |  |
| TEMP_2_SDA | I2C22-DIFF1 | PAIR | 3 | 5 | 5 | 10 | 5 | 14 | 6 | 10 | 12 | 12 | 12 | 12 | 15 |  |  |
| TEMP_2_SDA | I2C22-DIFF1 | PAIR | 4 | 5 | 5 | 10 | 5 | 14 | 6 | 10 | 12 | 12 | 12 | 12 | 15 |  |  |
| TEMP_2_SDA | I2C22-DIFF1 | PAIR | 5 | 5 | 5 | 10 | 5 | 14 | 6 | 10 | 12 | 12 | 12 | 12 | 15 |  |  |
| TEMP_2_SDA | I2C22-DIFF1 | PAIR | 6 | 5 | 5 | 10 | 5 | 14 | 6 | 10 | 12 | 12 | 12 | 12 | 15 |  |  |
| TEMP_2_SDA | I2C22-DIFF1 | PAIR | 7 | 5 | 5 | 10 | 5 | 14 | 6 | 10 | 12 | 12 | 12 | 12 | 15 |  |  |
| TEMP_2_SDA | I2C22-DIFF1 | PAIR | 8 | 4.75 | 5 | 10 | 5 | 14 | 6 | 9.5 | 12 | 12 | 12 | 12 | 15 |  |  |
| TEMP_3_SCL | I2C23-DIFF1 | PAIR | 1 | 4.75 | 5 | 10 | 5 | 14 | 6 | 9.5 | 12 | 12 | 12 | 12 | 15 |  |  |
| TEMP_3_SCL | I2C23-DIFF1 | PAIR | 2 | 5 | 5 | 10 | 5 | 14 | 6 | 10 | 12 | 12 | 12 | 12 | 15 |  |  |
| TEMP_3_SCL | I2C23-DIFF1 | PAIR | 3 | 5 | 5 | 10 | 5 | 14 | 6 | 10 | 12 | 12 | 12 | 12 | 15 |  |  |
| TEMP_3_SCL | I2C23-DIFF1 | PAIR | 4 | 5 | 5 | 10 | 5 | 14 | 6 | 10 | 12 | 12 | 12 | 12 | 15 |  |  |
| TEMP_3_SCL | I2C23-DIFF1 | PAIR | 5 | 5 | 5 | 10 | 5 | 14 | 6 | 10 | 12 | 12 | 12 | 12 | 15 |  |  |
| TEMP_3_SCL | I2C23-DIFF1 | PAIR | 6 | 5 | 5 | 10 | 5 | 14 | 6 | 10 | 12 | 12 | 12 | 12 | 15 |  |  |
| TEMP_3_SCL | I2C23-DIFF1 | PAIR | 7 | 5 | 5 | 10 | 5 | 14 | 6 | 10 | 12 | 12 | 12 | 12 | 15 |  |  |
| TEMP_3_SCL | I2C23-DIFF1 | PAIR | 8 | 4.75 | 5 | 10 | 5 | 14 | 6 | 9.5 | 12 | 12 | 12 | 12 | 15 |  |  |
| TEMP_3_SDA | I2C23-DIFF1 | PAIR | 1 | 4.75 | 5 | 10 | 5 | 14 | 6 | 9.5 | 12 | 12 | 12 | 12 | 15 |  |  |
| TEMP_3_SDA | I2C23-DIFF1 | PAIR | 2 | 5 | 5 | 10 | 5 | 14 | 6 | 10 | 12 | 12 | 12 | 12 | 15 |  |  |
| TEMP_3_SDA | I2C23-DIFF1 | PAIR | 3 | 5 | 5 | 10 | 5 | 14 | 6 | 10 | 12 | 12 | 12 | 12 | 15 |  |  |
| TEMP_3_SDA | I2C23-DIFF1 | PAIR | 4 | 5 | 5 | 10 | 5 | 14 | 6 | 10 | 12 | 12 | 12 | 12 | 15 |  |  |
| TEMP_3_SDA | I2C23-DIFF1 | PAIR | 5 | 5 | 5 | 10 | 5 | 14 | 6 | 10 | 12 | 12 | 12 | 12 | 15 |  |  |
| TEMP_3_SDA | I2C23-DIFF1 | PAIR | 6 | 5 | 5 | 10 | 5 | 14 | 6 | 10 | 12 | 12 | 12 | 12 | 15 |  |  |
| TEMP_3_SDA | I2C23-DIFF1 | PAIR | 7 | 5 | 5 | 10 | 5 | 14 | 6 | 10 | 12 | 12 | 12 | 12 | 15 |  |  |
| TEMP_3_SDA | I2C23-DIFF1 | PAIR | 8 | 4.75 | 5 | 10 | 5 | 14 | 6 | 9.5 | 12 | 12 | 12 | 12 | 15 |  |  |
| BMC_I2C10_8536_SCL | I2C24-DIFF1 | PAIR | 1 | 4.75 | 5 | 10 | 5 | 14 | 6 | 15 | 12 | 12 | 12 | 12 | 15 |  |  |
| BMC_I2C10_8536_SCL | I2C24-DIFF1 | PAIR | 2 | 5 | 5 | 10 | 5 | 14 | 6 | 15 | 12 | 12 | 12 | 12 | 15 |  |  |
| BMC_I2C10_8536_SCL | I2C24-DIFF1 | PAIR | 3 | 5 | 5 | 10 | 5 | 14 | 6 | 15 | 12 | 12 | 12 | 12 | 15 |  |  |
| BMC_I2C10_8536_SCL | I2C24-DIFF1 | PAIR | 4 | 5 | 5 | 10 | 5 | 14 | 6 | 15 | 12 | 12 | 12 | 12 | 15 |  |  |
| BMC_I2C10_8536_SCL | I2C24-DIFF1 | PAIR | 5 | 5 | 5 | 10 | 5 | 14 | 6 | 15 | 12 | 12 | 12 | 12 | 15 |  |  |
| BMC_I2C10_8536_SCL | I2C24-DIFF1 | PAIR | 6 | 5 | 5 | 10 | 5 | 14 | 6 | 15 | 12 | 12 | 12 | 12 | 15 |  |  |
| BMC_I2C10_8536_SCL | I2C24-DIFF1 | PAIR | 7 | 5 | 5 | 10 | 5 | 14 | 6 | 15 | 12 | 12 | 12 | 12 | 15 |  |  |
| BMC_I2C10_8536_SCL | I2C24-DIFF1 | PAIR | 8 | 4.75 | 5 | 10 | 5 | 14 | 6 | 15 | 12 | 12 | 12 | 12 | 15 |  |  |
| BMC_I2C10_8536_SDA | I2C24-DIFF1 | PAIR | 1 | 4.75 | 5 | 10 | 5 | 14 | 6 | 15 | 12 | 12 | 12 | 12 | 15 |  |  |
| BMC_I2C10_8536_SDA | I2C24-DIFF1 | PAIR | 2 | 5 | 5 | 10 | 5 | 14 | 6 | 15 | 12 | 12 | 12 | 12 | 15 |  |  |
| BMC_I2C10_8536_SDA | I2C24-DIFF1 | PAIR | 3 | 5 | 5 | 10 | 5 | 14 | 6 | 15 | 12 | 12 | 12 | 12 | 15 |  |  |
| BMC_I2C10_8536_SDA | I2C24-DIFF1 | PAIR | 4 | 5 | 5 | 10 | 5 | 14 | 6 | 15 | 12 | 12 | 12 | 12 | 15 |  |  |
| BMC_I2C10_8536_SDA | I2C24-DIFF1 | PAIR | 5 | 5 | 5 | 10 | 5 | 14 | 6 | 15 | 12 | 12 | 12 | 12 | 15 |  |  |
| BMC_I2C10_8536_SDA | I2C24-DIFF1 | PAIR | 6 | 5 | 5 | 10 | 5 | 14 | 6 | 15 | 12 | 12 | 12 | 12 | 15 |  |  |
| BMC_I2C10_8536_SDA | I2C24-DIFF1 | PAIR | 7 | 5 | 5 | 10 | 5 | 14 | 6 | 15 | 12 | 12 | 12 | 12 | 15 |  |  |
| BMC_I2C10_8536_SDA | I2C24-DIFF1 | PAIR | 8 | 4.75 | 5 | 10 | 5 | 14 | 6 | 15 | 12 | 12 | 12 | 12 | 15 |  |  |
| BMC0_SMB10_CLK | I2C25-DIFF1 | PAIR | 1 | 4.75 | 5 | 10 | 5 | 14 | 6 | 9.5 | 12 | 12 | 12 | 12 | 15 |  |  |
| BMC0_SMB10_CLK | I2C25-DIFF1 | PAIR | 2 | 5 | 5 | 10 | 5 | 14 | 6 | 10 | 12 | 12 | 12 | 12 | 15 |  |  |
| BMC0_SMB10_CLK | I2C25-DIFF1 | PAIR | 3 | 5 | 5 | 10 | 5 | 14 | 6 | 10 | 12 | 12 | 12 | 12 | 15 |  |  |
| BMC0_SMB10_CLK | I2C25-DIFF1 | PAIR | 4 | 5 | 5 | 10 | 5 | 14 | 6 | 10 | 12 | 12 | 12 | 12 | 15 |  |  |
| BMC0_SMB10_CLK | I2C25-DIFF1 | PAIR | 5 | 5 | 5 | 10 | 5 | 14 | 6 | 10 | 12 | 12 | 12 | 12 | 15 |  |  |
| BMC0_SMB10_CLK | I2C25-DIFF1 | PAIR | 6 | 5 | 5 | 10 | 5 | 14 | 6 | 10 | 12 | 12 | 12 | 12 | 15 |  |  |
| BMC0_SMB10_CLK | I2C25-DIFF1 | PAIR | 7 | 5 | 5 | 10 | 5 | 14 | 6 | 10 | 12 | 12 | 12 | 12 | 15 |  |  |
| BMC0_SMB10_CLK | I2C25-DIFF1 | PAIR | 8 | 4.75 | 5 | 10 | 5 | 14 | 6 | 9.5 | 12 | 12 | 12 | 12 | 15 |  |  |
| BMC0_SMB10_DAT | I2C25-DIFF1 | PAIR | 1 | 4.75 | 5 | 10 | 5 | 14 | 6 | 9.5 | 12 | 12 | 12 | 12 | 15 |  |  |
| BMC0_SMB10_DAT | I2C25-DIFF1 | PAIR | 2 | 5 | 5 | 10 | 5 | 14 | 6 | 10 | 12 | 12 | 12 | 12 | 15 |  |  |
| BMC0_SMB10_DAT | I2C25-DIFF1 | PAIR | 3 | 5 | 5 | 10 | 5 | 14 | 6 | 10 | 12 | 12 | 12 | 12 | 15 |  |  |
| BMC0_SMB10_DAT | I2C25-DIFF1 | PAIR | 4 | 5 | 5 | 10 | 5 | 14 | 6 | 10 | 12 | 12 | 12 | 12 | 15 |  |  |
| BMC0_SMB10_DAT | I2C25-DIFF1 | PAIR | 5 | 5 | 5 | 10 | 5 | 14 | 6 | 10 | 12 | 12 | 12 | 12 | 15 |  |  |
| BMC0_SMB10_DAT | I2C25-DIFF1 | PAIR | 6 | 5 | 5 | 10 | 5 | 14 | 6 | 10 | 12 | 12 | 12 | 12 | 15 |  |  |
| BMC0_SMB10_DAT | I2C25-DIFF1 | PAIR | 7 | 5 | 5 | 10 | 5 | 14 | 6 | 10 | 12 | 12 | 12 | 12 | 15 |  |  |
| BMC0_SMB10_DAT | I2C25-DIFF1 | PAIR | 8 | 4.75 | 5 | 10 | 5 | 14 | 6 | 9.5 | 12 | 12 | 12 | 12 | 15 |  |  |
| BMC0_SMB14_CLK | I2C26-DIFF1 | PAIR | 1 | 4.75 | 5 | 10 | 5 | 14 | 6 | 9.5 | 12 | 12 | 12 | 12 | 15 |  |  |
| BMC0_SMB14_CLK | I2C26-DIFF1 | PAIR | 2 | 5 | 5 | 10 | 5 | 14 | 6 | 10 | 12 | 12 | 12 | 12 | 15 |  |  |
| BMC0_SMB14_CLK | I2C26-DIFF1 | PAIR | 3 | 5 | 5 | 10 | 5 | 14 | 6 | 10 | 12 | 12 | 12 | 12 | 15 |  |  |
| BMC0_SMB14_CLK | I2C26-DIFF1 | PAIR | 4 | 5 | 5 | 10 | 5 | 14 | 6 | 10 | 12 | 12 | 12 | 12 | 15 |  |  |
| BMC0_SMB14_CLK | I2C26-DIFF1 | PAIR | 5 | 5 | 5 | 10 | 5 | 14 | 6 | 10 | 12 | 12 | 12 | 12 | 15 |  |  |
| BMC0_SMB14_CLK | I2C26-DIFF1 | PAIR | 6 | 5 | 5 | 10 | 5 | 14 | 6 | 10 | 12 | 12 | 12 | 12 | 15 |  |  |
| BMC0_SMB14_CLK | I2C26-DIFF1 | PAIR | 7 | 5 | 5 | 10 | 5 | 14 | 6 | 10 | 12 | 12 | 12 | 12 | 15 |  |  |
| BMC0_SMB14_CLK | I2C26-DIFF1 | PAIR | 8 | 4.75 | 5 | 10 | 5 | 14 | 6 | 9.5 | 12 | 12 | 12 | 12 | 15 |  |  |
| BMC0_SMB14_SDA | I2C26-DIFF1 | PAIR | 1 | 4.75 | 5 | 10 | 5 | 14 | 6 | 9.5 | 12 | 12 | 12 | 12 | 15 |  |  |
| BMC0_SMB14_SDA | I2C26-DIFF1 | PAIR | 2 | 5 | 5 | 10 | 5 | 14 | 6 | 10 | 12 | 12 | 12 | 12 | 15 |  |  |
| BMC0_SMB14_SDA | I2C26-DIFF1 | PAIR | 3 | 5 | 5 | 10 | 5 | 14 | 6 | 10 | 12 | 12 | 12 | 12 | 15 |  |  |
| BMC0_SMB14_SDA | I2C26-DIFF1 | PAIR | 4 | 5 | 5 | 10 | 5 | 14 | 6 | 10 | 12 | 12 | 12 | 12 | 15 |  |  |
| BMC0_SMB14_SDA | I2C26-DIFF1 | PAIR | 5 | 5 | 5 | 10 | 5 | 14 | 6 | 10 | 12 | 12 | 12 | 12 | 15 |  |  |
| BMC0_SMB14_SDA | I2C26-DIFF1 | PAIR | 6 | 5 | 5 | 10 | 5 | 14 | 6 | 10 | 12 | 12 | 12 | 12 | 15 |  |  |
| BMC0_SMB14_SDA | I2C26-DIFF1 | PAIR | 7 | 5 | 5 | 10 | 5 | 14 | 6 | 10 | 12 | 12 | 12 | 12 | 15 |  |  |
| BMC0_SMB14_SDA | I2C26-DIFF1 | PAIR | 8 | 4.75 | 5 | 10 | 5 | 14 | 6 | 9.5 | 12 | 12 | 12 | 12 | 15 |  |  |
| BMC0_SMB1_CLK | I2C27-DIFF1 | PAIR | 1 | 4.75 | 5 | 10 | 5 | 14 | 6 | 9.5 | 12 | 12 | 12 | 12 | 15 |  |  |
| BMC0_SMB1_CLK | I2C27-DIFF1 | PAIR | 2 | 5 | 5 | 10 | 5 | 14 | 6 | 10 | 12 | 12 | 12 | 12 | 15 |  |  |
| BMC0_SMB1_CLK | I2C27-DIFF1 | PAIR | 3 | 5 | 5 | 10 | 5 | 14 | 6 | 10 | 12 | 12 | 12 | 12 | 15 |  |  |
| BMC0_SMB1_CLK | I2C27-DIFF1 | PAIR | 4 | 5 | 5 | 10 | 5 | 14 | 6 | 10 | 12 | 12 | 12 | 12 | 15 |  |  |
| BMC0_SMB1_CLK | I2C27-DIFF1 | PAIR | 5 | 5 | 5 | 10 | 5 | 14 | 6 | 10 | 12 | 12 | 12 | 12 | 15 |  |  |
| BMC0_SMB1_CLK | I2C27-DIFF1 | PAIR | 6 | 5 | 5 | 10 | 5 | 14 | 6 | 10 | 12 | 12 | 12 | 12 | 15 |  |  |
| BMC0_SMB1_CLK | I2C27-DIFF1 | PAIR | 7 | 5 | 5 | 10 | 5 | 14 | 6 | 10 | 12 | 12 | 12 | 12 | 15 |  |  |
| BMC0_SMB1_CLK | I2C27-DIFF1 | PAIR | 8 | 4.75 | 5 | 10 | 5 | 14 | 6 | 9.5 | 12 | 12 | 12 | 12 | 15 |  |  |
| BMC0_SMB1_DAT | I2C27-DIFF1 | PAIR | 1 | 4.75 | 5 | 10 | 5 | 14 | 6 | 9.5 | 12 | 12 | 12 | 12 | 15 |  |  |
| BMC0_SMB1_DAT | I2C27-DIFF1 | PAIR | 2 | 5 | 5 | 10 | 5 | 14 | 6 | 10 | 12 | 12 | 12 | 12 | 15 |  |  |
| BMC0_SMB1_DAT | I2C27-DIFF1 | PAIR | 3 | 5 | 5 | 10 | 5 | 14 | 6 | 10 | 12 | 12 | 12 | 12 | 15 |  |  |
| BMC0_SMB1_DAT | I2C27-DIFF1 | PAIR | 4 | 5 | 5 | 10 | 5 | 14 | 6 | 10 | 12 | 12 | 12 | 12 | 15 |  |  |
| BMC0_SMB1_DAT | I2C27-DIFF1 | PAIR | 5 | 5 | 5 | 10 | 5 | 14 | 6 | 10 | 12 | 12 | 12 | 12 | 15 |  |  |
| BMC0_SMB1_DAT | I2C27-DIFF1 | PAIR | 6 | 5 | 5 | 10 | 5 | 14 | 6 | 10 | 12 | 12 | 12 | 12 | 15 |  |  |
| BMC0_SMB1_DAT | I2C27-DIFF1 | PAIR | 7 | 5 | 5 | 10 | 5 | 14 | 6 | 10 | 12 | 12 | 12 | 12 | 15 |  |  |
| BMC0_SMB1_DAT | I2C27-DIFF1 | PAIR | 8 | 4.75 | 5 | 10 | 5 | 14 | 6 | 9.5 | 12 | 12 | 12 | 12 | 15 |  |  |
| BMC0_SMB2_CLK | I2C28-DIFF1 | PAIR | 1 | 4.75 | 5 | 10 | 5 | 14 | 6 | 9.5 | 12 | 12 | 12 | 12 | 15 |  |  |
| BMC0_SMB2_CLK | I2C28-DIFF1 | PAIR | 2 | 5 | 5 | 10 | 5 | 14 | 6 | 10 | 12 | 12 | 12 | 12 | 15 |  |  |
| BMC0_SMB2_CLK | I2C28-DIFF1 | PAIR | 3 | 5 | 5 | 10 | 5 | 14 | 6 | 10 | 12 | 12 | 12 | 12 | 15 |  |  |
| BMC0_SMB2_CLK | I2C28-DIFF1 | PAIR | 4 | 5 | 5 | 10 | 5 | 14 | 6 | 10 | 12 | 12 | 12 | 12 | 15 |  |  |
| BMC0_SMB2_CLK | I2C28-DIFF1 | PAIR | 5 | 5 | 5 | 10 | 5 | 14 | 6 | 10 | 12 | 12 | 12 | 12 | 15 |  |  |
| BMC0_SMB2_CLK | I2C28-DIFF1 | PAIR | 6 | 5 | 5 | 10 | 5 | 14 | 6 | 10 | 12 | 12 | 12 | 12 | 15 |  |  |
| BMC0_SMB2_CLK | I2C28-DIFF1 | PAIR | 7 | 5 | 5 | 10 | 5 | 14 | 6 | 10 | 12 | 12 | 12 | 12 | 15 |  |  |
| BMC0_SMB2_CLK | I2C28-DIFF1 | PAIR | 8 | 4.75 | 5 | 10 | 5 | 14 | 6 | 9.5 | 12 | 12 | 12 | 12 | 15 |  |  |
| BMC0_SMB2_DAT | I2C28-DIFF1 | PAIR | 1 | 4.75 | 5 | 10 | 5 | 14 | 6 | 9.5 | 12 | 12 | 12 | 12 | 15 |  |  |
| BMC0_SMB2_DAT | I2C28-DIFF1 | PAIR | 2 | 5 | 5 | 10 | 5 | 14 | 6 | 10 | 12 | 12 | 12 | 12 | 15 |  |  |
| BMC0_SMB2_DAT | I2C28-DIFF1 | PAIR | 3 | 5 | 5 | 10 | 5 | 14 | 6 | 10 | 12 | 12 | 12 | 12 | 15 |  |  |
| BMC0_SMB2_DAT | I2C28-DIFF1 | PAIR | 4 | 5 | 5 | 10 | 5 | 14 | 6 | 10 | 12 | 12 | 12 | 12 | 15 |  |  |
| BMC0_SMB2_DAT | I2C28-DIFF1 | PAIR | 5 | 5 | 5 | 10 | 5 | 14 | 6 | 10 | 12 | 12 | 12 | 12 | 15 |  |  |
| BMC0_SMB2_DAT | I2C28-DIFF1 | PAIR | 6 | 5 | 5 | 10 | 5 | 14 | 6 | 10 | 12 | 12 | 12 | 12 | 15 |  |  |
| BMC0_SMB2_DAT | I2C28-DIFF1 | PAIR | 7 | 5 | 5 | 10 | 5 | 14 | 6 | 10 | 12 | 12 | 12 | 12 | 15 |  |  |
| BMC0_SMB2_DAT | I2C28-DIFF1 | PAIR | 8 | 4.75 | 5 | 10 | 5 | 14 | 6 | 9.5 | 12 | 12 | 12 | 12 | 15 |  |  |
| TWI_SCL2_R | I2C29-DIFF1 | PAIR | 1 | 4.75 | 5 | 10 | 5 | 14 | 6 | 9.5 | 12 | 12 | 12 | 12 | 15 |  |  |
| TWI_SCL2_R | I2C29-DIFF1 | PAIR | 2 | 5 | 5 | 10 | 5 | 14 | 6 | 10 | 12 | 12 | 12 | 12 | 15 |  |  |
| TWI_SCL2_R | I2C29-DIFF1 | PAIR | 3 | 5 | 5 | 10 | 5 | 14 | 6 | 10 | 12 | 12 | 12 | 12 | 15 |  |  |
| TWI_SCL2_R | I2C29-DIFF1 | PAIR | 4 | 5 | 5 | 10 | 5 | 14 | 6 | 10 | 12 | 12 | 12 | 12 | 15 |  |  |
| TWI_SCL2_R | I2C29-DIFF1 | PAIR | 5 | 5 | 5 | 10 | 5 | 14 | 6 | 10 | 12 | 12 | 12 | 12 | 15 |  |  |
| TWI_SCL2_R | I2C29-DIFF1 | PAIR | 6 | 5 | 5 | 10 | 5 | 14 | 6 | 10 | 12 | 12 | 12 | 12 | 15 |  |  |
| TWI_SCL2_R | I2C29-DIFF1 | PAIR | 7 | 5 | 5 | 10 | 5 | 14 | 6 | 10 | 12 | 12 | 12 | 12 | 15 |  |  |
| TWI_SCL2_R | I2C29-DIFF1 | PAIR | 8 | 4.75 | 5 | 10 | 5 | 14 | 6 | 9.5 | 12 | 12 | 12 | 12 | 15 |  |  |
| TWI_SDA2_R | I2C29-DIFF1 | PAIR | 1 | 4.75 | 5 | 10 | 5 | 14 | 6 | 9.5 | 12 | 12 | 12 | 12 | 15 |  |  |
| TWI_SDA2_R | I2C29-DIFF1 | PAIR | 2 | 5 | 5 | 10 | 5 | 14 | 6 | 10 | 12 | 12 | 12 | 12 | 15 |  |  |
| TWI_SDA2_R | I2C29-DIFF1 | PAIR | 3 | 5 | 5 | 10 | 5 | 14 | 6 | 10 | 12 | 12 | 12 | 12 | 15 |  |  |
| TWI_SDA2_R | I2C29-DIFF1 | PAIR | 4 | 5 | 5 | 10 | 5 | 14 | 6 | 10 | 12 | 12 | 12 | 12 | 15 |  |  |
| TWI_SDA2_R | I2C29-DIFF1 | PAIR | 5 | 5 | 5 | 10 | 5 | 14 | 6 | 10 | 12 | 12 | 12 | 12 | 15 |  |  |
| TWI_SDA2_R | I2C29-DIFF1 | PAIR | 6 | 5 | 5 | 10 | 5 | 14 | 6 | 10 | 12 | 12 | 12 | 12 | 15 |  |  |
| TWI_SDA2_R | I2C29-DIFF1 | PAIR | 7 | 5 | 5 | 10 | 5 | 14 | 6 | 10 | 12 | 12 | 12 | 12 | 15 |  |  |
| TWI_SDA2_R | I2C29-DIFF1 | PAIR | 8 | 4.75 | 5 | 10 | 5 | 14 | 6 | 9.5 | 12 | 12 | 12 | 12 | 15 |  |  |
| TWI_SCL2 | I2C2-DIFF1 | PAIR | 1 | 4.75 | 5 | 10 | 5 | 14 | 6 | 9.5 | 12 | 12 | 12 | 12 | 15 |  |  |
| TWI_SCL2 | I2C2-DIFF1 | PAIR | 2 | 5 | 5 | 10 | 5 | 14 | 6 | 10 | 12 | 12 | 12 | 12 | 15 |  |  |
| TWI_SCL2 | I2C2-DIFF1 | PAIR | 3 | 5 | 5 | 10 | 5 | 14 | 6 | 10 | 12 | 12 | 12 | 12 | 15 |  |  |
| TWI_SCL2 | I2C2-DIFF1 | PAIR | 4 | 5 | 5 | 10 | 5 | 14 | 6 | 10 | 12 | 12 | 12 | 12 | 15 |  |  |
| TWI_SCL2 | I2C2-DIFF1 | PAIR | 5 | 5 | 5 | 10 | 5 | 14 | 6 | 10 | 12 | 12 | 12 | 12 | 15 |  |  |
| TWI_SCL2 | I2C2-DIFF1 | PAIR | 6 | 5 | 5 | 10 | 5 | 14 | 6 | 10 | 12 | 12 | 12 | 12 | 15 |  |  |
| TWI_SCL2 | I2C2-DIFF1 | PAIR | 7 | 5 | 5 | 10 | 5 | 14 | 6 | 10 | 12 | 12 | 12 | 12 | 15 |  |  |
| TWI_SCL2 | I2C2-DIFF1 | PAIR | 8 | 4.75 | 5 | 10 | 5 | 14 | 6 | 9.5 | 12 | 12 | 12 | 12 | 15 |  |  |
| TWI_SDA2 | I2C2-DIFF1 | PAIR | 1 | 4.75 | 5 | 10 | 5 | 14 | 6 | 9.5 | 12 | 12 | 12 | 12 | 15 |  |  |
| TWI_SDA2 | I2C2-DIFF1 | PAIR | 2 | 5 | 5 | 10 | 5 | 14 | 6 | 10 | 12 | 12 | 12 | 12 | 15 |  |  |
| TWI_SDA2 | I2C2-DIFF1 | PAIR | 3 | 5 | 5 | 10 | 5 | 14 | 6 | 10 | 12 | 12 | 12 | 12 | 15 |  |  |
| TWI_SDA2 | I2C2-DIFF1 | PAIR | 4 | 5 | 5 | 10 | 5 | 14 | 6 | 10 | 12 | 12 | 12 | 12 | 15 |  |  |
| TWI_SDA2 | I2C2-DIFF1 | PAIR | 5 | 5 | 5 | 10 | 5 | 14 | 6 | 10 | 12 | 12 | 12 | 12 | 15 |  |  |
| TWI_SDA2 | I2C2-DIFF1 | PAIR | 6 | 5 | 5 | 10 | 5 | 14 | 6 | 10 | 12 | 12 | 12 | 12 | 15 |  |  |
| TWI_SDA2 | I2C2-DIFF1 | PAIR | 7 | 5 | 5 | 10 | 5 | 14 | 6 | 10 | 12 | 12 | 12 | 12 | 15 |  |  |
| TWI_SDA2 | I2C2-DIFF1 | PAIR | 8 | 4.75 | 5 | 10 | 5 | 14 | 6 | 9.5 | 12 | 12 | 12 | 12 | 15 |  |  |
| BMC0_SMB4_CLK | I2C30-DIFF1 | PAIR | 1 | 4.75 | 5 | 10 | 5 | 14 | 6 | 9.5 | 12 | 12 | 12 | 12 | 15 |  |  |
| BMC0_SMB4_CLK | I2C30-DIFF1 | PAIR | 2 | 5 | 5 | 10 | 5 | 14 | 6 | 10 | 12 | 12 | 12 | 12 | 15 |  |  |
| BMC0_SMB4_CLK | I2C30-DIFF1 | PAIR | 3 | 5 | 5 | 10 | 5 | 14 | 6 | 10 | 12 | 12 | 12 | 12 | 15 |  |  |
| BMC0_SMB4_CLK | I2C30-DIFF1 | PAIR | 4 | 5 | 5 | 10 | 5 | 14 | 6 | 10 | 12 | 12 | 12 | 12 | 15 |  |  |
| BMC0_SMB4_CLK | I2C30-DIFF1 | PAIR | 5 | 5 | 5 | 10 | 5 | 14 | 6 | 10 | 12 | 12 | 12 | 12 | 15 |  |  |
| BMC0_SMB4_CLK | I2C30-DIFF1 | PAIR | 6 | 5 | 5 | 10 | 5 | 14 | 6 | 10 | 12 | 12 | 12 | 12 | 15 |  |  |
| BMC0_SMB4_CLK | I2C30-DIFF1 | PAIR | 7 | 5 | 5 | 10 | 5 | 14 | 6 | 10 | 12 | 12 | 12 | 12 | 15 |  |  |
| BMC0_SMB4_CLK | I2C30-DIFF1 | PAIR | 8 | 4.75 | 5 | 10 | 5 | 14 | 6 | 9.5 | 12 | 12 | 12 | 12 | 15 |  |  |
| BMC0_SMB4_DAT | I2C30-DIFF1 | PAIR | 1 | 4.75 | 5 | 10 | 5 | 14 | 6 | 9.5 | 12 | 12 | 12 | 12 | 15 |  |  |
| BMC0_SMB4_DAT | I2C30-DIFF1 | PAIR | 2 | 5 | 5 | 10 | 5 | 14 | 6 | 10 | 12 | 12 | 12 | 12 | 15 |  |  |
| BMC0_SMB4_DAT | I2C30-DIFF1 | PAIR | 3 | 5 | 5 | 10 | 5 | 14 | 6 | 10 | 12 | 12 | 12 | 12 | 15 |  |  |
| BMC0_SMB4_DAT | I2C30-DIFF1 | PAIR | 4 | 5 | 5 | 10 | 5 | 14 | 6 | 10 | 12 | 12 | 12 | 12 | 15 |  |  |
| BMC0_SMB4_DAT | I2C30-DIFF1 | PAIR | 5 | 5 | 5 | 10 | 5 | 14 | 6 | 10 | 12 | 12 | 12 | 12 | 15 |  |  |
| BMC0_SMB4_DAT | I2C30-DIFF1 | PAIR | 6 | 5 | 5 | 10 | 5 | 14 | 6 | 10 | 12 | 12 | 12 | 12 | 15 |  |  |
| BMC0_SMB4_DAT | I2C30-DIFF1 | PAIR | 7 | 5 | 5 | 10 | 5 | 14 | 6 | 10 | 12 | 12 | 12 | 12 | 15 |  |  |
| BMC0_SMB4_DAT | I2C30-DIFF1 | PAIR | 8 | 4.75 | 5 | 10 | 5 | 14 | 6 | 9.5 | 12 | 12 | 12 | 12 | 15 |  |  |
| BMC0_SMB5_CLK | I2C31-DIFF1 | PAIR | 1 | 4.75 | 5 | 10 | 5 | 14 | 6 | 9.5 | 12 | 12 | 12 | 12 | 15 |  |  |
| BMC0_SMB5_CLK | I2C31-DIFF1 | PAIR | 2 | 5 | 5 | 10 | 5 | 14 | 6 | 10 | 12 | 12 | 12 | 12 | 15 |  |  |
| BMC0_SMB5_CLK | I2C31-DIFF1 | PAIR | 3 | 5 | 5 | 10 | 5 | 14 | 6 | 10 | 12 | 12 | 12 | 12 | 15 |  |  |
| BMC0_SMB5_CLK | I2C31-DIFF1 | PAIR | 4 | 5 | 5 | 10 | 5 | 14 | 6 | 10 | 12 | 12 | 12 | 12 | 15 |  |  |
| BMC0_SMB5_CLK | I2C31-DIFF1 | PAIR | 5 | 5 | 5 | 10 | 5 | 14 | 6 | 10 | 12 | 12 | 12 | 12 | 15 |  |  |
| BMC0_SMB5_CLK | I2C31-DIFF1 | PAIR | 6 | 5 | 5 | 10 | 5 | 14 | 6 | 10 | 12 | 12 | 12 | 12 | 15 |  |  |
| BMC0_SMB5_CLK | I2C31-DIFF1 | PAIR | 7 | 5 | 5 | 10 | 5 | 14 | 6 | 10 | 12 | 12 | 12 | 12 | 15 |  |  |
| BMC0_SMB5_CLK | I2C31-DIFF1 | PAIR | 8 | 4.75 | 5 | 10 | 5 | 14 | 6 | 9.5 | 12 | 12 | 12 | 12 | 15 |  |  |
| BMC0_SMB5_DAT | I2C31-DIFF1 | PAIR | 1 | 4.75 | 5 | 10 | 5 | 14 | 6 | 9.5 | 12 | 12 | 12 | 12 | 15 |  |  |
| BMC0_SMB5_DAT | I2C31-DIFF1 | PAIR | 2 | 5 | 5 | 10 | 5 | 14 | 6 | 10 | 12 | 12 | 12 | 12 | 15 |  |  |
| BMC0_SMB5_DAT | I2C31-DIFF1 | PAIR | 3 | 5 | 5 | 10 | 5 | 14 | 6 | 10 | 12 | 12 | 12 | 12 | 15 |  |  |
| BMC0_SMB5_DAT | I2C31-DIFF1 | PAIR | 4 | 5 | 5 | 10 | 5 | 14 | 6 | 10 | 12 | 12 | 12 | 12 | 15 |  |  |
| BMC0_SMB5_DAT | I2C31-DIFF1 | PAIR | 5 | 5 | 5 | 10 | 5 | 14 | 6 | 10 | 12 | 12 | 12 | 12 | 15 |  |  |
| BMC0_SMB5_DAT | I2C31-DIFF1 | PAIR | 6 | 5 | 5 | 10 | 5 | 14 | 6 | 10 | 12 | 12 | 12 | 12 | 15 |  |  |
| BMC0_SMB5_DAT | I2C31-DIFF1 | PAIR | 7 | 5 | 5 | 10 | 5 | 14 | 6 | 10 | 12 | 12 | 12 | 12 | 15 |  |  |
| BMC0_SMB5_DAT | I2C31-DIFF1 | PAIR | 8 | 4.75 | 5 | 10 | 5 | 14 | 6 | 9.5 | 12 | 12 | 12 | 12 | 15 |  |  |
| BMC0_SMB6_CLK | I2C32-DIFF1 | PAIR | 1 | 4.75 | 5 | 10 | 5 | 14 | 6 | 9.5 | 12 | 12 | 12 | 12 | 15 |  |  |
| BMC0_SMB6_CLK | I2C32-DIFF1 | PAIR | 2 | 5 | 5 | 10 | 5 | 14 | 6 | 10 | 12 | 12 | 12 | 12 | 15 |  |  |
| BMC0_SMB6_CLK | I2C32-DIFF1 | PAIR | 3 | 5 | 5 | 10 | 5 | 14 | 6 | 10 | 12 | 12 | 12 | 12 | 15 |  |  |
| BMC0_SMB6_CLK | I2C32-DIFF1 | PAIR | 4 | 5 | 5 | 10 | 5 | 14 | 6 | 10 | 12 | 12 | 12 | 12 | 15 |  |  |
| BMC0_SMB6_CLK | I2C32-DIFF1 | PAIR | 5 | 5 | 5 | 10 | 5 | 14 | 6 | 10 | 12 | 12 | 12 | 12 | 15 |  |  |
| BMC0_SMB6_CLK | I2C32-DIFF1 | PAIR | 6 | 5 | 5 | 10 | 5 | 14 | 6 | 10 | 12 | 12 | 12 | 12 | 15 |  |  |
| BMC0_SMB6_CLK | I2C32-DIFF1 | PAIR | 7 | 5 | 5 | 10 | 5 | 14 | 6 | 10 | 12 | 12 | 12 | 12 | 15 |  |  |
| BMC0_SMB6_CLK | I2C32-DIFF1 | PAIR | 8 | 4.75 | 5 | 10 | 5 | 14 | 6 | 9.5 | 12 | 12 | 12 | 12 | 15 |  |  |
| BMC0_SMB6_DAT | I2C32-DIFF1 | PAIR | 1 | 4.75 | 5 | 10 | 5 | 14 | 6 | 9.5 | 12 | 12 | 12 | 12 | 15 |  |  |
| BMC0_SMB6_DAT | I2C32-DIFF1 | PAIR | 2 | 5 | 5 | 10 | 5 | 14 | 6 | 10 | 12 | 12 | 12 | 12 | 15 |  |  |
| BMC0_SMB6_DAT | I2C32-DIFF1 | PAIR | 3 | 5 | 5 | 10 | 5 | 14 | 6 | 10 | 12 | 12 | 12 | 12 | 15 |  |  |
| BMC0_SMB6_DAT | I2C32-DIFF1 | PAIR | 4 | 5 | 5 | 10 | 5 | 14 | 6 | 10 | 12 | 12 | 12 | 12 | 15 |  |  |
| BMC0_SMB6_DAT | I2C32-DIFF1 | PAIR | 5 | 5 | 5 | 10 | 5 | 14 | 6 | 10 | 12 | 12 | 12 | 12 | 15 |  |  |
| BMC0_SMB6_DAT | I2C32-DIFF1 | PAIR | 6 | 5 | 5 | 10 | 5 | 14 | 6 | 10 | 12 | 12 | 12 | 12 | 15 |  |  |
| BMC0_SMB6_DAT | I2C32-DIFF1 | PAIR | 7 | 5 | 5 | 10 | 5 | 14 | 6 | 10 | 12 | 12 | 12 | 12 | 15 |  |  |
| BMC0_SMB6_DAT | I2C32-DIFF1 | PAIR | 8 | 4.75 | 5 | 10 | 5 | 14 | 6 | 9.5 | 12 | 12 | 12 | 12 | 15 |  |  |
| BMC0_SMB7_CLK | I2C33-DIFF1 | PAIR | 1 | 4.75 | 5 | 10 | 5 | 14 | 6 | 9.5 | 12 | 12 | 12 | 12 | 15 |  |  |
| BMC0_SMB7_CLK | I2C33-DIFF1 | PAIR | 2 | 5 | 5 | 10 | 5 | 14 | 6 | 10 | 12 | 12 | 12 | 12 | 15 |  |  |
| BMC0_SMB7_CLK | I2C33-DIFF1 | PAIR | 3 | 5 | 5 | 10 | 5 | 14 | 6 | 10 | 12 | 12 | 12 | 12 | 15 |  |  |
| BMC0_SMB7_CLK | I2C33-DIFF1 | PAIR | 4 | 5 | 5 | 10 | 5 | 14 | 6 | 10 | 12 | 12 | 12 | 12 | 15 |  |  |
| BMC0_SMB7_CLK | I2C33-DIFF1 | PAIR | 5 | 5 | 5 | 10 | 5 | 14 | 6 | 10 | 12 | 12 | 12 | 12 | 15 |  |  |
| BMC0_SMB7_CLK | I2C33-DIFF1 | PAIR | 6 | 5 | 5 | 10 | 5 | 14 | 6 | 10 | 12 | 12 | 12 | 12 | 15 |  |  |
| BMC0_SMB7_CLK | I2C33-DIFF1 | PAIR | 7 | 5 | 5 | 10 | 5 | 14 | 6 | 10 | 12 | 12 | 12 | 12 | 15 |  |  |
| BMC0_SMB7_CLK | I2C33-DIFF1 | PAIR | 8 | 4.75 | 5 | 10 | 5 | 14 | 6 | 9.5 | 12 | 12 | 12 | 12 | 15 |  |  |
| BMC0_SMB7_DAT | I2C33-DIFF1 | PAIR | 1 | 4.75 | 5 | 10 | 5 | 14 | 6 | 9.5 | 12 | 12 | 12 | 12 | 15 |  |  |
| BMC0_SMB7_DAT | I2C33-DIFF1 | PAIR | 2 | 5 | 5 | 10 | 5 | 14 | 6 | 10 | 12 | 12 | 12 | 12 | 15 |  |  |
| BMC0_SMB7_DAT | I2C33-DIFF1 | PAIR | 3 | 5 | 5 | 10 | 5 | 14 | 6 | 10 | 12 | 12 | 12 | 12 | 15 |  |  |
| BMC0_SMB7_DAT | I2C33-DIFF1 | PAIR | 4 | 5 | 5 | 10 | 5 | 14 | 6 | 10 | 12 | 12 | 12 | 12 | 15 |  |  |
| BMC0_SMB7_DAT | I2C33-DIFF1 | PAIR | 5 | 5 | 5 | 10 | 5 | 14 | 6 | 10 | 12 | 12 | 12 | 12 | 15 |  |  |
| BMC0_SMB7_DAT | I2C33-DIFF1 | PAIR | 6 | 5 | 5 | 10 | 5 | 14 | 6 | 10 | 12 | 12 | 12 | 12 | 15 |  |  |
| BMC0_SMB7_DAT | I2C33-DIFF1 | PAIR | 7 | 5 | 5 | 10 | 5 | 14 | 6 | 10 | 12 | 12 | 12 | 12 | 15 |  |  |
| BMC0_SMB7_DAT | I2C33-DIFF1 | PAIR | 8 | 4.75 | 5 | 10 | 5 | 14 | 6 | 9.5 | 12 | 12 | 12 | 12 | 15 |  |  |
| BMC0_SMB8_CLK | I2C34-DIFF1 | PAIR | 1 | 4.75 | 5 | 10 | 5 | 14 | 6 | 9.5 | 12 | 12 | 12 | 12 | 15 |  |  |
| BMC0_SMB8_CLK | I2C34-DIFF1 | PAIR | 2 | 5 | 5 | 10 | 5 | 14 | 6 | 10 | 12 | 12 | 12 | 12 | 15 |  |  |
| BMC0_SMB8_CLK | I2C34-DIFF1 | PAIR | 3 | 5 | 5 | 10 | 5 | 14 | 6 | 10 | 12 | 12 | 12 | 12 | 15 |  |  |
| BMC0_SMB8_CLK | I2C34-DIFF1 | PAIR | 4 | 5 | 5 | 10 | 5 | 14 | 6 | 10 | 12 | 12 | 12 | 12 | 15 |  |  |
| BMC0_SMB8_CLK | I2C34-DIFF1 | PAIR | 5 | 5 | 5 | 10 | 5 | 14 | 6 | 10 | 12 | 12 | 12 | 12 | 15 |  |  |
| BMC0_SMB8_CLK | I2C34-DIFF1 | PAIR | 6 | 5 | 5 | 10 | 5 | 14 | 6 | 10 | 12 | 12 | 12 | 12 | 15 |  |  |
| BMC0_SMB8_CLK | I2C34-DIFF1 | PAIR | 7 | 5 | 5 | 10 | 5 | 14 | 6 | 10 | 12 | 12 | 12 | 12 | 15 |  |  |
| BMC0_SMB8_CLK | I2C34-DIFF1 | PAIR | 8 | 4.75 | 5 | 10 | 5 | 14 | 6 | 9.5 | 12 | 12 | 12 | 12 | 15 |  |  |
| BMC0_SMB8_DAT | I2C34-DIFF1 | PAIR | 1 | 4.75 | 5 | 10 | 5 | 14 | 6 | 9.5 | 12 | 12 | 12 | 12 | 15 |  |  |
| BMC0_SMB8_DAT | I2C34-DIFF1 | PAIR | 2 | 5 | 5 | 10 | 5 | 14 | 6 | 10 | 12 | 12 | 12 | 12 | 15 |  |  |
| BMC0_SMB8_DAT | I2C34-DIFF1 | PAIR | 3 | 5 | 5 | 10 | 5 | 14 | 6 | 10 | 12 | 12 | 12 | 12 | 15 |  |  |
| BMC0_SMB8_DAT | I2C34-DIFF1 | PAIR | 4 | 5 | 5 | 10 | 5 | 14 | 6 | 10 | 12 | 12 | 12 | 12 | 15 |  |  |
| BMC0_SMB8_DAT | I2C34-DIFF1 | PAIR | 5 | 5 | 5 | 10 | 5 | 14 | 6 | 10 | 12 | 12 | 12 | 12 | 15 |  |  |
| BMC0_SMB8_DAT | I2C34-DIFF1 | PAIR | 6 | 5 | 5 | 10 | 5 | 14 | 6 | 10 | 12 | 12 | 12 | 12 | 15 |  |  |
| BMC0_SMB8_DAT | I2C34-DIFF1 | PAIR | 7 | 5 | 5 | 10 | 5 | 14 | 6 | 10 | 12 | 12 | 12 | 12 | 15 |  |  |
| BMC0_SMB8_DAT | I2C34-DIFF1 | PAIR | 8 | 4.75 | 5 | 10 | 5 | 14 | 6 | 9.5 | 12 | 12 | 12 | 12 | 15 |  |  |
| BMC0_SMB9_CLK | I2C35-DIFF1 | PAIR | 1 | 4.75 | 5 | 10 | 5 | 14 | 6 | 9.5 | 12 | 12 | 12 | 12 | 15 |  |  |
| BMC0_SMB9_CLK | I2C35-DIFF1 | PAIR | 2 | 5 | 5 | 10 | 5 | 14 | 6 | 10 | 12 | 12 | 12 | 12 | 15 |  |  |
| BMC0_SMB9_CLK | I2C35-DIFF1 | PAIR | 3 | 5 | 5 | 10 | 5 | 14 | 6 | 10 | 12 | 12 | 12 | 12 | 15 |  |  |
| BMC0_SMB9_CLK | I2C35-DIFF1 | PAIR | 4 | 5 | 5 | 10 | 5 | 14 | 6 | 10 | 12 | 12 | 12 | 12 | 15 |  |  |
| BMC0_SMB9_CLK | I2C35-DIFF1 | PAIR | 5 | 5 | 5 | 10 | 5 | 14 | 6 | 10 | 12 | 12 | 12 | 12 | 15 |  |  |
| BMC0_SMB9_CLK | I2C35-DIFF1 | PAIR | 6 | 5 | 5 | 10 | 5 | 14 | 6 | 10 | 12 | 12 | 12 | 12 | 15 |  |  |
| BMC0_SMB9_CLK | I2C35-DIFF1 | PAIR | 7 | 5 | 5 | 10 | 5 | 14 | 6 | 10 | 12 | 12 | 12 | 12 | 15 |  |  |
| BMC0_SMB9_CLK | I2C35-DIFF1 | PAIR | 8 | 4.75 | 5 | 10 | 5 | 14 | 6 | 9.5 | 12 | 12 | 12 | 12 | 15 |  |  |
| BMC0_SMB9_DAT | I2C35-DIFF1 | PAIR | 1 | 4.75 | 5 | 10 | 5 | 14 | 6 | 9.5 | 12 | 12 | 12 | 12 | 15 |  |  |
| BMC0_SMB9_DAT | I2C35-DIFF1 | PAIR | 2 | 5 | 5 | 10 | 5 | 14 | 6 | 10 | 12 | 12 | 12 | 12 | 15 |  |  |
| BMC0_SMB9_DAT | I2C35-DIFF1 | PAIR | 3 | 5 | 5 | 10 | 5 | 14 | 6 | 10 | 12 | 12 | 12 | 12 | 15 |  |  |
| BMC0_SMB9_DAT | I2C35-DIFF1 | PAIR | 4 | 5 | 5 | 10 | 5 | 14 | 6 | 10 | 12 | 12 | 12 | 12 | 15 |  |  |
| BMC0_SMB9_DAT | I2C35-DIFF1 | PAIR | 5 | 5 | 5 | 10 | 5 | 14 | 6 | 10 | 12 | 12 | 12 | 12 | 15 |  |  |
| BMC0_SMB9_DAT | I2C35-DIFF1 | PAIR | 6 | 5 | 5 | 10 | 5 | 14 | 6 | 10 | 12 | 12 | 12 | 12 | 15 |  |  |
| BMC0_SMB9_DAT | I2C35-DIFF1 | PAIR | 7 | 5 | 5 | 10 | 5 | 14 | 6 | 10 | 12 | 12 | 12 | 12 | 15 |  |  |
| BMC0_SMB9_DAT | I2C35-DIFF1 | PAIR | 8 | 4.75 | 5 | 10 | 5 | 14 | 6 | 9.5 | 12 | 12 | 12 | 12 | 15 |  |  |
| BMC_I2C11_MINI5_SCL | I2C36-DIFF1 | PAIR | 1 | 4.75 | 5 | 10 | 5 | 14 | 6 | 9.5 | 12 | 12 | 12 | 12 | 15 |  |  |
| BMC_I2C11_MINI5_SCL | I2C36-DIFF1 | PAIR | 2 | 5 | 5 | 10 | 5 | 14 | 6 | 10 | 12 | 12 | 12 | 12 | 15 |  |  |
| BMC_I2C11_MINI5_SCL | I2C36-DIFF1 | PAIR | 3 | 5 | 5 | 10 | 5 | 14 | 6 | 10 | 12 | 12 | 12 | 12 | 15 |  |  |
| BMC_I2C11_MINI5_SCL | I2C36-DIFF1 | PAIR | 4 | 5 | 5 | 10 | 5 | 14 | 6 | 10 | 12 | 12 | 12 | 12 | 15 |  |  |
| BMC_I2C11_MINI5_SCL | I2C36-DIFF1 | PAIR | 5 | 5 | 5 | 10 | 5 | 14 | 6 | 10 | 12 | 12 | 12 | 12 | 15 |  |  |
| BMC_I2C11_MINI5_SCL | I2C36-DIFF1 | PAIR | 6 | 5 | 5 | 10 | 5 | 14 | 6 | 10 | 12 | 12 | 12 | 12 | 15 |  |  |
| BMC_I2C11_MINI5_SCL | I2C36-DIFF1 | PAIR | 7 | 5 | 5 | 10 | 5 | 14 | 6 | 10 | 12 | 12 | 12 | 12 | 15 |  |  |
| BMC_I2C11_MINI5_SCL | I2C36-DIFF1 | PAIR | 8 | 4.75 | 5 | 10 | 5 | 14 | 6 | 9.5 | 12 | 12 | 12 | 12 | 15 |  |  |
| BMC_I2C11_MINI5_SDA | I2C36-DIFF1 | PAIR | 1 | 4.75 | 5 | 10 | 5 | 14 | 6 | 9.5 | 12 | 12 | 12 | 12 | 15 |  |  |
| BMC_I2C11_MINI5_SDA | I2C36-DIFF1 | PAIR | 2 | 5 | 5 | 10 | 5 | 14 | 6 | 10 | 12 | 12 | 12 | 12 | 15 |  |  |
| BMC_I2C11_MINI5_SDA | I2C36-DIFF1 | PAIR | 3 | 5 | 5 | 10 | 5 | 14 | 6 | 10 | 12 | 12 | 12 | 12 | 15 |  |  |
| BMC_I2C11_MINI5_SDA | I2C36-DIFF1 | PAIR | 4 | 5 | 5 | 10 | 5 | 14 | 6 | 10 | 12 | 12 | 12 | 12 | 15 |  |  |
| BMC_I2C11_MINI5_SDA | I2C36-DIFF1 | PAIR | 5 | 5 | 5 | 10 | 5 | 14 | 6 | 10 | 12 | 12 | 12 | 12 | 15 |  |  |
| BMC_I2C11_MINI5_SDA | I2C36-DIFF1 | PAIR | 6 | 5 | 5 | 10 | 5 | 14 | 6 | 10 | 12 | 12 | 12 | 12 | 15 |  |  |
| BMC_I2C11_MINI5_SDA | I2C36-DIFF1 | PAIR | 7 | 5 | 5 | 10 | 5 | 14 | 6 | 10 | 12 | 12 | 12 | 12 | 15 |  |  |
| BMC_I2C11_MINI5_SDA | I2C36-DIFF1 | PAIR | 8 | 4.75 | 5 | 10 | 5 | 14 | 6 | 9.5 | 12 | 12 | 12 | 12 | 15 |  |  |
| BMC_I2C1_MINI1_SCL | I2C37-DIFF1 | PAIR | 1 | 4.75 | 5 | 10 | 5 | 14 | 6 | 9.5 | 12 | 12 | 12 | 12 | 15 |  |  |
| BMC_I2C1_MINI1_SCL | I2C37-DIFF1 | PAIR | 2 | 5 | 5 | 10 | 5 | 14 | 6 | 10 | 12 | 12 | 12 | 12 | 15 |  |  |
| BMC_I2C1_MINI1_SCL | I2C37-DIFF1 | PAIR | 3 | 5 | 5 | 10 | 5 | 14 | 6 | 10 | 12 | 12 | 12 | 12 | 15 |  |  |
| BMC_I2C1_MINI1_SCL | I2C37-DIFF1 | PAIR | 4 | 5 | 5 | 10 | 5 | 14 | 6 | 10 | 12 | 12 | 12 | 12 | 15 |  |  |
| BMC_I2C1_MINI1_SCL | I2C37-DIFF1 | PAIR | 5 | 5 | 5 | 10 | 5 | 14 | 6 | 10 | 12 | 12 | 12 | 12 | 15 |  |  |
| BMC_I2C1_MINI1_SCL | I2C37-DIFF1 | PAIR | 6 | 5 | 5 | 10 | 5 | 14 | 6 | 10 | 12 | 12 | 12 | 12 | 15 |  |  |
| BMC_I2C1_MINI1_SCL | I2C37-DIFF1 | PAIR | 7 | 5 | 5 | 10 | 5 | 14 | 6 | 10 | 12 | 12 | 12 | 12 | 15 |  |  |
| BMC_I2C1_MINI1_SCL | I2C37-DIFF1 | PAIR | 8 | 4.75 | 5 | 10 | 5 | 14 | 6 | 9.5 | 12 | 12 | 12 | 12 | 15 |  |  |
| BMC_I2C1_MINI1_SDA | I2C37-DIFF1 | PAIR | 1 | 4.75 | 5 | 10 | 5 | 14 | 6 | 9.5 | 12 | 12 | 12 | 12 | 15 |  |  |
| BMC_I2C1_MINI1_SDA | I2C37-DIFF1 | PAIR | 2 | 5 | 5 | 10 | 5 | 14 | 6 | 10 | 12 | 12 | 12 | 12 | 15 |  |  |
| BMC_I2C1_MINI1_SDA | I2C37-DIFF1 | PAIR | 3 | 5 | 5 | 10 | 5 | 14 | 6 | 10 | 12 | 12 | 12 | 12 | 15 |  |  |
| BMC_I2C1_MINI1_SDA | I2C37-DIFF1 | PAIR | 4 | 5 | 5 | 10 | 5 | 14 | 6 | 10 | 12 | 12 | 12 | 12 | 15 |  |  |
| BMC_I2C1_MINI1_SDA | I2C37-DIFF1 | PAIR | 5 | 5 | 5 | 10 | 5 | 14 | 6 | 10 | 12 | 12 | 12 | 12 | 15 |  |  |
| BMC_I2C1_MINI1_SDA | I2C37-DIFF1 | PAIR | 6 | 5 | 5 | 10 | 5 | 14 | 6 | 10 | 12 | 12 | 12 | 12 | 15 |  |  |
| BMC_I2C1_MINI1_SDA | I2C37-DIFF1 | PAIR | 7 | 5 | 5 | 10 | 5 | 14 | 6 | 10 | 12 | 12 | 12 | 12 | 15 |  |  |
| BMC_I2C1_MINI1_SDA | I2C37-DIFF1 | PAIR | 8 | 4.75 | 5 | 10 | 5 | 14 | 6 | 9.5 | 12 | 12 | 12 | 12 | 15 |  |  |
| BMC_I2C2_MINI2_SCL | I2C38-DIFF1 | PAIR | 1 | 4.75 | 5 | 10 | 5 | 14 | 6 | 9.5 | 12 | 12 | 12 | 12 | 15 |  |  |
| BMC_I2C2_MINI2_SCL | I2C38-DIFF1 | PAIR | 2 | 5 | 5 | 10 | 5 | 14 | 6 | 10 | 12 | 12 | 12 | 12 | 15 |  |  |
| BMC_I2C2_MINI2_SCL | I2C38-DIFF1 | PAIR | 3 | 5 | 5 | 10 | 5 | 14 | 6 | 10 | 12 | 12 | 12 | 12 | 15 |  |  |
| BMC_I2C2_MINI2_SCL | I2C38-DIFF1 | PAIR | 4 | 5 | 5 | 10 | 5 | 14 | 6 | 10 | 12 | 12 | 12 | 12 | 15 |  |  |
| BMC_I2C2_MINI2_SCL | I2C38-DIFF1 | PAIR | 5 | 5 | 5 | 10 | 5 | 14 | 6 | 10 | 12 | 12 | 12 | 12 | 15 |  |  |
| BMC_I2C2_MINI2_SCL | I2C38-DIFF1 | PAIR | 6 | 5 | 5 | 10 | 5 | 14 | 6 | 10 | 12 | 12 | 12 | 12 | 15 |  |  |
| BMC_I2C2_MINI2_SCL | I2C38-DIFF1 | PAIR | 7 | 5 | 5 | 10 | 5 | 14 | 6 | 10 | 12 | 12 | 12 | 12 | 15 |  |  |
| BMC_I2C2_MINI2_SCL | I2C38-DIFF1 | PAIR | 8 | 4.75 | 5 | 10 | 5 | 14 | 6 | 9.5 | 12 | 12 | 12 | 12 | 15 |  |  |
| BMC_I2C2_MINI2_SDA | I2C38-DIFF1 | PAIR | 1 | 4.75 | 5 | 10 | 5 | 14 | 6 | 9.5 | 12 | 12 | 12 | 12 | 15 |  |  |
| BMC_I2C2_MINI2_SDA | I2C38-DIFF1 | PAIR | 2 | 5 | 5 | 10 | 5 | 14 | 6 | 10 | 12 | 12 | 12 | 12 | 15 |  |  |
| BMC_I2C2_MINI2_SDA | I2C38-DIFF1 | PAIR | 3 | 5 | 5 | 10 | 5 | 14 | 6 | 10 | 12 | 12 | 12 | 12 | 15 |  |  |
| BMC_I2C2_MINI2_SDA | I2C38-DIFF1 | PAIR | 4 | 5 | 5 | 10 | 5 | 14 | 6 | 10 | 12 | 12 | 12 | 12 | 15 |  |  |
| BMC_I2C2_MINI2_SDA | I2C38-DIFF1 | PAIR | 5 | 5 | 5 | 10 | 5 | 14 | 6 | 10 | 12 | 12 | 12 | 12 | 15 |  |  |
| BMC_I2C2_MINI2_SDA | I2C38-DIFF1 | PAIR | 6 | 5 | 5 | 10 | 5 | 14 | 6 | 10 | 12 | 12 | 12 | 12 | 15 |  |  |
| BMC_I2C2_MINI2_SDA | I2C38-DIFF1 | PAIR | 7 | 5 | 5 | 10 | 5 | 14 | 6 | 10 | 12 | 12 | 12 | 12 | 15 |  |  |
| BMC_I2C2_MINI2_SDA | I2C38-DIFF1 | PAIR | 8 | 4.75 | 5 | 10 | 5 | 14 | 6 | 9.5 | 12 | 12 | 12 | 12 | 15 |  |  |
| BMC_I2C13_MINI7_SCL | I2C39-DIFF1 | PAIR | 1 | 4.75 | 5 | 10 | 5 | 14 | 6 | 9.5 | 12 | 12 | 12 | 12 | 15 |  |  |
| BMC_I2C13_MINI7_SCL | I2C39-DIFF1 | PAIR | 2 | 5 | 5 | 10 | 5 | 14 | 6 | 10 | 12 | 12 | 12 | 12 | 15 |  |  |
| BMC_I2C13_MINI7_SCL | I2C39-DIFF1 | PAIR | 3 | 5 | 5 | 10 | 5 | 14 | 6 | 10 | 12 | 12 | 12 | 12 | 15 |  |  |
| BMC_I2C13_MINI7_SCL | I2C39-DIFF1 | PAIR | 4 | 5 | 5 | 10 | 5 | 14 | 6 | 10 | 12 | 12 | 12 | 12 | 15 |  |  |
| BMC_I2C13_MINI7_SCL | I2C39-DIFF1 | PAIR | 5 | 5 | 5 | 10 | 5 | 14 | 6 | 10 | 12 | 12 | 12 | 12 | 15 |  |  |
| BMC_I2C13_MINI7_SCL | I2C39-DIFF1 | PAIR | 6 | 5 | 5 | 10 | 5 | 14 | 6 | 10 | 12 | 12 | 12 | 12 | 15 |  |  |
| BMC_I2C13_MINI7_SCL | I2C39-DIFF1 | PAIR | 7 | 5 | 5 | 10 | 5 | 14 | 6 | 10 | 12 | 12 | 12 | 12 | 15 |  |  |
| BMC_I2C13_MINI7_SCL | I2C39-DIFF1 | PAIR | 8 | 4.75 | 5 | 10 | 5 | 14 | 6 | 9.5 | 12 | 12 | 12 | 12 | 15 |  |  |
| BMC_I2C13_MINI7_SDA | I2C39-DIFF1 | PAIR | 1 | 4.75 | 5 | 10 | 5 | 14 | 6 | 9.5 | 12 | 12 | 12 | 12 | 15 |  |  |
| BMC_I2C13_MINI7_SDA | I2C39-DIFF1 | PAIR | 2 | 5 | 5 | 10 | 5 | 14 | 6 | 10 | 12 | 12 | 12 | 12 | 15 |  |  |
| BMC_I2C13_MINI7_SDA | I2C39-DIFF1 | PAIR | 3 | 5 | 5 | 10 | 5 | 14 | 6 | 10 | 12 | 12 | 12 | 12 | 15 |  |  |
| BMC_I2C13_MINI7_SDA | I2C39-DIFF1 | PAIR | 4 | 5 | 5 | 10 | 5 | 14 | 6 | 10 | 12 | 12 | 12 | 12 | 15 |  |  |
| BMC_I2C13_MINI7_SDA | I2C39-DIFF1 | PAIR | 5 | 5 | 5 | 10 | 5 | 14 | 6 | 10 | 12 | 12 | 12 | 12 | 15 |  |  |
| BMC_I2C13_MINI7_SDA | I2C39-DIFF1 | PAIR | 6 | 5 | 5 | 10 | 5 | 14 | 6 | 10 | 12 | 12 | 12 | 12 | 15 |  |  |
| BMC_I2C13_MINI7_SDA | I2C39-DIFF1 | PAIR | 7 | 5 | 5 | 10 | 5 | 14 | 6 | 10 | 12 | 12 | 12 | 12 | 15 |  |  |
| BMC_I2C13_MINI7_SDA | I2C39-DIFF1 | PAIR | 8 | 4.75 | 5 | 10 | 5 | 14 | 6 | 9.5 | 12 | 12 | 12 | 12 | 15 |  |  |
| BMC_I2C3_MINI3_SCL | I2C40-DIFF1 | PAIR | 1 | 4.75 | 5 | 10 | 5 | 14 | 6 | 9.5 | 12 | 12 | 12 | 12 | 15 |  |  |
| BMC_I2C3_MINI3_SCL | I2C40-DIFF1 | PAIR | 2 | 5 | 5 | 10 | 5 | 14 | 6 | 10 | 12 | 12 | 12 | 12 | 15 |  |  |
| BMC_I2C3_MINI3_SCL | I2C40-DIFF1 | PAIR | 3 | 5 | 5 | 10 | 5 | 14 | 6 | 10 | 12 | 12 | 12 | 12 | 15 |  |  |
| BMC_I2C3_MINI3_SCL | I2C40-DIFF1 | PAIR | 4 | 5 | 5 | 10 | 5 | 14 | 6 | 10 | 12 | 12 | 12 | 12 | 15 |  |  |
| BMC_I2C3_MINI3_SCL | I2C40-DIFF1 | PAIR | 5 | 5 | 5 | 10 | 5 | 14 | 6 | 10 | 12 | 12 | 12 | 12 | 15 |  |  |
| BMC_I2C3_MINI3_SCL | I2C40-DIFF1 | PAIR | 6 | 5 | 5 | 10 | 5 | 14 | 6 | 10 | 12 | 12 | 12 | 12 | 15 |  |  |
| BMC_I2C3_MINI3_SCL | I2C40-DIFF1 | PAIR | 7 | 5 | 5 | 10 | 5 | 14 | 6 | 10 | 12 | 12 | 12 | 12 | 15 |  |  |
| BMC_I2C3_MINI3_SCL | I2C40-DIFF1 | PAIR | 8 | 4.75 | 5 | 10 | 5 | 14 | 6 | 9.5 | 12 | 12 | 12 | 12 | 15 |  |  |
| BMC_I2C3_MINI3_SDA | I2C40-DIFF1 | PAIR | 1 | 4.75 | 5 | 10 | 5 | 14 | 6 | 9.5 | 12 | 12 | 12 | 12 | 15 |  |  |
| BMC_I2C3_MINI3_SDA | I2C40-DIFF1 | PAIR | 2 | 5 | 5 | 10 | 5 | 14 | 6 | 10 | 12 | 12 | 12 | 12 | 15 |  |  |
| BMC_I2C3_MINI3_SDA | I2C40-DIFF1 | PAIR | 3 | 5 | 5 | 10 | 5 | 14 | 6 | 10 | 12 | 12 | 12 | 12 | 15 |  |  |
| BMC_I2C3_MINI3_SDA | I2C40-DIFF1 | PAIR | 4 | 5 | 5 | 10 | 5 | 14 | 6 | 10 | 12 | 12 | 12 | 12 | 15 |  |  |
| BMC_I2C3_MINI3_SDA | I2C40-DIFF1 | PAIR | 5 | 5 | 5 | 10 | 5 | 14 | 6 | 10 | 12 | 12 | 12 | 12 | 15 |  |  |
| BMC_I2C3_MINI3_SDA | I2C40-DIFF1 | PAIR | 6 | 5 | 5 | 10 | 5 | 14 | 6 | 10 | 12 | 12 | 12 | 12 | 15 |  |  |
| BMC_I2C3_MINI3_SDA | I2C40-DIFF1 | PAIR | 7 | 5 | 5 | 10 | 5 | 14 | 6 | 10 | 12 | 12 | 12 | 12 | 15 |  |  |
| BMC_I2C3_MINI3_SDA | I2C40-DIFF1 | PAIR | 8 | 4.75 | 5 | 10 | 5 | 14 | 6 | 9.5 | 12 | 12 | 12 | 12 | 15 |  |  |
| BMC_I2C8_CLKBUF1_SCL_R | I2C41-DIFF1 | PAIR | 1 | 4.75 | 5 | 10 | 5 | 14 | 6 | 9.5 | 12 | 12 | 12 | 12 | 15 |  |  |
| BMC_I2C8_CLKBUF1_SCL_R | I2C41-DIFF1 | PAIR | 2 | 5 | 5 | 10 | 5 | 14 | 6 | 10 | 12 | 12 | 12 | 12 | 15 |  |  |
| BMC_I2C8_CLKBUF1_SCL_R | I2C41-DIFF1 | PAIR | 3 | 5 | 5 | 10 | 5 | 14 | 6 | 10 | 12 | 12 | 12 | 12 | 15 |  |  |
| BMC_I2C8_CLKBUF1_SCL_R | I2C41-DIFF1 | PAIR | 4 | 5 | 5 | 10 | 5 | 14 | 6 | 10 | 12 | 12 | 12 | 12 | 15 |  |  |
| BMC_I2C8_CLKBUF1_SCL_R | I2C41-DIFF1 | PAIR | 5 | 5 | 5 | 10 | 5 | 14 | 6 | 10 | 12 | 12 | 12 | 12 | 15 |  |  |
| BMC_I2C8_CLKBUF1_SCL_R | I2C41-DIFF1 | PAIR | 6 | 5 | 5 | 10 | 5 | 14 | 6 | 10 | 12 | 12 | 12 | 12 | 15 |  |  |
| BMC_I2C8_CLKBUF1_SCL_R | I2C41-DIFF1 | PAIR | 7 | 5 | 5 | 10 | 5 | 14 | 6 | 10 | 12 | 12 | 12 | 12 | 15 |  |  |
| BMC_I2C8_CLKBUF1_SCL_R | I2C41-DIFF1 | PAIR | 8 | 4.75 | 5 | 10 | 5 | 14 | 6 | 9.5 | 12 | 12 | 12 | 12 | 15 |  |  |
| BMC_I2C8_CLKBUF1_SDA_R | I2C41-DIFF1 | PAIR | 1 | 4.75 | 5 | 10 | 5 | 14 | 6 | 9.5 | 12 | 12 | 12 | 12 | 15 |  |  |
| BMC_I2C8_CLKBUF1_SDA_R | I2C41-DIFF1 | PAIR | 2 | 5 | 5 | 10 | 5 | 14 | 6 | 10 | 12 | 12 | 12 | 12 | 15 |  |  |
| BMC_I2C8_CLKBUF1_SDA_R | I2C41-DIFF1 | PAIR | 3 | 5 | 5 | 10 | 5 | 14 | 6 | 10 | 12 | 12 | 12 | 12 | 15 |  |  |
| BMC_I2C8_CLKBUF1_SDA_R | I2C41-DIFF1 | PAIR | 4 | 5 | 5 | 10 | 5 | 14 | 6 | 10 | 12 | 12 | 12 | 12 | 15 |  |  |
| BMC_I2C8_CLKBUF1_SDA_R | I2C41-DIFF1 | PAIR | 5 | 5 | 5 | 10 | 5 | 14 | 6 | 10 | 12 | 12 | 12 | 12 | 15 |  |  |
| BMC_I2C8_CLKBUF1_SDA_R | I2C41-DIFF1 | PAIR | 6 | 5 | 5 | 10 | 5 | 14 | 6 | 10 | 12 | 12 | 12 | 12 | 15 |  |  |
| BMC_I2C8_CLKBUF1_SDA_R | I2C41-DIFF1 | PAIR | 7 | 5 | 5 | 10 | 5 | 14 | 6 | 10 | 12 | 12 | 12 | 12 | 15 |  |  |
| BMC_I2C8_CLKBUF1_SDA_R | I2C41-DIFF1 | PAIR | 8 | 4.75 | 5 | 10 | 5 | 14 | 6 | 9.5 | 12 | 12 | 12 | 12 | 15 |  |  |
| BUF_I2C8_CLKBUF1_SCL_R | I2C42-DIFF1 | PAIR | 1 | 4.75 | 5 | 10 | 5 | 14 | 6 | 9.5 | 12 | 12 | 12 | 12 | 15 |  |  |
| BUF_I2C8_CLKBUF1_SCL_R | I2C42-DIFF1 | PAIR | 2 | 5 | 5 | 10 | 5 | 14 | 6 | 10 | 12 | 12 | 12 | 12 | 15 |  |  |
| BUF_I2C8_CLKBUF1_SCL_R | I2C42-DIFF1 | PAIR | 3 | 5 | 5 | 10 | 5 | 14 | 6 | 10 | 12 | 12 | 12 | 12 | 15 |  |  |
| BUF_I2C8_CLKBUF1_SCL_R | I2C42-DIFF1 | PAIR | 4 | 5 | 5 | 10 | 5 | 14 | 6 | 10 | 12 | 12 | 12 | 12 | 15 |  |  |
| BUF_I2C8_CLKBUF1_SCL_R | I2C42-DIFF1 | PAIR | 5 | 5 | 5 | 10 | 5 | 14 | 6 | 10 | 12 | 12 | 12 | 12 | 15 |  |  |
| BUF_I2C8_CLKBUF1_SCL_R | I2C42-DIFF1 | PAIR | 6 | 5 | 5 | 10 | 5 | 14 | 6 | 10 | 12 | 12 | 12 | 12 | 15 |  |  |
| BUF_I2C8_CLKBUF1_SCL_R | I2C42-DIFF1 | PAIR | 7 | 5 | 5 | 10 | 5 | 14 | 6 | 10 | 12 | 12 | 12 | 12 | 15 |  |  |
| BUF_I2C8_CLKBUF1_SCL_R | I2C42-DIFF1 | PAIR | 8 | 4.75 | 5 | 10 | 5 | 14 | 6 | 9.5 | 12 | 12 | 12 | 12 | 15 |  |  |
| BUF_I2C8_CLKBUF1_SDA_R | I2C42-DIFF1 | PAIR | 1 | 4.75 | 5 | 10 | 5 | 14 | 6 | 9.5 | 12 | 12 | 12 | 12 | 15 |  |  |
| BUF_I2C8_CLKBUF1_SDA_R | I2C42-DIFF1 | PAIR | 2 | 5 | 5 | 10 | 5 | 14 | 6 | 10 | 12 | 12 | 12 | 12 | 15 |  |  |
| BUF_I2C8_CLKBUF1_SDA_R | I2C42-DIFF1 | PAIR | 3 | 5 | 5 | 10 | 5 | 14 | 6 | 10 | 12 | 12 | 12 | 12 | 15 |  |  |
| BUF_I2C8_CLKBUF1_SDA_R | I2C42-DIFF1 | PAIR | 4 | 5 | 5 | 10 | 5 | 14 | 6 | 10 | 12 | 12 | 12 | 12 | 15 |  |  |
| BUF_I2C8_CLKBUF1_SDA_R | I2C42-DIFF1 | PAIR | 5 | 5 | 5 | 10 | 5 | 14 | 6 | 10 | 12 | 12 | 12 | 12 | 15 |  |  |
| BUF_I2C8_CLKBUF1_SDA_R | I2C42-DIFF1 | PAIR | 6 | 5 | 5 | 10 | 5 | 14 | 6 | 10 | 12 | 12 | 12 | 12 | 15 |  |  |
| BUF_I2C8_CLKBUF1_SDA_R | I2C42-DIFF1 | PAIR | 7 | 5 | 5 | 10 | 5 | 14 | 6 | 10 | 12 | 12 | 12 | 12 | 15 |  |  |
| BUF_I2C8_CLKBUF1_SDA_R | I2C42-DIFF1 | PAIR | 8 | 4.75 | 5 | 10 | 5 | 14 | 6 | 9.5 | 12 | 12 | 12 | 12 | 15 |  |  |
| BMC_I2C14_MINI8_SCL | I2C43-DIFF1 | PAIR | 1 | 4.75 | 5 | 10 | 5 | 14 | 6 | 9.5 | 12 | 12 | 12 | 12 | 15 |  |  |
| BMC_I2C14_MINI8_SCL | I2C43-DIFF1 | PAIR | 2 | 5 | 5 | 10 | 5 | 14 | 6 | 10 | 12 | 12 | 12 | 12 | 15 |  |  |
| BMC_I2C14_MINI8_SCL | I2C43-DIFF1 | PAIR | 3 | 5 | 5 | 10 | 5 | 14 | 6 | 10 | 12 | 12 | 12 | 12 | 15 |  |  |
| BMC_I2C14_MINI8_SCL | I2C43-DIFF1 | PAIR | 4 | 5 | 5 | 10 | 5 | 14 | 6 | 10 | 12 | 12 | 12 | 12 | 15 |  |  |
| BMC_I2C14_MINI8_SCL | I2C43-DIFF1 | PAIR | 5 | 5 | 5 | 10 | 5 | 14 | 6 | 10 | 12 | 12 | 12 | 12 | 15 |  |  |
| BMC_I2C14_MINI8_SCL | I2C43-DIFF1 | PAIR | 6 | 5 | 5 | 10 | 5 | 14 | 6 | 10 | 12 | 12 | 12 | 12 | 15 |  |  |
| BMC_I2C14_MINI8_SCL | I2C43-DIFF1 | PAIR | 7 | 5 | 5 | 10 | 5 | 14 | 6 | 10 | 12 | 12 | 12 | 12 | 15 |  |  |
| BMC_I2C14_MINI8_SCL | I2C43-DIFF1 | PAIR | 8 | 4.75 | 5 | 10 | 5 | 14 | 6 | 9.5 | 12 | 12 | 12 | 12 | 15 |  |  |
| BMC_I2C14_MINI8_SDA | I2C43-DIFF1 | PAIR | 1 | 4.75 | 5 | 10 | 5 | 14 | 6 | 9.5 | 12 | 12 | 12 | 12 | 15 |  |  |
| BMC_I2C14_MINI8_SDA | I2C43-DIFF1 | PAIR | 2 | 5 | 5 | 10 | 5 | 14 | 6 | 10 | 12 | 12 | 12 | 12 | 15 |  |  |
| BMC_I2C14_MINI8_SDA | I2C43-DIFF1 | PAIR | 3 | 5 | 5 | 10 | 5 | 14 | 6 | 10 | 12 | 12 | 12 | 12 | 15 |  |  |
| BMC_I2C14_MINI8_SDA | I2C43-DIFF1 | PAIR | 4 | 5 | 5 | 10 | 5 | 14 | 6 | 10 | 12 | 12 | 12 | 12 | 15 |  |  |
| BMC_I2C14_MINI8_SDA | I2C43-DIFF1 | PAIR | 5 | 5 | 5 | 10 | 5 | 14 | 6 | 10 | 12 | 12 | 12 | 12 | 15 |  |  |
| BMC_I2C14_MINI8_SDA | I2C43-DIFF1 | PAIR | 6 | 5 | 5 | 10 | 5 | 14 | 6 | 10 | 12 | 12 | 12 | 12 | 15 |  |  |
| BMC_I2C14_MINI8_SDA | I2C43-DIFF1 | PAIR | 7 | 5 | 5 | 10 | 5 | 14 | 6 | 10 | 12 | 12 | 12 | 12 | 15 |  |  |
| BMC_I2C14_MINI8_SDA | I2C43-DIFF1 | PAIR | 8 | 4.75 | 5 | 10 | 5 | 14 | 6 | 9.5 | 12 | 12 | 12 | 12 | 15 |  |  |
| I2C_MUX_1A | I2C44-DIFF1 | PAIR | 1 | 4.75 | 5 | 10 | 5 | 14 | 6 | 9.5 | 12 | 12 | 12 | 12 | 15 |  |  |
| I2C_MUX_1A | I2C44-DIFF1 | PAIR | 2 | 5 | 5 | 10 | 5 | 14 | 6 | 10 | 12 | 12 | 12 | 12 | 15 |  |  |
| I2C_MUX_1A | I2C44-DIFF1 | PAIR | 3 | 5 | 5 | 10 | 5 | 14 | 6 | 10 | 12 | 12 | 12 | 12 | 15 |  |  |
| I2C_MUX_1A | I2C44-DIFF1 | PAIR | 4 | 5 | 5 | 10 | 5 | 14 | 6 | 10 | 12 | 12 | 12 | 12 | 15 |  |  |
| I2C_MUX_1A | I2C44-DIFF1 | PAIR | 5 | 5 | 5 | 10 | 5 | 14 | 6 | 10 | 12 | 12 | 12 | 12 | 15 |  |  |
| I2C_MUX_1A | I2C44-DIFF1 | PAIR | 6 | 5 | 5 | 10 | 5 | 14 | 6 | 10 | 12 | 12 | 12 | 12 | 15 |  |  |
| I2C_MUX_1A | I2C44-DIFF1 | PAIR | 7 | 5 | 5 | 10 | 5 | 14 | 6 | 10 | 12 | 12 | 12 | 12 | 15 |  |  |
| I2C_MUX_1A | I2C44-DIFF1 | PAIR | 8 | 4.75 | 5 | 10 | 5 | 14 | 6 | 9.5 | 12 | 12 | 12 | 12 | 15 |  |  |
| I2C_MUX_2A | I2C44-DIFF1 | PAIR | 1 | 4.75 | 5 | 10 | 5 | 14 | 6 | 9.5 | 12 | 12 | 12 | 12 | 15 |  |  |
| I2C_MUX_2A | I2C44-DIFF1 | PAIR | 2 | 5 | 5 | 10 | 5 | 14 | 6 | 10 | 12 | 12 | 12 | 12 | 15 |  |  |
| I2C_MUX_2A | I2C44-DIFF1 | PAIR | 3 | 5 | 5 | 10 | 5 | 14 | 6 | 10 | 12 | 12 | 12 | 12 | 15 |  |  |
| I2C_MUX_2A | I2C44-DIFF1 | PAIR | 4 | 5 | 5 | 10 | 5 | 14 | 6 | 10 | 12 | 12 | 12 | 12 | 15 |  |  |
| I2C_MUX_2A | I2C44-DIFF1 | PAIR | 5 | 5 | 5 | 10 | 5 | 14 | 6 | 10 | 12 | 12 | 12 | 12 | 15 |  |  |
| I2C_MUX_2A | I2C44-DIFF1 | PAIR | 6 | 5 | 5 | 10 | 5 | 14 | 6 | 10 | 12 | 12 | 12 | 12 | 15 |  |  |
| I2C_MUX_2A | I2C44-DIFF1 | PAIR | 7 | 5 | 5 | 10 | 5 | 14 | 6 | 10 | 12 | 12 | 12 | 12 | 15 |  |  |
| I2C_MUX_2A | I2C44-DIFF1 | PAIR | 8 | 4.75 | 5 | 10 | 5 | 14 | 6 | 9.5 | 12 | 12 | 12 | 12 | 15 |  |  |
| BMC_I2C7_B_DBP_SCL | I2C45-DIFF1 | PAIR | 1 | 4.75 | 5 | 10 | 5 | 14 | 6 | 9.5 | 12 | 12 | 12 | 12 | 15 |  |  |
| BMC_I2C7_B_DBP_SCL | I2C45-DIFF1 | PAIR | 2 | 5 | 5 | 10 | 5 | 14 | 6 | 10 | 12 | 12 | 12 | 12 | 15 |  |  |
| BMC_I2C7_B_DBP_SCL | I2C45-DIFF1 | PAIR | 3 | 5 | 5 | 10 | 5 | 14 | 6 | 10 | 12 | 12 | 12 | 12 | 15 |  |  |
| BMC_I2C7_B_DBP_SCL | I2C45-DIFF1 | PAIR | 4 | 5 | 5 | 10 | 5 | 14 | 6 | 10 | 12 | 12 | 12 | 12 | 15 |  |  |
| BMC_I2C7_B_DBP_SCL | I2C45-DIFF1 | PAIR | 5 | 5 | 5 | 10 | 5 | 14 | 6 | 10 | 12 | 12 | 12 | 12 | 15 |  |  |
| BMC_I2C7_B_DBP_SCL | I2C45-DIFF1 | PAIR | 6 | 5 | 5 | 10 | 5 | 14 | 6 | 10 | 12 | 12 | 12 | 12 | 15 |  |  |
| BMC_I2C7_B_DBP_SCL | I2C45-DIFF1 | PAIR | 7 | 5 | 5 | 10 | 5 | 14 | 6 | 10 | 12 | 12 | 12 | 12 | 15 |  |  |
| BMC_I2C7_B_DBP_SCL | I2C45-DIFF1 | PAIR | 8 | 4.75 | 5 | 10 | 5 | 14 | 6 | 9.5 | 12 | 12 | 12 | 12 | 15 |  |  |
| BMC_I2C7_B_DPB_SDA | I2C45-DIFF1 | PAIR | 1 | 4.75 | 5 | 10 | 5 | 14 | 6 | 9.5 | 12 | 12 | 12 | 12 | 15 |  |  |
| BMC_I2C7_B_DPB_SDA | I2C45-DIFF1 | PAIR | 2 | 5 | 5 | 10 | 5 | 14 | 6 | 10 | 12 | 12 | 12 | 12 | 15 |  |  |
| BMC_I2C7_B_DPB_SDA | I2C45-DIFF1 | PAIR | 3 | 5 | 5 | 10 | 5 | 14 | 6 | 10 | 12 | 12 | 12 | 12 | 15 |  |  |
| BMC_I2C7_B_DPB_SDA | I2C45-DIFF1 | PAIR | 4 | 5 | 5 | 10 | 5 | 14 | 6 | 10 | 12 | 12 | 12 | 12 | 15 |  |  |
| BMC_I2C7_B_DPB_SDA | I2C45-DIFF1 | PAIR | 5 | 5 | 5 | 10 | 5 | 14 | 6 | 10 | 12 | 12 | 12 | 12 | 15 |  |  |
| BMC_I2C7_B_DPB_SDA | I2C45-DIFF1 | PAIR | 6 | 5 | 5 | 10 | 5 | 14 | 6 | 10 | 12 | 12 | 12 | 12 | 15 |  |  |
| BMC_I2C7_B_DPB_SDA | I2C45-DIFF1 | PAIR | 7 | 5 | 5 | 10 | 5 | 14 | 6 | 10 | 12 | 12 | 12 | 12 | 15 |  |  |
| BMC_I2C7_B_DPB_SDA | I2C45-DIFF1 | PAIR | 8 | 4.75 | 5 | 10 | 5 | 14 | 6 | 9.5 | 12 | 12 | 12 | 12 | 15 |  |  |
| BUF_I2C9_CLKBUF2_SCL_R | I2C46-DIFF1 | PAIR | 1 | 4.75 | 5 | 10 | 5 | 14 | 6 | 9.5 | 12 | 12 | 12 | 12 | 15 |  |  |
| BUF_I2C9_CLKBUF2_SCL_R | I2C46-DIFF1 | PAIR | 2 | 5 | 5 | 10 | 5 | 14 | 6 | 10 | 12 | 12 | 12 | 12 | 15 |  |  |
| BUF_I2C9_CLKBUF2_SCL_R | I2C46-DIFF1 | PAIR | 3 | 5 | 5 | 10 | 5 | 14 | 6 | 10 | 12 | 12 | 12 | 12 | 15 |  |  |
| BUF_I2C9_CLKBUF2_SCL_R | I2C46-DIFF1 | PAIR | 4 | 5 | 5 | 10 | 5 | 14 | 6 | 10 | 12 | 12 | 12 | 12 | 15 |  |  |
| BUF_I2C9_CLKBUF2_SCL_R | I2C46-DIFF1 | PAIR | 5 | 5 | 5 | 10 | 5 | 14 | 6 | 10 | 12 | 12 | 12 | 12 | 15 |  |  |
| BUF_I2C9_CLKBUF2_SCL_R | I2C46-DIFF1 | PAIR | 6 | 5 | 5 | 10 | 5 | 14 | 6 | 10 | 12 | 12 | 12 | 12 | 15 |  |  |
| BUF_I2C9_CLKBUF2_SCL_R | I2C46-DIFF1 | PAIR | 7 | 5 | 5 | 10 | 5 | 14 | 6 | 10 | 12 | 12 | 12 | 12 | 15 |  |  |
| BUF_I2C9_CLKBUF2_SCL_R | I2C46-DIFF1 | PAIR | 8 | 4.75 | 5 | 10 | 5 | 14 | 6 | 9.5 | 12 | 12 | 12 | 12 | 15 |  |  |
| BUF_I2C9_CLKBUF2_SDA_R | I2C46-DIFF1 | PAIR | 1 | 4.75 | 5 | 10 | 5 | 14 | 6 | 9.5 | 12 | 12 | 12 | 12 | 15 |  |  |
| BUF_I2C9_CLKBUF2_SDA_R | I2C46-DIFF1 | PAIR | 2 | 5 | 5 | 10 | 5 | 14 | 6 | 10 | 12 | 12 | 12 | 12 | 15 |  |  |
| BUF_I2C9_CLKBUF2_SDA_R | I2C46-DIFF1 | PAIR | 3 | 5 | 5 | 10 | 5 | 14 | 6 | 10 | 12 | 12 | 12 | 12 | 15 |  |  |
| BUF_I2C9_CLKBUF2_SDA_R | I2C46-DIFF1 | PAIR | 4 | 5 | 5 | 10 | 5 | 14 | 6 | 10 | 12 | 12 | 12 | 12 | 15 |  |  |
| BUF_I2C9_CLKBUF2_SDA_R | I2C46-DIFF1 | PAIR | 5 | 5 | 5 | 10 | 5 | 14 | 6 | 10 | 12 | 12 | 12 | 12 | 15 |  |  |
| BUF_I2C9_CLKBUF2_SDA_R | I2C46-DIFF1 | PAIR | 6 | 5 | 5 | 10 | 5 | 14 | 6 | 10 | 12 | 12 | 12 | 12 | 15 |  |  |
| BUF_I2C9_CLKBUF2_SDA_R | I2C46-DIFF1 | PAIR | 7 | 5 | 5 | 10 | 5 | 14 | 6 | 10 | 12 | 12 | 12 | 12 | 15 |  |  |
| BUF_I2C9_CLKBUF2_SDA_R | I2C46-DIFF1 | PAIR | 8 | 4.75 | 5 | 10 | 5 | 14 | 6 | 9.5 | 12 | 12 | 12 | 12 | 15 |  |  |
| BMC_I2C5_D_PEB_SCL | I2C47-DIFF1 | PAIR | 1 | 4.75 | 5 | 10 | 5 | 14 | 6 | 9.5 | 12 | 12 | 12 | 12 | 15 |  |  |
| BMC_I2C5_D_PEB_SCL | I2C47-DIFF1 | PAIR | 2 | 5 | 5 | 10 | 5 | 14 | 6 | 10 | 12 | 12 | 12 | 12 | 15 |  |  |
| BMC_I2C5_D_PEB_SCL | I2C47-DIFF1 | PAIR | 3 | 5 | 5 | 10 | 5 | 14 | 6 | 10 | 12 | 12 | 12 | 12 | 15 |  |  |
| BMC_I2C5_D_PEB_SCL | I2C47-DIFF1 | PAIR | 4 | 5 | 5 | 10 | 5 | 14 | 6 | 10 | 12 | 12 | 12 | 12 | 15 |  |  |
| BMC_I2C5_D_PEB_SCL | I2C47-DIFF1 | PAIR | 5 | 5 | 5 | 10 | 5 | 14 | 6 | 10 | 12 | 12 | 12 | 12 | 15 |  |  |
| BMC_I2C5_D_PEB_SCL | I2C47-DIFF1 | PAIR | 6 | 5 | 5 | 10 | 5 | 14 | 6 | 10 | 12 | 12 | 12 | 12 | 15 |  |  |
| BMC_I2C5_D_PEB_SCL | I2C47-DIFF1 | PAIR | 7 | 5 | 5 | 10 | 5 | 14 | 6 | 10 | 12 | 12 | 12 | 12 | 15 |  |  |
| BMC_I2C5_D_PEB_SCL | I2C47-DIFF1 | PAIR | 8 | 4.75 | 5 | 10 | 5 | 14 | 6 | 9.5 | 12 | 12 | 12 | 12 | 15 |  |  |
| BMC_I2C5_D_PEB_SDA | I2C47-DIFF1 | PAIR | 1 | 4.75 | 5 | 10 | 5 | 14 | 6 | 9.5 | 12 | 12 | 12 | 12 | 15 |  |  |
| BMC_I2C5_D_PEB_SDA | I2C47-DIFF1 | PAIR | 2 | 5 | 5 | 10 | 5 | 14 | 6 | 10 | 12 | 12 | 12 | 12 | 15 |  |  |
| BMC_I2C5_D_PEB_SDA | I2C47-DIFF1 | PAIR | 3 | 5 | 5 | 10 | 5 | 14 | 6 | 10 | 12 | 12 | 12 | 12 | 15 |  |  |
| BMC_I2C5_D_PEB_SDA | I2C47-DIFF1 | PAIR | 4 | 5 | 5 | 10 | 5 | 14 | 6 | 10 | 12 | 12 | 12 | 12 | 15 |  |  |
| BMC_I2C5_D_PEB_SDA | I2C47-DIFF1 | PAIR | 5 | 5 | 5 | 10 | 5 | 14 | 6 | 10 | 12 | 12 | 12 | 12 | 15 |  |  |
| BMC_I2C5_D_PEB_SDA | I2C47-DIFF1 | PAIR | 6 | 5 | 5 | 10 | 5 | 14 | 6 | 10 | 12 | 12 | 12 | 12 | 15 |  |  |
| BMC_I2C5_D_PEB_SDA | I2C47-DIFF1 | PAIR | 7 | 5 | 5 | 10 | 5 | 14 | 6 | 10 | 12 | 12 | 12 | 12 | 15 |  |  |
| BMC_I2C5_D_PEB_SDA | I2C47-DIFF1 | PAIR | 8 | 4.75 | 5 | 10 | 5 | 14 | 6 | 9.5 | 12 | 12 | 12 | 12 | 15 |  |  |
| BMC_I2C9_CLKBUF2_SCL_R | I2C48-DIFF1 | PAIR | 1 | 4.75 | 5 | 10 | 5 | 14 | 6 | 9.5 | 12 | 12 | 12 | 12 | 15 |  |  |
| BMC_I2C9_CLKBUF2_SCL_R | I2C48-DIFF1 | PAIR | 2 | 5 | 5 | 10 | 5 | 14 | 6 | 10 | 12 | 12 | 12 | 12 | 15 |  |  |
| BMC_I2C9_CLKBUF2_SCL_R | I2C48-DIFF1 | PAIR | 3 | 5 | 5 | 10 | 5 | 14 | 6 | 10 | 12 | 12 | 12 | 12 | 15 |  |  |
| BMC_I2C9_CLKBUF2_SCL_R | I2C48-DIFF1 | PAIR | 4 | 5 | 5 | 10 | 5 | 14 | 6 | 10 | 12 | 12 | 12 | 12 | 15 |  |  |
| BMC_I2C9_CLKBUF2_SCL_R | I2C48-DIFF1 | PAIR | 5 | 5 | 5 | 10 | 5 | 14 | 6 | 10 | 12 | 12 | 12 | 12 | 15 |  |  |
| BMC_I2C9_CLKBUF2_SCL_R | I2C48-DIFF1 | PAIR | 6 | 5 | 5 | 10 | 5 | 14 | 6 | 10 | 12 | 12 | 12 | 12 | 15 |  |  |
| BMC_I2C9_CLKBUF2_SCL_R | I2C48-DIFF1 | PAIR | 7 | 5 | 5 | 10 | 5 | 14 | 6 | 10 | 12 | 12 | 12 | 12 | 15 |  |  |
| BMC_I2C9_CLKBUF2_SCL_R | I2C48-DIFF1 | PAIR | 8 | 4.75 | 5 | 10 | 5 | 14 | 6 | 9.5 | 12 | 12 | 12 | 12 | 15 |  |  |
| BMC_I2C9_CLKBUF2_SDA_R | I2C48-DIFF1 | PAIR | 1 | 4.75 | 5 | 10 | 5 | 14 | 6 | 9.5 | 12 | 12 | 12 | 12 | 15 |  |  |
| BMC_I2C9_CLKBUF2_SDA_R | I2C48-DIFF1 | PAIR | 2 | 5 | 5 | 10 | 5 | 14 | 6 | 10 | 12 | 12 | 12 | 12 | 15 |  |  |
| BMC_I2C9_CLKBUF2_SDA_R | I2C48-DIFF1 | PAIR | 3 | 5 | 5 | 10 | 5 | 14 | 6 | 10 | 12 | 12 | 12 | 12 | 15 |  |  |
| BMC_I2C9_CLKBUF2_SDA_R | I2C48-DIFF1 | PAIR | 4 | 5 | 5 | 10 | 5 | 14 | 6 | 10 | 12 | 12 | 12 | 12 | 15 |  |  |
| BMC_I2C9_CLKBUF2_SDA_R | I2C48-DIFF1 | PAIR | 5 | 5 | 5 | 10 | 5 | 14 | 6 | 10 | 12 | 12 | 12 | 12 | 15 |  |  |
| BMC_I2C9_CLKBUF2_SDA_R | I2C48-DIFF1 | PAIR | 6 | 5 | 5 | 10 | 5 | 14 | 6 | 10 | 12 | 12 | 12 | 12 | 15 |  |  |
| BMC_I2C9_CLKBUF2_SDA_R | I2C48-DIFF1 | PAIR | 7 | 5 | 5 | 10 | 5 | 14 | 6 | 10 | 12 | 12 | 12 | 12 | 15 |  |  |
| BMC_I2C9_CLKBUF2_SDA_R | I2C48-DIFF1 | PAIR | 8 | 4.75 | 5 | 10 | 5 | 14 | 6 | 9.5 | 12 | 12 | 12 | 12 | 15 |  |  |
| BUF_I2C7_B_DBP_SCL_R | I2C49-DIFF1 | PAIR | 1 | 4.75 | 5 | 10 | 5 | 14 | 6 | 9.5 | 12 | 12 | 12 | 12 | 15 |  |  |
| BUF_I2C7_B_DBP_SCL_R | I2C49-DIFF1 | PAIR | 2 | 5 | 5 | 10 | 5 | 14 | 6 | 10 | 12 | 12 | 12 | 12 | 15 |  |  |
| BUF_I2C7_B_DBP_SCL_R | I2C49-DIFF1 | PAIR | 3 | 5 | 5 | 10 | 5 | 14 | 6 | 10 | 12 | 12 | 12 | 12 | 15 |  |  |
| BUF_I2C7_B_DBP_SCL_R | I2C49-DIFF1 | PAIR | 4 | 5 | 5 | 10 | 5 | 14 | 6 | 10 | 12 | 12 | 12 | 12 | 15 |  |  |
| BUF_I2C7_B_DBP_SCL_R | I2C49-DIFF1 | PAIR | 5 | 5 | 5 | 10 | 5 | 14 | 6 | 10 | 12 | 12 | 12 | 12 | 15 |  |  |
| BUF_I2C7_B_DBP_SCL_R | I2C49-DIFF1 | PAIR | 6 | 5 | 5 | 10 | 5 | 14 | 6 | 10 | 12 | 12 | 12 | 12 | 15 |  |  |
| BUF_I2C7_B_DBP_SCL_R | I2C49-DIFF1 | PAIR | 7 | 5 | 5 | 10 | 5 | 14 | 6 | 10 | 12 | 12 | 12 | 12 | 15 |  |  |
| BUF_I2C7_B_DBP_SCL_R | I2C49-DIFF1 | PAIR | 8 | 4.75 | 5 | 10 | 5 | 14 | 6 | 9.5 | 12 | 12 | 12 | 12 | 15 |  |  |
| BUF_I2C7_B_DPB_SDA_R | I2C49-DIFF1 | PAIR | 1 | 4.75 | 5 | 10 | 5 | 14 | 6 | 9.5 | 12 | 12 | 12 | 12 | 15 |  |  |
| BUF_I2C7_B_DPB_SDA_R | I2C49-DIFF1 | PAIR | 2 | 5 | 5 | 10 | 5 | 14 | 6 | 10 | 12 | 12 | 12 | 12 | 15 |  |  |
| BUF_I2C7_B_DPB_SDA_R | I2C49-DIFF1 | PAIR | 3 | 5 | 5 | 10 | 5 | 14 | 6 | 10 | 12 | 12 | 12 | 12 | 15 |  |  |
| BUF_I2C7_B_DPB_SDA_R | I2C49-DIFF1 | PAIR | 4 | 5 | 5 | 10 | 5 | 14 | 6 | 10 | 12 | 12 | 12 | 12 | 15 |  |  |
| BUF_I2C7_B_DPB_SDA_R | I2C49-DIFF1 | PAIR | 5 | 5 | 5 | 10 | 5 | 14 | 6 | 10 | 12 | 12 | 12 | 12 | 15 |  |  |
| BUF_I2C7_B_DPB_SDA_R | I2C49-DIFF1 | PAIR | 6 | 5 | 5 | 10 | 5 | 14 | 6 | 10 | 12 | 12 | 12 | 12 | 15 |  |  |
| BUF_I2C7_B_DPB_SDA_R | I2C49-DIFF1 | PAIR | 7 | 5 | 5 | 10 | 5 | 14 | 6 | 10 | 12 | 12 | 12 | 12 | 15 |  |  |
| BUF_I2C7_B_DPB_SDA_R | I2C49-DIFF1 | PAIR | 8 | 4.75 | 5 | 10 | 5 | 14 | 6 | 9.5 | 12 | 12 | 12 | 12 | 15 |  |  |
| BMC0_SCL13_R | I2C50-DIFF1 | PAIR | 1 | 4.75 | 5 | 10 | 5 | 14 | 6 | 9.5 | 12 | 12 | 12 | 12 | 15 |  |  |
| BMC0_SCL13_R | I2C50-DIFF1 | PAIR | 2 | 5 | 5 | 10 | 5 | 14 | 6 | 10 | 12 | 12 | 12 | 12 | 15 |  |  |
| BMC0_SCL13_R | I2C50-DIFF1 | PAIR | 3 | 5 | 5 | 10 | 5 | 14 | 6 | 10 | 12 | 12 | 12 | 12 | 15 |  |  |
| BMC0_SCL13_R | I2C50-DIFF1 | PAIR | 4 | 5 | 5 | 10 | 5 | 14 | 6 | 10 | 12 | 12 | 12 | 12 | 15 |  |  |
| BMC0_SCL13_R | I2C50-DIFF1 | PAIR | 5 | 5 | 5 | 10 | 5 | 14 | 6 | 10 | 12 | 12 | 12 | 12 | 15 |  |  |
| BMC0_SCL13_R | I2C50-DIFF1 | PAIR | 6 | 5 | 5 | 10 | 5 | 14 | 6 | 10 | 12 | 12 | 12 | 12 | 15 |  |  |
| BMC0_SCL13_R | I2C50-DIFF1 | PAIR | 7 | 5 | 5 | 10 | 5 | 14 | 6 | 10 | 12 | 12 | 12 | 12 | 15 |  |  |
| BMC0_SCL13_R | I2C50-DIFF1 | PAIR | 8 | 4.75 | 5 | 10 | 5 | 14 | 6 | 9.5 | 12 | 12 | 12 | 12 | 15 |  |  |
| BMC0_SDA13_R | I2C50-DIFF1 | PAIR | 1 | 4.75 | 5 | 10 | 5 | 14 | 6 | 9.5 | 12 | 12 | 12 | 12 | 15 |  |  |
| BMC0_SDA13_R | I2C50-DIFF1 | PAIR | 2 | 5 | 5 | 10 | 5 | 14 | 6 | 10 | 12 | 12 | 12 | 12 | 15 |  |  |
| BMC0_SDA13_R | I2C50-DIFF1 | PAIR | 3 | 5 | 5 | 10 | 5 | 14 | 6 | 10 | 12 | 12 | 12 | 12 | 15 |  |  |
| BMC0_SDA13_R | I2C50-DIFF1 | PAIR | 4 | 5 | 5 | 10 | 5 | 14 | 6 | 10 | 12 | 12 | 12 | 12 | 15 |  |  |
| BMC0_SDA13_R | I2C50-DIFF1 | PAIR | 5 | 5 | 5 | 10 | 5 | 14 | 6 | 10 | 12 | 12 | 12 | 12 | 15 |  |  |
| BMC0_SDA13_R | I2C50-DIFF1 | PAIR | 6 | 5 | 5 | 10 | 5 | 14 | 6 | 10 | 12 | 12 | 12 | 12 | 15 |  |  |
| BMC0_SDA13_R | I2C50-DIFF1 | PAIR | 7 | 5 | 5 | 10 | 5 | 14 | 6 | 10 | 12 | 12 | 12 | 12 | 15 |  |  |
| BMC0_SDA13_R | I2C50-DIFF1 | PAIR | 8 | 4.75 | 5 | 10 | 5 | 14 | 6 | 9.5 | 12 | 12 | 12 | 12 | 15 |  |  |
| BUF_I2C7_B_DBP_SCL | I2C51-DIFF1 | PAIR | 1 | 4.75 | 5 | 10 | 5 | 14 | 6 | 9.5 | 12 | 12 | 12 | 12 | 15 |  |  |
| BUF_I2C7_B_DBP_SCL | I2C51-DIFF1 | PAIR | 2 | 5 | 5 | 10 | 5 | 14 | 6 | 10 | 12 | 12 | 12 | 12 | 15 |  |  |
| BUF_I2C7_B_DBP_SCL | I2C51-DIFF1 | PAIR | 3 | 5 | 5 | 10 | 5 | 14 | 6 | 10 | 12 | 12 | 12 | 12 | 15 |  |  |
| BUF_I2C7_B_DBP_SCL | I2C51-DIFF1 | PAIR | 4 | 5 | 5 | 10 | 5 | 14 | 6 | 10 | 12 | 12 | 12 | 12 | 15 |  |  |
| BUF_I2C7_B_DBP_SCL | I2C51-DIFF1 | PAIR | 5 | 5 | 5 | 10 | 5 | 14 | 6 | 10 | 12 | 12 | 12 | 12 | 15 |  |  |
| BUF_I2C7_B_DBP_SCL | I2C51-DIFF1 | PAIR | 6 | 5 | 5 | 10 | 5 | 14 | 6 | 10 | 12 | 12 | 12 | 12 | 15 |  |  |
| BUF_I2C7_B_DBP_SCL | I2C51-DIFF1 | PAIR | 7 | 5 | 5 | 10 | 5 | 14 | 6 | 10 | 12 | 12 | 12 | 12 | 15 |  |  |
| BUF_I2C7_B_DBP_SCL | I2C51-DIFF1 | PAIR | 8 | 4.75 | 5 | 10 | 5 | 14 | 6 | 9.5 | 12 | 12 | 12 | 12 | 15 |  |  |
| BUF_I2C7_B_DPB_SDA | I2C51-DIFF1 | PAIR | 1 | 4.75 | 5 | 10 | 5 | 14 | 6 | 9.5 | 12 | 12 | 12 | 12 | 15 |  |  |
| BUF_I2C7_B_DPB_SDA | I2C51-DIFF1 | PAIR | 2 | 5 | 5 | 10 | 5 | 14 | 6 | 10 | 12 | 12 | 12 | 12 | 15 |  |  |
| BUF_I2C7_B_DPB_SDA | I2C51-DIFF1 | PAIR | 3 | 5 | 5 | 10 | 5 | 14 | 6 | 10 | 12 | 12 | 12 | 12 | 15 |  |  |
| BUF_I2C7_B_DPB_SDA | I2C51-DIFF1 | PAIR | 4 | 5 | 5 | 10 | 5 | 14 | 6 | 10 | 12 | 12 | 12 | 12 | 15 |  |  |
| BUF_I2C7_B_DPB_SDA | I2C51-DIFF1 | PAIR | 5 | 5 | 5 | 10 | 5 | 14 | 6 | 10 | 12 | 12 | 12 | 12 | 15 |  |  |
| BUF_I2C7_B_DPB_SDA | I2C51-DIFF1 | PAIR | 6 | 5 | 5 | 10 | 5 | 14 | 6 | 10 | 12 | 12 | 12 | 12 | 15 |  |  |
| BUF_I2C7_B_DPB_SDA | I2C51-DIFF1 | PAIR | 7 | 5 | 5 | 10 | 5 | 14 | 6 | 10 | 12 | 12 | 12 | 12 | 15 |  |  |
| BUF_I2C7_B_DPB_SDA | I2C51-DIFF1 | PAIR | 8 | 4.75 | 5 | 10 | 5 | 14 | 6 | 9.5 | 12 | 12 | 12 | 12 | 15 |  |  |
| BMC_I2C7_B_DBP_SCL_R | I2C52-DIFF1 | PAIR | 1 | 4.75 | 5 | 10 | 5 | 14 | 6 | 9.5 | 12 | 12 | 12 | 12 | 15 |  |  |
| BMC_I2C7_B_DBP_SCL_R | I2C52-DIFF1 | PAIR | 2 | 5 | 5 | 10 | 5 | 14 | 6 | 10 | 12 | 12 | 12 | 12 | 15 |  |  |
| BMC_I2C7_B_DBP_SCL_R | I2C52-DIFF1 | PAIR | 3 | 5 | 5 | 10 | 5 | 14 | 6 | 10 | 12 | 12 | 12 | 12 | 15 |  |  |
| BMC_I2C7_B_DBP_SCL_R | I2C52-DIFF1 | PAIR | 4 | 5 | 5 | 10 | 5 | 14 | 6 | 10 | 12 | 12 | 12 | 12 | 15 |  |  |
| BMC_I2C7_B_DBP_SCL_R | I2C52-DIFF1 | PAIR | 5 | 5 | 5 | 10 | 5 | 14 | 6 | 10 | 12 | 12 | 12 | 12 | 15 |  |  |
| BMC_I2C7_B_DBP_SCL_R | I2C52-DIFF1 | PAIR | 6 | 5 | 5 | 10 | 5 | 14 | 6 | 10 | 12 | 12 | 12 | 12 | 15 |  |  |
| BMC_I2C7_B_DBP_SCL_R | I2C52-DIFF1 | PAIR | 7 | 5 | 5 | 10 | 5 | 14 | 6 | 10 | 12 | 12 | 12 | 12 | 15 |  |  |
| BMC_I2C7_B_DBP_SCL_R | I2C52-DIFF1 | PAIR | 8 | 4.75 | 5 | 10 | 5 | 14 | 6 | 9.5 | 12 | 12 | 12 | 12 | 15 |  |  |
| BMC_I2C7_B_DPB_SDA_R | I2C52-DIFF1 | PAIR | 1 | 4.75 | 5 | 10 | 5 | 14 | 6 | 9.5 | 12 | 12 | 12 | 12 | 15 |  |  |
| BMC_I2C7_B_DPB_SDA_R | I2C52-DIFF1 | PAIR | 2 | 5 | 5 | 10 | 5 | 14 | 6 | 10 | 12 | 12 | 12 | 12 | 15 |  |  |
| BMC_I2C7_B_DPB_SDA_R | I2C52-DIFF1 | PAIR | 3 | 5 | 5 | 10 | 5 | 14 | 6 | 10 | 12 | 12 | 12 | 12 | 15 |  |  |
| BMC_I2C7_B_DPB_SDA_R | I2C52-DIFF1 | PAIR | 4 | 5 | 5 | 10 | 5 | 14 | 6 | 10 | 12 | 12 | 12 | 12 | 15 |  |  |
| BMC_I2C7_B_DPB_SDA_R | I2C52-DIFF1 | PAIR | 5 | 5 | 5 | 10 | 5 | 14 | 6 | 10 | 12 | 12 | 12 | 12 | 15 |  |  |
| BMC_I2C7_B_DPB_SDA_R | I2C52-DIFF1 | PAIR | 6 | 5 | 5 | 10 | 5 | 14 | 6 | 10 | 12 | 12 | 12 | 12 | 15 |  |  |
| BMC_I2C7_B_DPB_SDA_R | I2C52-DIFF1 | PAIR | 7 | 5 | 5 | 10 | 5 | 14 | 6 | 10 | 12 | 12 | 12 | 12 | 15 |  |  |
| BMC_I2C7_B_DPB_SDA_R | I2C52-DIFF1 | PAIR | 8 | 4.75 | 5 | 10 | 5 | 14 | 6 | 9.5 | 12 | 12 | 12 | 12 | 15 |  |  |
| BMC0_SCL12_R | I2C53-DIFF1 | PAIR | 1 | 4.75 | 5 | 10 | 5 | 14 | 6 | 9.5 | 12 | 12 | 12 | 12 | 15 |  |  |
| BMC0_SCL12_R | I2C53-DIFF1 | PAIR | 2 | 5 | 5 | 10 | 5 | 14 | 6 | 10 | 12 | 12 | 12 | 12 | 15 |  |  |
| BMC0_SCL12_R | I2C53-DIFF1 | PAIR | 3 | 5 | 5 | 10 | 5 | 14 | 6 | 10 | 12 | 12 | 12 | 12 | 15 |  |  |
| BMC0_SCL12_R | I2C53-DIFF1 | PAIR | 4 | 5 | 5 | 10 | 5 | 14 | 6 | 10 | 12 | 12 | 12 | 12 | 15 |  |  |
| BMC0_SCL12_R | I2C53-DIFF1 | PAIR | 5 | 5 | 5 | 10 | 5 | 14 | 6 | 10 | 12 | 12 | 12 | 12 | 15 |  |  |
| BMC0_SCL12_R | I2C53-DIFF1 | PAIR | 6 | 5 | 5 | 10 | 5 | 14 | 6 | 10 | 12 | 12 | 12 | 12 | 15 |  |  |
| BMC0_SCL12_R | I2C53-DIFF1 | PAIR | 7 | 5 | 5 | 10 | 5 | 14 | 6 | 10 | 12 | 12 | 12 | 12 | 15 |  |  |
| BMC0_SCL12_R | I2C53-DIFF1 | PAIR | 8 | 4.75 | 5 | 10 | 5 | 14 | 6 | 9.5 | 12 | 12 | 12 | 12 | 15 |  |  |
| BMC0_SDA12_R | I2C53-DIFF1 | PAIR | 1 | 4.75 | 5 | 10 | 5 | 14 | 6 | 9.5 | 12 | 12 | 12 | 12 | 15 |  |  |
| BMC0_SDA12_R | I2C53-DIFF1 | PAIR | 2 | 5 | 5 | 10 | 5 | 14 | 6 | 10 | 12 | 12 | 12 | 12 | 15 |  |  |
| BMC0_SDA12_R | I2C53-DIFF1 | PAIR | 3 | 5 | 5 | 10 | 5 | 14 | 6 | 10 | 12 | 12 | 12 | 12 | 15 |  |  |
| BMC0_SDA12_R | I2C53-DIFF1 | PAIR | 4 | 5 | 5 | 10 | 5 | 14 | 6 | 10 | 12 | 12 | 12 | 12 | 15 |  |  |
| BMC0_SDA12_R | I2C53-DIFF1 | PAIR | 5 | 5 | 5 | 10 | 5 | 14 | 6 | 10 | 12 | 12 | 12 | 12 | 15 |  |  |
| BMC0_SDA12_R | I2C53-DIFF1 | PAIR | 6 | 5 | 5 | 10 | 5 | 14 | 6 | 10 | 12 | 12 | 12 | 12 | 15 |  |  |
| BMC0_SDA12_R | I2C53-DIFF1 | PAIR | 7 | 5 | 5 | 10 | 5 | 14 | 6 | 10 | 12 | 12 | 12 | 12 | 15 |  |  |
| BMC0_SDA12_R | I2C53-DIFF1 | PAIR | 8 | 4.75 | 5 | 10 | 5 | 14 | 6 | 9.5 | 12 | 12 | 12 | 12 | 15 |  |  |
| BUF_I2C6_C_FCB_SCL_R | I2C54-DIFF1 | PAIR | 1 | 4.75 | 5 | 10 | 5 | 14 | 6 | 9.5 | 12 | 12 | 12 | 12 | 15 |  |  |
| BUF_I2C6_C_FCB_SCL_R | I2C54-DIFF1 | PAIR | 2 | 5 | 5 | 10 | 5 | 14 | 6 | 10 | 12 | 12 | 12 | 12 | 15 |  |  |
| BUF_I2C6_C_FCB_SCL_R | I2C54-DIFF1 | PAIR | 3 | 5 | 5 | 10 | 5 | 14 | 6 | 10 | 12 | 12 | 12 | 12 | 15 |  |  |
| BUF_I2C6_C_FCB_SCL_R | I2C54-DIFF1 | PAIR | 4 | 5 | 5 | 10 | 5 | 14 | 6 | 10 | 12 | 12 | 12 | 12 | 15 |  |  |
| BUF_I2C6_C_FCB_SCL_R | I2C54-DIFF1 | PAIR | 5 | 5 | 5 | 10 | 5 | 14 | 6 | 10 | 12 | 12 | 12 | 12 | 15 |  |  |
| BUF_I2C6_C_FCB_SCL_R | I2C54-DIFF1 | PAIR | 6 | 5 | 5 | 10 | 5 | 14 | 6 | 10 | 12 | 12 | 12 | 12 | 15 |  |  |
| BUF_I2C6_C_FCB_SCL_R | I2C54-DIFF1 | PAIR | 7 | 5 | 5 | 10 | 5 | 14 | 6 | 10 | 12 | 12 | 12 | 12 | 15 |  |  |
| BUF_I2C6_C_FCB_SCL_R | I2C54-DIFF1 | PAIR | 8 | 4.75 | 5 | 10 | 5 | 14 | 6 | 9.5 | 12 | 12 | 12 | 12 | 15 |  |  |
| BUF_I2C6_C_FCB_SDA_R | I2C54-DIFF1 | PAIR | 1 | 4.75 | 5 | 10 | 5 | 14 | 6 | 9.5 | 12 | 12 | 12 | 12 | 15 |  |  |
| BUF_I2C6_C_FCB_SDA_R | I2C54-DIFF1 | PAIR | 2 | 5 | 5 | 10 | 5 | 14 | 6 | 10 | 12 | 12 | 12 | 12 | 15 |  |  |
| BUF_I2C6_C_FCB_SDA_R | I2C54-DIFF1 | PAIR | 3 | 5 | 5 | 10 | 5 | 14 | 6 | 10 | 12 | 12 | 12 | 12 | 15 |  |  |
| BUF_I2C6_C_FCB_SDA_R | I2C54-DIFF1 | PAIR | 4 | 5 | 5 | 10 | 5 | 14 | 6 | 10 | 12 | 12 | 12 | 12 | 15 |  |  |
| BUF_I2C6_C_FCB_SDA_R | I2C54-DIFF1 | PAIR | 5 | 5 | 5 | 10 | 5 | 14 | 6 | 10 | 12 | 12 | 12 | 12 | 15 |  |  |
| BUF_I2C6_C_FCB_SDA_R | I2C54-DIFF1 | PAIR | 6 | 5 | 5 | 10 | 5 | 14 | 6 | 10 | 12 | 12 | 12 | 12 | 15 |  |  |
| BUF_I2C6_C_FCB_SDA_R | I2C54-DIFF1 | PAIR | 7 | 5 | 5 | 10 | 5 | 14 | 6 | 10 | 12 | 12 | 12 | 12 | 15 |  |  |
| BUF_I2C6_C_FCB_SDA_R | I2C54-DIFF1 | PAIR | 8 | 4.75 | 5 | 10 | 5 | 14 | 6 | 9.5 | 12 | 12 | 12 | 12 | 15 |  |  |
| BMC0_SCL11_R | I2C55-DIFF1 | PAIR | 1 | 4.75 | 5 | 10 | 5 | 14 | 6 | 9.5 | 12 | 12 | 12 | 12 | 15 |  |  |
| BMC0_SCL11_R | I2C55-DIFF1 | PAIR | 2 | 5 | 5 | 10 | 5 | 14 | 6 | 10 | 12 | 12 | 12 | 12 | 15 |  |  |
| BMC0_SCL11_R | I2C55-DIFF1 | PAIR | 3 | 5 | 5 | 10 | 5 | 14 | 6 | 10 | 12 | 12 | 12 | 12 | 15 |  |  |
| BMC0_SCL11_R | I2C55-DIFF1 | PAIR | 4 | 5 | 5 | 10 | 5 | 14 | 6 | 10 | 12 | 12 | 12 | 12 | 15 |  |  |
| BMC0_SCL11_R | I2C55-DIFF1 | PAIR | 5 | 5 | 5 | 10 | 5 | 14 | 6 | 10 | 12 | 12 | 12 | 12 | 15 |  |  |
| BMC0_SCL11_R | I2C55-DIFF1 | PAIR | 6 | 5 | 5 | 10 | 5 | 14 | 6 | 10 | 12 | 12 | 12 | 12 | 15 |  |  |
| BMC0_SCL11_R | I2C55-DIFF1 | PAIR | 7 | 5 | 5 | 10 | 5 | 14 | 6 | 10 | 12 | 12 | 12 | 12 | 15 |  |  |
| BMC0_SCL11_R | I2C55-DIFF1 | PAIR | 8 | 4.75 | 5 | 10 | 5 | 14 | 6 | 9.5 | 12 | 12 | 12 | 12 | 15 |  |  |
| BMC0_SDA11_R | I2C55-DIFF1 | PAIR | 1 | 4.75 | 5 | 10 | 5 | 14 | 6 | 9.5 | 12 | 12 | 12 | 12 | 15 |  |  |
| BMC0_SDA11_R | I2C55-DIFF1 | PAIR | 2 | 5 | 5 | 10 | 5 | 14 | 6 | 10 | 12 | 12 | 12 | 12 | 15 |  |  |
| BMC0_SDA11_R | I2C55-DIFF1 | PAIR | 3 | 5 | 5 | 10 | 5 | 14 | 6 | 10 | 12 | 12 | 12 | 12 | 15 |  |  |
| BMC0_SDA11_R | I2C55-DIFF1 | PAIR | 4 | 5 | 5 | 10 | 5 | 14 | 6 | 10 | 12 | 12 | 12 | 12 | 15 |  |  |
| BMC0_SDA11_R | I2C55-DIFF1 | PAIR | 5 | 5 | 5 | 10 | 5 | 14 | 6 | 10 | 12 | 12 | 12 | 12 | 15 |  |  |
| BMC0_SDA11_R | I2C55-DIFF1 | PAIR | 6 | 5 | 5 | 10 | 5 | 14 | 6 | 10 | 12 | 12 | 12 | 12 | 15 |  |  |
| BMC0_SDA11_R | I2C55-DIFF1 | PAIR | 7 | 5 | 5 | 10 | 5 | 14 | 6 | 10 | 12 | 12 | 12 | 12 | 15 |  |  |
| BMC0_SDA11_R | I2C55-DIFF1 | PAIR | 8 | 4.75 | 5 | 10 | 5 | 14 | 6 | 9.5 | 12 | 12 | 12 | 12 | 15 |  |  |
| BUF_I2C6_C_FCB_SCL | I2C56-DIFF1 | PAIR | 1 | 4.75 | 5 | 10 | 5 | 14 | 6 | 9.5 | 12 | 12 | 12 | 12 | 15 |  |  |
| BUF_I2C6_C_FCB_SCL | I2C56-DIFF1 | PAIR | 2 | 5 | 5 | 10 | 5 | 14 | 6 | 10 | 12 | 12 | 12 | 12 | 15 |  |  |
| BUF_I2C6_C_FCB_SCL | I2C56-DIFF1 | PAIR | 3 | 5 | 5 | 10 | 5 | 14 | 6 | 10 | 12 | 12 | 12 | 12 | 15 |  |  |
| BUF_I2C6_C_FCB_SCL | I2C56-DIFF1 | PAIR | 4 | 5 | 5 | 10 | 5 | 14 | 6 | 10 | 12 | 12 | 12 | 12 | 15 |  |  |
| BUF_I2C6_C_FCB_SCL | I2C56-DIFF1 | PAIR | 5 | 5 | 5 | 10 | 5 | 14 | 6 | 10 | 12 | 12 | 12 | 12 | 15 |  |  |
| BUF_I2C6_C_FCB_SCL | I2C56-DIFF1 | PAIR | 6 | 5 | 5 | 10 | 5 | 14 | 6 | 10 | 12 | 12 | 12 | 12 | 15 |  |  |
| BUF_I2C6_C_FCB_SCL | I2C56-DIFF1 | PAIR | 7 | 5 | 5 | 10 | 5 | 14 | 6 | 10 | 12 | 12 | 12 | 12 | 15 |  |  |
| BUF_I2C6_C_FCB_SCL | I2C56-DIFF1 | PAIR | 8 | 4.75 | 5 | 10 | 5 | 14 | 6 | 9.5 | 12 | 12 | 12 | 12 | 15 |  |  |
| BUF_I2C6_C_FCB_SDA | I2C56-DIFF1 | PAIR | 1 | 4.75 | 5 | 10 | 5 | 14 | 6 | 9.5 | 12 | 12 | 12 | 12 | 15 |  |  |
| BUF_I2C6_C_FCB_SDA | I2C56-DIFF1 | PAIR | 2 | 5 | 5 | 10 | 5 | 14 | 6 | 10 | 12 | 12 | 12 | 12 | 15 |  |  |
| BUF_I2C6_C_FCB_SDA | I2C56-DIFF1 | PAIR | 3 | 5 | 5 | 10 | 5 | 14 | 6 | 10 | 12 | 12 | 12 | 12 | 15 |  |  |
| BUF_I2C6_C_FCB_SDA | I2C56-DIFF1 | PAIR | 4 | 5 | 5 | 10 | 5 | 14 | 6 | 10 | 12 | 12 | 12 | 12 | 15 |  |  |
| BUF_I2C6_C_FCB_SDA | I2C56-DIFF1 | PAIR | 5 | 5 | 5 | 10 | 5 | 14 | 6 | 10 | 12 | 12 | 12 | 12 | 15 |  |  |
| BUF_I2C6_C_FCB_SDA | I2C56-DIFF1 | PAIR | 6 | 5 | 5 | 10 | 5 | 14 | 6 | 10 | 12 | 12 | 12 | 12 | 15 |  |  |
| BUF_I2C6_C_FCB_SDA | I2C56-DIFF1 | PAIR | 7 | 5 | 5 | 10 | 5 | 14 | 6 | 10 | 12 | 12 | 12 | 12 | 15 |  |  |
| BUF_I2C6_C_FCB_SDA | I2C56-DIFF1 | PAIR | 8 | 4.75 | 5 | 10 | 5 | 14 | 6 | 9.5 | 12 | 12 | 12 | 12 | 15 |  |  |
| BMC_I2C6_C_FCB_SCL_R | I2C57-DIFF1 | PAIR | 1 | 4.75 | 5 | 10 | 5 | 14 | 6 | 9.5 | 12 | 12 | 12 | 12 | 15 |  |  |
| BMC_I2C6_C_FCB_SCL_R | I2C57-DIFF1 | PAIR | 2 | 5 | 5 | 10 | 5 | 14 | 6 | 10 | 12 | 12 | 12 | 12 | 15 |  |  |
| BMC_I2C6_C_FCB_SCL_R | I2C57-DIFF1 | PAIR | 3 | 5 | 5 | 10 | 5 | 14 | 6 | 10 | 12 | 12 | 12 | 12 | 15 |  |  |
| BMC_I2C6_C_FCB_SCL_R | I2C57-DIFF1 | PAIR | 4 | 5 | 5 | 10 | 5 | 14 | 6 | 10 | 12 | 12 | 12 | 12 | 15 |  |  |
| BMC_I2C6_C_FCB_SCL_R | I2C57-DIFF1 | PAIR | 5 | 5 | 5 | 10 | 5 | 14 | 6 | 10 | 12 | 12 | 12 | 12 | 15 |  |  |
| BMC_I2C6_C_FCB_SCL_R | I2C57-DIFF1 | PAIR | 6 | 5 | 5 | 10 | 5 | 14 | 6 | 10 | 12 | 12 | 12 | 12 | 15 |  |  |
| BMC_I2C6_C_FCB_SCL_R | I2C57-DIFF1 | PAIR | 7 | 5 | 5 | 10 | 5 | 14 | 6 | 10 | 12 | 12 | 12 | 12 | 15 |  |  |
| BMC_I2C6_C_FCB_SCL_R | I2C57-DIFF1 | PAIR | 8 | 4.75 | 5 | 10 | 5 | 14 | 6 | 9.5 | 12 | 12 | 12 | 12 | 15 |  |  |
| BMC_I2C6_C_FCB_SDA_R | I2C57-DIFF1 | PAIR | 1 | 4.75 | 5 | 10 | 5 | 14 | 6 | 9.5 | 12 | 12 | 12 | 12 | 15 |  |  |
| BMC_I2C6_C_FCB_SDA_R | I2C57-DIFF1 | PAIR | 2 | 5 | 5 | 10 | 5 | 14 | 6 | 10 | 12 | 12 | 12 | 12 | 15 |  |  |
| BMC_I2C6_C_FCB_SDA_R | I2C57-DIFF1 | PAIR | 3 | 5 | 5 | 10 | 5 | 14 | 6 | 10 | 12 | 12 | 12 | 12 | 15 |  |  |
| BMC_I2C6_C_FCB_SDA_R | I2C57-DIFF1 | PAIR | 4 | 5 | 5 | 10 | 5 | 14 | 6 | 10 | 12 | 12 | 12 | 12 | 15 |  |  |
| BMC_I2C6_C_FCB_SDA_R | I2C57-DIFF1 | PAIR | 5 | 5 | 5 | 10 | 5 | 14 | 6 | 10 | 12 | 12 | 12 | 12 | 15 |  |  |
| BMC_I2C6_C_FCB_SDA_R | I2C57-DIFF1 | PAIR | 6 | 5 | 5 | 10 | 5 | 14 | 6 | 10 | 12 | 12 | 12 | 12 | 15 |  |  |
| BMC_I2C6_C_FCB_SDA_R | I2C57-DIFF1 | PAIR | 7 | 5 | 5 | 10 | 5 | 14 | 6 | 10 | 12 | 12 | 12 | 12 | 15 |  |  |
| BMC_I2C6_C_FCB_SDA_R | I2C57-DIFF1 | PAIR | 8 | 4.75 | 5 | 10 | 5 | 14 | 6 | 9.5 | 12 | 12 | 12 | 12 | 15 |  |  |
| BUF_I2C_SCL_2_R | I2C58-DIFF1 | PAIR | 1 | 4.75 | 5 | 10 | 5 | 14 | 6 | 9.5 | 12 | 12 | 12 | 12 | 15 |  |  |
| BUF_I2C_SCL_2_R | I2C58-DIFF1 | PAIR | 2 | 5 | 5 | 10 | 5 | 14 | 6 | 10 | 12 | 12 | 12 | 12 | 15 |  |  |
| BUF_I2C_SCL_2_R | I2C58-DIFF1 | PAIR | 3 | 5 | 5 | 10 | 5 | 14 | 6 | 10 | 12 | 12 | 12 | 12 | 15 |  |  |
| BUF_I2C_SCL_2_R | I2C58-DIFF1 | PAIR | 4 | 5 | 5 | 10 | 5 | 14 | 6 | 10 | 12 | 12 | 12 | 12 | 15 |  |  |
| BUF_I2C_SCL_2_R | I2C58-DIFF1 | PAIR | 5 | 5 | 5 | 10 | 5 | 14 | 6 | 10 | 12 | 12 | 12 | 12 | 15 |  |  |
| BUF_I2C_SCL_2_R | I2C58-DIFF1 | PAIR | 6 | 5 | 5 | 10 | 5 | 14 | 6 | 10 | 12 | 12 | 12 | 12 | 15 |  |  |
| BUF_I2C_SCL_2_R | I2C58-DIFF1 | PAIR | 7 | 5 | 5 | 10 | 5 | 14 | 6 | 10 | 12 | 12 | 12 | 12 | 15 |  |  |
| BUF_I2C_SCL_2_R | I2C58-DIFF1 | PAIR | 8 | 4.75 | 5 | 10 | 5 | 14 | 6 | 9.5 | 12 | 12 | 12 | 12 | 15 |  |  |
| BUF_I2C_SDA_2_R | I2C58-DIFF1 | PAIR | 1 | 4.75 | 5 | 10 | 5 | 14 | 6 | 9.5 | 12 | 12 | 12 | 12 | 15 |  |  |
| BUF_I2C_SDA_2_R | I2C58-DIFF1 | PAIR | 2 | 5 | 5 | 10 | 5 | 14 | 6 | 10 | 12 | 12 | 12 | 12 | 15 |  |  |
| BUF_I2C_SDA_2_R | I2C58-DIFF1 | PAIR | 3 | 5 | 5 | 10 | 5 | 14 | 6 | 10 | 12 | 12 | 12 | 12 | 15 |  |  |
| BUF_I2C_SDA_2_R | I2C58-DIFF1 | PAIR | 4 | 5 | 5 | 10 | 5 | 14 | 6 | 10 | 12 | 12 | 12 | 12 | 15 |  |  |
| BUF_I2C_SDA_2_R | I2C58-DIFF1 | PAIR | 5 | 5 | 5 | 10 | 5 | 14 | 6 | 10 | 12 | 12 | 12 | 12 | 15 |  |  |
| BUF_I2C_SDA_2_R | I2C58-DIFF1 | PAIR | 6 | 5 | 5 | 10 | 5 | 14 | 6 | 10 | 12 | 12 | 12 | 12 | 15 |  |  |
| BUF_I2C_SDA_2_R | I2C58-DIFF1 | PAIR | 7 | 5 | 5 | 10 | 5 | 14 | 6 | 10 | 12 | 12 | 12 | 12 | 15 |  |  |
| BUF_I2C_SDA_2_R | I2C58-DIFF1 | PAIR | 8 | 4.75 | 5 | 10 | 5 | 14 | 6 | 9.5 | 12 | 12 | 12 | 12 | 15 |  |  |
| BMC_I2C10_8536_SCL_R | I2C59-DIFF1 | PAIR | 1 | 4.75 | 5 | 10 | 5 | 14 | 6 | 9.5 | 12 | 12 | 12 | 12 | 15 |  |  |
| BMC_I2C10_8536_SCL_R | I2C59-DIFF1 | PAIR | 2 | 5 | 5 | 10 | 5 | 14 | 6 | 10 | 12 | 12 | 12 | 12 | 15 |  |  |
| BMC_I2C10_8536_SCL_R | I2C59-DIFF1 | PAIR | 3 | 5 | 5 | 10 | 5 | 14 | 6 | 10 | 12 | 12 | 12 | 12 | 15 |  |  |
| BMC_I2C10_8536_SCL_R | I2C59-DIFF1 | PAIR | 4 | 5 | 5 | 10 | 5 | 14 | 6 | 10 | 12 | 12 | 12 | 12 | 15 |  |  |
| BMC_I2C10_8536_SCL_R | I2C59-DIFF1 | PAIR | 5 | 5 | 5 | 10 | 5 | 14 | 6 | 10 | 12 | 12 | 12 | 12 | 15 |  |  |
| BMC_I2C10_8536_SCL_R | I2C59-DIFF1 | PAIR | 6 | 5 | 5 | 10 | 5 | 14 | 6 | 10 | 12 | 12 | 12 | 12 | 15 |  |  |
| BMC_I2C10_8536_SCL_R | I2C59-DIFF1 | PAIR | 7 | 5 | 5 | 10 | 5 | 14 | 6 | 10 | 12 | 12 | 12 | 12 | 15 |  |  |
| BMC_I2C10_8536_SCL_R | I2C59-DIFF1 | PAIR | 8 | 4.75 | 5 | 10 | 5 | 14 | 6 | 9.5 | 12 | 12 | 12 | 12 | 15 |  |  |
| BMC_I2C10_8536_SDA_R | I2C59-DIFF1 | PAIR | 1 | 4.75 | 5 | 10 | 5 | 14 | 6 | 9.5 | 12 | 12 | 12 | 12 | 15 |  |  |
| BMC_I2C10_8536_SDA_R | I2C59-DIFF1 | PAIR | 2 | 5 | 5 | 10 | 5 | 14 | 6 | 10 | 12 | 12 | 12 | 12 | 15 |  |  |
| BMC_I2C10_8536_SDA_R | I2C59-DIFF1 | PAIR | 3 | 5 | 5 | 10 | 5 | 14 | 6 | 10 | 12 | 12 | 12 | 12 | 15 |  |  |
| BMC_I2C10_8536_SDA_R | I2C59-DIFF1 | PAIR | 4 | 5 | 5 | 10 | 5 | 14 | 6 | 10 | 12 | 12 | 12 | 12 | 15 |  |  |
| BMC_I2C10_8536_SDA_R | I2C59-DIFF1 | PAIR | 5 | 5 | 5 | 10 | 5 | 14 | 6 | 10 | 12 | 12 | 12 | 12 | 15 |  |  |
| BMC_I2C10_8536_SDA_R | I2C59-DIFF1 | PAIR | 6 | 5 | 5 | 10 | 5 | 14 | 6 | 10 | 12 | 12 | 12 | 12 | 15 |  |  |
| BMC_I2C10_8536_SDA_R | I2C59-DIFF1 | PAIR | 7 | 5 | 5 | 10 | 5 | 14 | 6 | 10 | 12 | 12 | 12 | 12 | 15 |  |  |
| BMC_I2C10_8536_SDA_R | I2C59-DIFF1 | PAIR | 8 | 4.75 | 5 | 10 | 5 | 14 | 6 | 9.5 | 12 | 12 | 12 | 12 | 15 |  |  |
| I2C_GPIO_SCL_4 | I2C60-DIFF1 | PAIR | 1 | 4.75 | 5 | 10 | 5 | 14 | 6 | 9.5 | 12 | 12 | 12 | 12 | 15 |  |  |
| I2C_GPIO_SCL_4 | I2C60-DIFF1 | PAIR | 2 | 5 | 5 | 10 | 5 | 14 | 6 | 10 | 12 | 12 | 12 | 12 | 15 |  |  |
| I2C_GPIO_SCL_4 | I2C60-DIFF1 | PAIR | 3 | 5 | 5 | 10 | 5 | 14 | 6 | 10 | 12 | 12 | 12 | 12 | 15 |  |  |
| I2C_GPIO_SCL_4 | I2C60-DIFF1 | PAIR | 4 | 5 | 5 | 10 | 5 | 14 | 6 | 10 | 12 | 12 | 12 | 12 | 15 |  |  |
| I2C_GPIO_SCL_4 | I2C60-DIFF1 | PAIR | 5 | 5 | 5 | 10 | 5 | 14 | 6 | 10 | 12 | 12 | 12 | 12 | 15 |  |  |
| I2C_GPIO_SCL_4 | I2C60-DIFF1 | PAIR | 6 | 5 | 5 | 10 | 5 | 14 | 6 | 10 | 12 | 12 | 12 | 12 | 15 |  |  |
| I2C_GPIO_SCL_4 | I2C60-DIFF1 | PAIR | 7 | 5 | 5 | 10 | 5 | 14 | 6 | 10 | 12 | 12 | 12 | 12 | 15 |  |  |
| I2C_GPIO_SCL_4 | I2C60-DIFF1 | PAIR | 8 | 4.75 | 5 | 10 | 5 | 14 | 6 | 9.5 | 12 | 12 | 12 | 12 | 15 |  |  |
| I2C_GPIO_SDA_4 | I2C60-DIFF1 | PAIR | 1 | 4.75 | 5 | 10 | 5 | 14 | 6 | 9.5 | 12 | 12 | 12 | 12 | 15 |  |  |
| I2C_GPIO_SDA_4 | I2C60-DIFF1 | PAIR | 2 | 5 | 5 | 10 | 5 | 14 | 6 | 10 | 12 | 12 | 12 | 12 | 15 |  |  |
| I2C_GPIO_SDA_4 | I2C60-DIFF1 | PAIR | 3 | 5 | 5 | 10 | 5 | 14 | 6 | 10 | 12 | 12 | 12 | 12 | 15 |  |  |
| I2C_GPIO_SDA_4 | I2C60-DIFF1 | PAIR | 4 | 5 | 5 | 10 | 5 | 14 | 6 | 10 | 12 | 12 | 12 | 12 | 15 |  |  |
| I2C_GPIO_SDA_4 | I2C60-DIFF1 | PAIR | 5 | 5 | 5 | 10 | 5 | 14 | 6 | 10 | 12 | 12 | 12 | 12 | 15 |  |  |
| I2C_GPIO_SDA_4 | I2C60-DIFF1 | PAIR | 6 | 5 | 5 | 10 | 5 | 14 | 6 | 10 | 12 | 12 | 12 | 12 | 15 |  |  |
| I2C_GPIO_SDA_4 | I2C60-DIFF1 | PAIR | 7 | 5 | 5 | 10 | 5 | 14 | 6 | 10 | 12 | 12 | 12 | 12 | 15 |  |  |
| I2C_GPIO_SDA_4 | I2C60-DIFF1 | PAIR | 8 | 4.75 | 5 | 10 | 5 | 14 | 6 | 9.5 | 12 | 12 | 12 | 12 | 15 |  |  |
| BMC_I2C12_MINI6_SCL | I2C61-DIFF1 | PAIR | 1 | 4.75 | 5 | 10 | 5 | 14 | 6 | 9.5 | 12 | 12 | 12 | 12 | 15 |  |  |
| BMC_I2C12_MINI6_SCL | I2C61-DIFF1 | PAIR | 2 | 5 | 5 | 10 | 5 | 14 | 6 | 10 | 12 | 12 | 12 | 12 | 15 |  |  |
| BMC_I2C12_MINI6_SCL | I2C61-DIFF1 | PAIR | 3 | 5 | 5 | 10 | 5 | 14 | 6 | 10 | 12 | 12 | 12 | 12 | 15 |  |  |
| BMC_I2C12_MINI6_SCL | I2C61-DIFF1 | PAIR | 4 | 5 | 5 | 10 | 5 | 14 | 6 | 10 | 12 | 12 | 12 | 12 | 15 |  |  |
| BMC_I2C12_MINI6_SCL | I2C61-DIFF1 | PAIR | 5 | 5 | 5 | 10 | 5 | 14 | 6 | 10 | 12 | 12 | 12 | 12 | 15 |  |  |
| BMC_I2C12_MINI6_SCL | I2C61-DIFF1 | PAIR | 6 | 5 | 5 | 10 | 5 | 14 | 6 | 10 | 12 | 12 | 12 | 12 | 15 |  |  |
| BMC_I2C12_MINI6_SCL | I2C61-DIFF1 | PAIR | 7 | 5 | 5 | 10 | 5 | 14 | 6 | 10 | 12 | 12 | 12 | 12 | 15 |  |  |
| BMC_I2C12_MINI6_SCL | I2C61-DIFF1 | PAIR | 8 | 4.75 | 5 | 10 | 5 | 14 | 6 | 9.5 | 12 | 12 | 12 | 12 | 15 |  |  |
| BMC_I2C12_MINI6_SDA | I2C61-DIFF1 | PAIR | 1 | 4.75 | 5 | 10 | 5 | 14 | 6 | 9.5 | 12 | 12 | 12 | 12 | 15 |  |  |
| BMC_I2C12_MINI6_SDA | I2C61-DIFF1 | PAIR | 2 | 5 | 5 | 10 | 5 | 14 | 6 | 10 | 12 | 12 | 12 | 12 | 15 |  |  |
| BMC_I2C12_MINI6_SDA | I2C61-DIFF1 | PAIR | 3 | 5 | 5 | 10 | 5 | 14 | 6 | 10 | 12 | 12 | 12 | 12 | 15 |  |  |
| BMC_I2C12_MINI6_SDA | I2C61-DIFF1 | PAIR | 4 | 5 | 5 | 10 | 5 | 14 | 6 | 10 | 12 | 12 | 12 | 12 | 15 |  |  |
| BMC_I2C12_MINI6_SDA | I2C61-DIFF1 | PAIR | 5 | 5 | 5 | 10 | 5 | 14 | 6 | 10 | 12 | 12 | 12 | 12 | 15 |  |  |
| BMC_I2C12_MINI6_SDA | I2C61-DIFF1 | PAIR | 6 | 5 | 5 | 10 | 5 | 14 | 6 | 10 | 12 | 12 | 12 | 12 | 15 |  |  |
| BMC_I2C12_MINI6_SDA | I2C61-DIFF1 | PAIR | 7 | 5 | 5 | 10 | 5 | 14 | 6 | 10 | 12 | 12 | 12 | 12 | 15 |  |  |
| BMC_I2C12_MINI6_SDA | I2C61-DIFF1 | PAIR | 8 | 4.75 | 5 | 10 | 5 | 14 | 6 | 9.5 | 12 | 12 | 12 | 12 | 15 |  |  |
| BMC_I2C4_MINI4_SCL | I2C62-DIFF1 | PAIR | 1 | 4.75 | 5 | 10 | 5 | 14 | 6 | 9.5 | 12 | 12 | 12 | 12 | 15 |  |  |
| BMC_I2C4_MINI4_SCL | I2C62-DIFF1 | PAIR | 2 | 5 | 5 | 10 | 5 | 14 | 6 | 10 | 12 | 12 | 12 | 12 | 15 |  |  |
| BMC_I2C4_MINI4_SCL | I2C62-DIFF1 | PAIR | 3 | 5 | 5 | 10 | 5 | 14 | 6 | 10 | 12 | 12 | 12 | 12 | 15 |  |  |
| BMC_I2C4_MINI4_SCL | I2C62-DIFF1 | PAIR | 4 | 5 | 5 | 10 | 5 | 14 | 6 | 10 | 12 | 12 | 12 | 12 | 15 |  |  |
| BMC_I2C4_MINI4_SCL | I2C62-DIFF1 | PAIR | 5 | 5 | 5 | 10 | 5 | 14 | 6 | 10 | 12 | 12 | 12 | 12 | 15 |  |  |
| BMC_I2C4_MINI4_SCL | I2C62-DIFF1 | PAIR | 6 | 5 | 5 | 10 | 5 | 14 | 6 | 10 | 12 | 12 | 12 | 12 | 15 |  |  |
| BMC_I2C4_MINI4_SCL | I2C62-DIFF1 | PAIR | 7 | 5 | 5 | 10 | 5 | 14 | 6 | 10 | 12 | 12 | 12 | 12 | 15 |  |  |
| BMC_I2C4_MINI4_SCL | I2C62-DIFF1 | PAIR | 8 | 4.75 | 5 | 10 | 5 | 14 | 6 | 9.5 | 12 | 12 | 12 | 12 | 15 |  |  |
| BMC_I2C4_MINI4_SDA | I2C62-DIFF1 | PAIR | 1 | 4.75 | 5 | 10 | 5 | 14 | 6 | 9.5 | 12 | 12 | 12 | 12 | 15 |  |  |
| BMC_I2C4_MINI4_SDA | I2C62-DIFF1 | PAIR | 2 | 5 | 5 | 10 | 5 | 14 | 6 | 10 | 12 | 12 | 12 | 12 | 15 |  |  |
| BMC_I2C4_MINI4_SDA | I2C62-DIFF1 | PAIR | 3 | 5 | 5 | 10 | 5 | 14 | 6 | 10 | 12 | 12 | 12 | 12 | 15 |  |  |
| BMC_I2C4_MINI4_SDA | I2C62-DIFF1 | PAIR | 4 | 5 | 5 | 10 | 5 | 14 | 6 | 10 | 12 | 12 | 12 | 12 | 15 |  |  |
| BMC_I2C4_MINI4_SDA | I2C62-DIFF1 | PAIR | 5 | 5 | 5 | 10 | 5 | 14 | 6 | 10 | 12 | 12 | 12 | 12 | 15 |  |  |
| BMC_I2C4_MINI4_SDA | I2C62-DIFF1 | PAIR | 6 | 5 | 5 | 10 | 5 | 14 | 6 | 10 | 12 | 12 | 12 | 12 | 15 |  |  |
| BMC_I2C4_MINI4_SDA | I2C62-DIFF1 | PAIR | 7 | 5 | 5 | 10 | 5 | 14 | 6 | 10 | 12 | 12 | 12 | 12 | 15 |  |  |
| BMC_I2C4_MINI4_SDA | I2C62-DIFF1 | PAIR | 8 | 4.75 | 5 | 10 | 5 | 14 | 6 | 9.5 | 12 | 12 | 12 | 12 | 15 |  |  |
| BMC_I2C9_CLKBUF2_SCL | I2C63-DIFF1 | PAIR | 1 | 4.75 | 5 | 10 | 5 | 14 | 6 | 9.5 | 12 | 12 | 12 | 12 | 15 |  |  |
| BMC_I2C9_CLKBUF2_SCL | I2C63-DIFF1 | PAIR | 2 | 5 | 5 | 10 | 5 | 14 | 6 | 10 | 12 | 12 | 12 | 12 | 15 |  |  |
| BMC_I2C9_CLKBUF2_SCL | I2C63-DIFF1 | PAIR | 3 | 5 | 5 | 10 | 5 | 14 | 6 | 10 | 12 | 12 | 12 | 12 | 15 |  |  |
| BMC_I2C9_CLKBUF2_SCL | I2C63-DIFF1 | PAIR | 4 | 5 | 5 | 10 | 5 | 14 | 6 | 10 | 12 | 12 | 12 | 12 | 15 |  |  |
| BMC_I2C9_CLKBUF2_SCL | I2C63-DIFF1 | PAIR | 5 | 5 | 5 | 10 | 5 | 14 | 6 | 10 | 12 | 12 | 12 | 12 | 15 |  |  |
| BMC_I2C9_CLKBUF2_SCL | I2C63-DIFF1 | PAIR | 6 | 5 | 5 | 10 | 5 | 14 | 6 | 10 | 12 | 12 | 12 | 12 | 15 |  |  |
| BMC_I2C9_CLKBUF2_SCL | I2C63-DIFF1 | PAIR | 7 | 5 | 5 | 10 | 5 | 14 | 6 | 10 | 12 | 12 | 12 | 12 | 15 |  |  |
| BMC_I2C9_CLKBUF2_SCL | I2C63-DIFF1 | PAIR | 8 | 4.75 | 5 | 10 | 5 | 14 | 6 | 9.5 | 12 | 12 | 12 | 12 | 15 |  |  |
| BMC_I2C9_CLKBUF2_SDA | I2C63-DIFF1 | PAIR | 1 | 4.75 | 5 | 10 | 5 | 14 | 6 | 9.5 | 12 | 12 | 12 | 12 | 15 |  |  |
| BMC_I2C9_CLKBUF2_SDA | I2C63-DIFF1 | PAIR | 2 | 5 | 5 | 10 | 5 | 14 | 6 | 10 | 12 | 12 | 12 | 12 | 15 |  |  |
| BMC_I2C9_CLKBUF2_SDA | I2C63-DIFF1 | PAIR | 3 | 5 | 5 | 10 | 5 | 14 | 6 | 10 | 12 | 12 | 12 | 12 | 15 |  |  |
| BMC_I2C9_CLKBUF2_SDA | I2C63-DIFF1 | PAIR | 4 | 5 | 5 | 10 | 5 | 14 | 6 | 10 | 12 | 12 | 12 | 12 | 15 |  |  |
| BMC_I2C9_CLKBUF2_SDA | I2C63-DIFF1 | PAIR | 5 | 5 | 5 | 10 | 5 | 14 | 6 | 10 | 12 | 12 | 12 | 12 | 15 |  |  |
| BMC_I2C9_CLKBUF2_SDA | I2C63-DIFF1 | PAIR | 6 | 5 | 5 | 10 | 5 | 14 | 6 | 10 | 12 | 12 | 12 | 12 | 15 |  |  |
| BMC_I2C9_CLKBUF2_SDA | I2C63-DIFF1 | PAIR | 7 | 5 | 5 | 10 | 5 | 14 | 6 | 10 | 12 | 12 | 12 | 12 | 15 |  |  |
| BMC_I2C9_CLKBUF2_SDA | I2C63-DIFF1 | PAIR | 8 | 4.75 | 5 | 10 | 5 | 14 | 6 | 9.5 | 12 | 12 | 12 | 12 | 15 |  |  |
| HSW_SCL_2 | I2C64-DIFF1 | PAIR | 1 | 4.75 | 5 | 10 | 5 | 14 | 6 | 9.5 | 12 | 12 | 12 | 12 | 15 |  |  |
| HSW_SCL_2 | I2C64-DIFF1 | PAIR | 2 | 5 | 5 | 10 | 5 | 14 | 6 | 10 | 12 | 12 | 12 | 12 | 15 |  |  |
| HSW_SCL_2 | I2C64-DIFF1 | PAIR | 3 | 5 | 5 | 10 | 5 | 14 | 6 | 10 | 12 | 12 | 12 | 12 | 15 |  |  |
| HSW_SCL_2 | I2C64-DIFF1 | PAIR | 4 | 5 | 5 | 10 | 5 | 14 | 6 | 10 | 12 | 12 | 12 | 12 | 15 |  |  |
| HSW_SCL_2 | I2C64-DIFF1 | PAIR | 5 | 5 | 5 | 10 | 5 | 14 | 6 | 10 | 12 | 12 | 12 | 12 | 15 |  |  |
| HSW_SCL_2 | I2C64-DIFF1 | PAIR | 6 | 5 | 5 | 10 | 5 | 14 | 6 | 10 | 12 | 12 | 12 | 12 | 15 |  |  |
| HSW_SCL_2 | I2C64-DIFF1 | PAIR | 7 | 5 | 5 | 10 | 5 | 14 | 6 | 10 | 12 | 12 | 12 | 12 | 15 |  |  |
| HSW_SCL_2 | I2C64-DIFF1 | PAIR | 8 | 4.75 | 5 | 10 | 5 | 14 | 6 | 9.5 | 12 | 12 | 12 | 12 | 15 |  |  |
| HSW_SDA_2 | I2C64-DIFF1 | PAIR | 1 | 4.75 | 5 | 10 | 5 | 14 | 6 | 9.5 | 12 | 12 | 12 | 12 | 15 |  |  |
| HSW_SDA_2 | I2C64-DIFF1 | PAIR | 2 | 5 | 5 | 10 | 5 | 14 | 6 | 10 | 12 | 12 | 12 | 12 | 15 |  |  |
| HSW_SDA_2 | I2C64-DIFF1 | PAIR | 3 | 5 | 5 | 10 | 5 | 14 | 6 | 10 | 12 | 12 | 12 | 12 | 15 |  |  |
| HSW_SDA_2 | I2C64-DIFF1 | PAIR | 4 | 5 | 5 | 10 | 5 | 14 | 6 | 10 | 12 | 12 | 12 | 12 | 15 |  |  |
| HSW_SDA_2 | I2C64-DIFF1 | PAIR | 5 | 5 | 5 | 10 | 5 | 14 | 6 | 10 | 12 | 12 | 12 | 12 | 15 |  |  |
| HSW_SDA_2 | I2C64-DIFF1 | PAIR | 6 | 5 | 5 | 10 | 5 | 14 | 6 | 10 | 12 | 12 | 12 | 12 | 15 |  |  |
| HSW_SDA_2 | I2C64-DIFF1 | PAIR | 7 | 5 | 5 | 10 | 5 | 14 | 6 | 10 | 12 | 12 | 12 | 12 | 15 |  |  |
| HSW_SDA_2 | I2C64-DIFF1 | PAIR | 8 | 4.75 | 5 | 10 | 5 | 14 | 6 | 9.5 | 12 | 12 | 12 | 12 | 15 |  |  |
| I2C_GPIO_SCL_1 | I2C66-DIFF1 | PAIR | 1 | 4.75 | 5 | 10 | 5 | 14 | 6 | 9.5 | 12 | 12 | 12 | 12 | 15 |  |  |
| I2C_GPIO_SCL_1 | I2C66-DIFF1 | PAIR | 2 | 5 | 5 | 10 | 5 | 14 | 6 | 10 | 12 | 12 | 12 | 12 | 15 |  |  |
| I2C_GPIO_SCL_1 | I2C66-DIFF1 | PAIR | 3 | 5 | 5 | 10 | 5 | 14 | 6 | 10 | 12 | 12 | 12 | 12 | 15 |  |  |
| I2C_GPIO_SCL_1 | I2C66-DIFF1 | PAIR | 4 | 5 | 5 | 10 | 5 | 14 | 6 | 10 | 12 | 12 | 12 | 12 | 15 |  |  |
| I2C_GPIO_SCL_1 | I2C66-DIFF1 | PAIR | 5 | 5 | 5 | 10 | 5 | 14 | 6 | 10 | 12 | 12 | 12 | 12 | 15 |  |  |
| I2C_GPIO_SCL_1 | I2C66-DIFF1 | PAIR | 6 | 5 | 5 | 10 | 5 | 14 | 6 | 10 | 12 | 12 | 12 | 12 | 15 |  |  |
| I2C_GPIO_SCL_1 | I2C66-DIFF1 | PAIR | 7 | 5 | 5 | 10 | 5 | 14 | 6 | 10 | 12 | 12 | 12 | 12 | 15 |  |  |
| I2C_GPIO_SCL_1 | I2C66-DIFF1 | PAIR | 8 | 4.75 | 5 | 10 | 5 | 14 | 6 | 9.5 | 12 | 12 | 12 | 12 | 15 |  |  |
| I2C_GPIO_SDA_1 | I2C66-DIFF1 | PAIR | 1 | 4.75 | 5 | 10 | 5 | 14 | 6 | 9.5 | 12 | 12 | 12 | 12 | 15 |  |  |
| I2C_GPIO_SDA_1 | I2C66-DIFF1 | PAIR | 2 | 5 | 5 | 10 | 5 | 14 | 6 | 10 | 12 | 12 | 12 | 12 | 15 |  |  |
| I2C_GPIO_SDA_1 | I2C66-DIFF1 | PAIR | 3 | 5 | 5 | 10 | 5 | 14 | 6 | 10 | 12 | 12 | 12 | 12 | 15 |  |  |
| I2C_GPIO_SDA_1 | I2C66-DIFF1 | PAIR | 4 | 5 | 5 | 10 | 5 | 14 | 6 | 10 | 12 | 12 | 12 | 12 | 15 |  |  |
| I2C_GPIO_SDA_1 | I2C66-DIFF1 | PAIR | 5 | 5 | 5 | 10 | 5 | 14 | 6 | 10 | 12 | 12 | 12 | 12 | 15 |  |  |
| I2C_GPIO_SDA_1 | I2C66-DIFF1 | PAIR | 6 | 5 | 5 | 10 | 5 | 14 | 6 | 10 | 12 | 12 | 12 | 12 | 15 |  |  |
| I2C_GPIO_SDA_1 | I2C66-DIFF1 | PAIR | 7 | 5 | 5 | 10 | 5 | 14 | 6 | 10 | 12 | 12 | 12 | 12 | 15 |  |  |
| I2C_GPIO_SDA_1 | I2C66-DIFF1 | PAIR | 8 | 4.75 | 5 | 10 | 5 | 14 | 6 | 9.5 | 12 | 12 | 12 | 12 | 15 |  |  |
| I2C_GPIO_SCL_2 | I2C67-DIFF1 | PAIR | 1 | 4.75 | 5 | 10 | 5 | 14 | 6 | 9.5 | 12 | 12 | 12 | 12 | 15 |  |  |
| I2C_GPIO_SCL_2 | I2C67-DIFF1 | PAIR | 2 | 5 | 5 | 10 | 5 | 14 | 6 | 10 | 12 | 12 | 12 | 12 | 15 |  |  |
| I2C_GPIO_SCL_2 | I2C67-DIFF1 | PAIR | 3 | 5 | 5 | 10 | 5 | 14 | 6 | 10 | 12 | 12 | 12 | 12 | 15 |  |  |
| I2C_GPIO_SCL_2 | I2C67-DIFF1 | PAIR | 4 | 5 | 5 | 10 | 5 | 14 | 6 | 10 | 12 | 12 | 12 | 12 | 15 |  |  |
| I2C_GPIO_SCL_2 | I2C67-DIFF1 | PAIR | 5 | 5 | 5 | 10 | 5 | 14 | 6 | 10 | 12 | 12 | 12 | 12 | 15 |  |  |
| I2C_GPIO_SCL_2 | I2C67-DIFF1 | PAIR | 6 | 5 | 5 | 10 | 5 | 14 | 6 | 10 | 12 | 12 | 12 | 12 | 15 |  |  |
| I2C_GPIO_SCL_2 | I2C67-DIFF1 | PAIR | 7 | 5 | 5 | 10 | 5 | 14 | 6 | 10 | 12 | 12 | 12 | 12 | 15 |  |  |
| I2C_GPIO_SCL_2 | I2C67-DIFF1 | PAIR | 8 | 4.75 | 5 | 10 | 5 | 14 | 6 | 9.5 | 12 | 12 | 12 | 12 | 15 |  |  |
| I2C_GPIO_SDA_2 | I2C67-DIFF1 | PAIR | 1 | 4.75 | 5 | 10 | 5 | 14 | 6 | 9.5 | 12 | 12 | 12 | 12 | 15 |  |  |
| I2C_GPIO_SDA_2 | I2C67-DIFF1 | PAIR | 2 | 5 | 5 | 10 | 5 | 14 | 6 | 10 | 12 | 12 | 12 | 12 | 15 |  |  |
| I2C_GPIO_SDA_2 | I2C67-DIFF1 | PAIR | 3 | 5 | 5 | 10 | 5 | 14 | 6 | 10 | 12 | 12 | 12 | 12 | 15 |  |  |
| I2C_GPIO_SDA_2 | I2C67-DIFF1 | PAIR | 4 | 5 | 5 | 10 | 5 | 14 | 6 | 10 | 12 | 12 | 12 | 12 | 15 |  |  |
| I2C_GPIO_SDA_2 | I2C67-DIFF1 | PAIR | 5 | 5 | 5 | 10 | 5 | 14 | 6 | 10 | 12 | 12 | 12 | 12 | 15 |  |  |
| I2C_GPIO_SDA_2 | I2C67-DIFF1 | PAIR | 6 | 5 | 5 | 10 | 5 | 14 | 6 | 10 | 12 | 12 | 12 | 12 | 15 |  |  |
| I2C_GPIO_SDA_2 | I2C67-DIFF1 | PAIR | 7 | 5 | 5 | 10 | 5 | 14 | 6 | 10 | 12 | 12 | 12 | 12 | 15 |  |  |
| I2C_GPIO_SDA_2 | I2C67-DIFF1 | PAIR | 8 | 4.75 | 5 | 10 | 5 | 14 | 6 | 9.5 | 12 | 12 | 12 | 12 | 15 |  |  |
| I2C_GPIO_SCL_3 | I2C68-DIFF1 | PAIR | 1 | 4.75 | 5 | 10 | 5 | 14 | 6 | 9.5 | 12 | 12 | 12 | 12 | 15 |  |  |
| I2C_GPIO_SCL_3 | I2C68-DIFF1 | PAIR | 2 | 5 | 5 | 10 | 5 | 14 | 6 | 10 | 12 | 12 | 12 | 12 | 15 |  |  |
| I2C_GPIO_SCL_3 | I2C68-DIFF1 | PAIR | 3 | 5 | 5 | 10 | 5 | 14 | 6 | 10 | 12 | 12 | 12 | 12 | 15 |  |  |
| I2C_GPIO_SCL_3 | I2C68-DIFF1 | PAIR | 4 | 5 | 5 | 10 | 5 | 14 | 6 | 10 | 12 | 12 | 12 | 12 | 15 |  |  |
| I2C_GPIO_SCL_3 | I2C68-DIFF1 | PAIR | 5 | 5 | 5 | 10 | 5 | 14 | 6 | 10 | 12 | 12 | 12 | 12 | 15 |  |  |
| I2C_GPIO_SCL_3 | I2C68-DIFF1 | PAIR | 6 | 5 | 5 | 10 | 5 | 14 | 6 | 10 | 12 | 12 | 12 | 12 | 15 |  |  |
| I2C_GPIO_SCL_3 | I2C68-DIFF1 | PAIR | 7 | 5 | 5 | 10 | 5 | 14 | 6 | 10 | 12 | 12 | 12 | 12 | 15 |  |  |
| I2C_GPIO_SCL_3 | I2C68-DIFF1 | PAIR | 8 | 4.75 | 5 | 10 | 5 | 14 | 6 | 9.5 | 12 | 12 | 12 | 12 | 15 |  |  |
| I2C_GPIO_SDA_3 | I2C68-DIFF1 | PAIR | 1 | 4.75 | 5 | 10 | 5 | 14 | 6 | 9.5 | 12 | 12 | 12 | 12 | 15 |  |  |
| I2C_GPIO_SDA_3 | I2C68-DIFF1 | PAIR | 2 | 5 | 5 | 10 | 5 | 14 | 6 | 10 | 12 | 12 | 12 | 12 | 15 |  |  |
| I2C_GPIO_SDA_3 | I2C68-DIFF1 | PAIR | 3 | 5 | 5 | 10 | 5 | 14 | 6 | 10 | 12 | 12 | 12 | 12 | 15 |  |  |
| I2C_GPIO_SDA_3 | I2C68-DIFF1 | PAIR | 4 | 5 | 5 | 10 | 5 | 14 | 6 | 10 | 12 | 12 | 12 | 12 | 15 |  |  |
| I2C_GPIO_SDA_3 | I2C68-DIFF1 | PAIR | 5 | 5 | 5 | 10 | 5 | 14 | 6 | 10 | 12 | 12 | 12 | 12 | 15 |  |  |
| I2C_GPIO_SDA_3 | I2C68-DIFF1 | PAIR | 6 | 5 | 5 | 10 | 5 | 14 | 6 | 10 | 12 | 12 | 12 | 12 | 15 |  |  |
| I2C_GPIO_SDA_3 | I2C68-DIFF1 | PAIR | 7 | 5 | 5 | 10 | 5 | 14 | 6 | 10 | 12 | 12 | 12 | 12 | 15 |  |  |
| I2C_GPIO_SDA_3 | I2C68-DIFF1 | PAIR | 8 | 4.75 | 5 | 10 | 5 | 14 | 6 | 9.5 | 12 | 12 | 12 | 12 | 15 |  |  |
| BUF_I2C9_CLKBUF2_SCL | I2C69-DIFF1 | PAIR | 1 | 4.75 | 5 | 10 | 5 | 14 | 6 | 9.5 | 12 | 12 | 12 | 12 | 15 |  |  |
| BUF_I2C9_CLKBUF2_SCL | I2C69-DIFF1 | PAIR | 2 | 5 | 5 | 10 | 5 | 14 | 6 | 10 | 12 | 12 | 12 | 12 | 15 |  |  |
| BUF_I2C9_CLKBUF2_SCL | I2C69-DIFF1 | PAIR | 3 | 5 | 5 | 10 | 5 | 14 | 6 | 10 | 12 | 12 | 12 | 12 | 15 |  |  |
| BUF_I2C9_CLKBUF2_SCL | I2C69-DIFF1 | PAIR | 4 | 5 | 5 | 10 | 5 | 14 | 6 | 10 | 12 | 12 | 12 | 12 | 15 |  |  |
| BUF_I2C9_CLKBUF2_SCL | I2C69-DIFF1 | PAIR | 5 | 5 | 5 | 10 | 5 | 14 | 6 | 10 | 12 | 12 | 12 | 12 | 15 |  |  |
| BUF_I2C9_CLKBUF2_SCL | I2C69-DIFF1 | PAIR | 6 | 5 | 5 | 10 | 5 | 14 | 6 | 10 | 12 | 12 | 12 | 12 | 15 |  |  |
| BUF_I2C9_CLKBUF2_SCL | I2C69-DIFF1 | PAIR | 7 | 5 | 5 | 10 | 5 | 14 | 6 | 10 | 12 | 12 | 12 | 12 | 15 |  |  |
| BUF_I2C9_CLKBUF2_SCL | I2C69-DIFF1 | PAIR | 8 | 4.75 | 5 | 10 | 5 | 14 | 6 | 9.5 | 12 | 12 | 12 | 12 | 15 |  |  |
| BUF_I2C9_CLKBUF2_SDA | I2C69-DIFF1 | PAIR | 1 | 4.75 | 5 | 10 | 5 | 14 | 6 | 9.5 | 12 | 12 | 12 | 12 | 15 |  |  |
| BUF_I2C9_CLKBUF2_SDA | I2C69-DIFF1 | PAIR | 2 | 5 | 5 | 10 | 5 | 14 | 6 | 10 | 12 | 12 | 12 | 12 | 15 |  |  |
| BUF_I2C9_CLKBUF2_SDA | I2C69-DIFF1 | PAIR | 3 | 5 | 5 | 10 | 5 | 14 | 6 | 10 | 12 | 12 | 12 | 12 | 15 |  |  |
| BUF_I2C9_CLKBUF2_SDA | I2C69-DIFF1 | PAIR | 4 | 5 | 5 | 10 | 5 | 14 | 6 | 10 | 12 | 12 | 12 | 12 | 15 |  |  |
| BUF_I2C9_CLKBUF2_SDA | I2C69-DIFF1 | PAIR | 5 | 5 | 5 | 10 | 5 | 14 | 6 | 10 | 12 | 12 | 12 | 12 | 15 |  |  |
| BUF_I2C9_CLKBUF2_SDA | I2C69-DIFF1 | PAIR | 6 | 5 | 5 | 10 | 5 | 14 | 6 | 10 | 12 | 12 | 12 | 12 | 15 |  |  |
| BUF_I2C9_CLKBUF2_SDA | I2C69-DIFF1 | PAIR | 7 | 5 | 5 | 10 | 5 | 14 | 6 | 10 | 12 | 12 | 12 | 12 | 15 |  |  |
| BUF_I2C9_CLKBUF2_SDA | I2C69-DIFF1 | PAIR | 8 | 4.75 | 5 | 10 | 5 | 14 | 6 | 9.5 | 12 | 12 | 12 | 12 | 15 |  |  |
| BUF_I2C8_CLKBUF1_SCL | I2C70-DIFF1 | PAIR | 1 | 4.75 | 5 | 10 | 5 | 14 | 6 | 9.5 | 12 | 12 | 12 | 12 | 15 |  |  |
| BUF_I2C8_CLKBUF1_SCL | I2C70-DIFF1 | PAIR | 2 | 5 | 5 | 10 | 5 | 14 | 6 | 10 | 12 | 12 | 12 | 12 | 15 |  |  |
| BUF_I2C8_CLKBUF1_SCL | I2C70-DIFF1 | PAIR | 3 | 5 | 5 | 10 | 5 | 14 | 6 | 10 | 12 | 12 | 12 | 12 | 15 |  |  |
| BUF_I2C8_CLKBUF1_SCL | I2C70-DIFF1 | PAIR | 4 | 5 | 5 | 10 | 5 | 14 | 6 | 10 | 12 | 12 | 12 | 12 | 15 |  |  |
| BUF_I2C8_CLKBUF1_SCL | I2C70-DIFF1 | PAIR | 5 | 5 | 5 | 10 | 5 | 14 | 6 | 10 | 12 | 12 | 12 | 12 | 15 |  |  |
| BUF_I2C8_CLKBUF1_SCL | I2C70-DIFF1 | PAIR | 6 | 5 | 5 | 10 | 5 | 14 | 6 | 10 | 12 | 12 | 12 | 12 | 15 |  |  |
| BUF_I2C8_CLKBUF1_SCL | I2C70-DIFF1 | PAIR | 7 | 5 | 5 | 10 | 5 | 14 | 6 | 10 | 12 | 12 | 12 | 12 | 15 |  |  |
| BUF_I2C8_CLKBUF1_SCL | I2C70-DIFF1 | PAIR | 8 | 4.75 | 5 | 10 | 5 | 14 | 6 | 9.5 | 12 | 12 | 12 | 12 | 15 |  |  |
| BUF_I2C8_CLKBUF1_SDA | I2C70-DIFF1 | PAIR | 1 | 4.75 | 5 | 10 | 5 | 14 | 6 | 9.5 | 12 | 12 | 12 | 12 | 15 |  |  |
| BUF_I2C8_CLKBUF1_SDA | I2C70-DIFF1 | PAIR | 2 | 5 | 5 | 10 | 5 | 14 | 6 | 10 | 12 | 12 | 12 | 12 | 15 |  |  |
| BUF_I2C8_CLKBUF1_SDA | I2C70-DIFF1 | PAIR | 3 | 5 | 5 | 10 | 5 | 14 | 6 | 10 | 12 | 12 | 12 | 12 | 15 |  |  |
| BUF_I2C8_CLKBUF1_SDA | I2C70-DIFF1 | PAIR | 4 | 5 | 5 | 10 | 5 | 14 | 6 | 10 | 12 | 12 | 12 | 12 | 15 |  |  |
| BUF_I2C8_CLKBUF1_SDA | I2C70-DIFF1 | PAIR | 5 | 5 | 5 | 10 | 5 | 14 | 6 | 10 | 12 | 12 | 12 | 12 | 15 |  |  |
| BUF_I2C8_CLKBUF1_SDA | I2C70-DIFF1 | PAIR | 6 | 5 | 5 | 10 | 5 | 14 | 6 | 10 | 12 | 12 | 12 | 12 | 15 |  |  |
| BUF_I2C8_CLKBUF1_SDA | I2C70-DIFF1 | PAIR | 7 | 5 | 5 | 10 | 5 | 14 | 6 | 10 | 12 | 12 | 12 | 12 | 15 |  |  |
| BUF_I2C8_CLKBUF1_SDA | I2C70-DIFF1 | PAIR | 8 | 4.75 | 5 | 10 | 5 | 14 | 6 | 9.5 | 12 | 12 | 12 | 12 | 15 |  |  |
| BMC_I2C8_CLKBUF1_SCL | I2C71-DIFF1 | PAIR | 1 | 4.75 | 5 | 10 | 5 | 14 | 6 | 9.5 | 12 | 12 | 12 | 12 | 15 |  |  |
| BMC_I2C8_CLKBUF1_SCL | I2C71-DIFF1 | PAIR | 2 | 5 | 5 | 10 | 5 | 14 | 6 | 10 | 12 | 12 | 12 | 12 | 15 |  |  |
| BMC_I2C8_CLKBUF1_SCL | I2C71-DIFF1 | PAIR | 3 | 5 | 5 | 10 | 5 | 14 | 6 | 10 | 12 | 12 | 12 | 12 | 15 |  |  |
| BMC_I2C8_CLKBUF1_SCL | I2C71-DIFF1 | PAIR | 4 | 5 | 5 | 10 | 5 | 14 | 6 | 10 | 12 | 12 | 12 | 12 | 15 |  |  |
| BMC_I2C8_CLKBUF1_SCL | I2C71-DIFF1 | PAIR | 5 | 5 | 5 | 10 | 5 | 14 | 6 | 10 | 12 | 12 | 12 | 12 | 15 |  |  |
| BMC_I2C8_CLKBUF1_SCL | I2C71-DIFF1 | PAIR | 6 | 5 | 5 | 10 | 5 | 14 | 6 | 10 | 12 | 12 | 12 | 12 | 15 |  |  |
| BMC_I2C8_CLKBUF1_SCL | I2C71-DIFF1 | PAIR | 7 | 5 | 5 | 10 | 5 | 14 | 6 | 10 | 12 | 12 | 12 | 12 | 15 |  |  |
| BMC_I2C8_CLKBUF1_SCL | I2C71-DIFF1 | PAIR | 8 | 4.75 | 5 | 10 | 5 | 14 | 6 | 9.5 | 12 | 12 | 12 | 12 | 15 |  |  |
| BMC_I2C8_CLKBUF1_SDA | I2C71-DIFF1 | PAIR | 1 | 4.75 | 5 | 10 | 5 | 14 | 6 | 9.5 | 12 | 12 | 12 | 12 | 15 |  |  |
| BMC_I2C8_CLKBUF1_SDA | I2C71-DIFF1 | PAIR | 2 | 5 | 5 | 10 | 5 | 14 | 6 | 10 | 12 | 12 | 12 | 12 | 15 |  |  |
| BMC_I2C8_CLKBUF1_SDA | I2C71-DIFF1 | PAIR | 3 | 5 | 5 | 10 | 5 | 14 | 6 | 10 | 12 | 12 | 12 | 12 | 15 |  |  |
| BMC_I2C8_CLKBUF1_SDA | I2C71-DIFF1 | PAIR | 4 | 5 | 5 | 10 | 5 | 14 | 6 | 10 | 12 | 12 | 12 | 12 | 15 |  |  |
| BMC_I2C8_CLKBUF1_SDA | I2C71-DIFF1 | PAIR | 5 | 5 | 5 | 10 | 5 | 14 | 6 | 10 | 12 | 12 | 12 | 12 | 15 |  |  |
| BMC_I2C8_CLKBUF1_SDA | I2C71-DIFF1 | PAIR | 6 | 5 | 5 | 10 | 5 | 14 | 6 | 10 | 12 | 12 | 12 | 12 | 15 |  |  |
| BMC_I2C8_CLKBUF1_SDA | I2C71-DIFF1 | PAIR | 7 | 5 | 5 | 10 | 5 | 14 | 6 | 10 | 12 | 12 | 12 | 12 | 15 |  |  |
| BMC_I2C8_CLKBUF1_SDA | I2C71-DIFF1 | PAIR | 8 | 4.75 | 5 | 10 | 5 | 14 | 6 | 9.5 | 12 | 12 | 12 | 12 | 15 |  |  |
| BMC_I2C6_C_FCB_SCL | I2C72-DIFF1 | PAIR | 1 | 4.75 | 5 | 10 | 5 | 14 | 6 | 9.5 | 12 | 12 | 12 | 12 | 15 |  |  |
| BMC_I2C6_C_FCB_SCL | I2C72-DIFF1 | PAIR | 2 | 5 | 5 | 10 | 5 | 14 | 6 | 10 | 12 | 12 | 12 | 12 | 15 |  |  |
| BMC_I2C6_C_FCB_SCL | I2C72-DIFF1 | PAIR | 3 | 5 | 5 | 10 | 5 | 14 | 6 | 10 | 12 | 12 | 12 | 12 | 15 |  |  |
| BMC_I2C6_C_FCB_SCL | I2C72-DIFF1 | PAIR | 4 | 5 | 5 | 10 | 5 | 14 | 6 | 10 | 12 | 12 | 12 | 12 | 15 |  |  |
| BMC_I2C6_C_FCB_SCL | I2C72-DIFF1 | PAIR | 5 | 5 | 5 | 10 | 5 | 14 | 6 | 10 | 12 | 12 | 12 | 12 | 15 |  |  |
| BMC_I2C6_C_FCB_SCL | I2C72-DIFF1 | PAIR | 6 | 5 | 5 | 10 | 5 | 14 | 6 | 10 | 12 | 12 | 12 | 12 | 15 |  |  |
| BMC_I2C6_C_FCB_SCL | I2C72-DIFF1 | PAIR | 7 | 5 | 5 | 10 | 5 | 14 | 6 | 10 | 12 | 12 | 12 | 12 | 15 |  |  |
| BMC_I2C6_C_FCB_SCL | I2C72-DIFF1 | PAIR | 8 | 4.75 | 5 | 10 | 5 | 14 | 6 | 9.5 | 12 | 12 | 12 | 12 | 15 |  |  |
| BMC_I2C6_C_FCB_SDA | I2C72-DIFF1 | PAIR | 1 | 4.75 | 5 | 10 | 5 | 14 | 6 | 9.5 | 12 | 12 | 12 | 12 | 15 |  |  |
| BMC_I2C6_C_FCB_SDA | I2C72-DIFF1 | PAIR | 2 | 5 | 5 | 10 | 5 | 14 | 6 | 10 | 12 | 12 | 12 | 12 | 15 |  |  |
| BMC_I2C6_C_FCB_SDA | I2C72-DIFF1 | PAIR | 3 | 5 | 5 | 10 | 5 | 14 | 6 | 10 | 12 | 12 | 12 | 12 | 15 |  |  |
| BMC_I2C6_C_FCB_SDA | I2C72-DIFF1 | PAIR | 4 | 5 | 5 | 10 | 5 | 14 | 6 | 10 | 12 | 12 | 12 | 12 | 15 |  |  |
| BMC_I2C6_C_FCB_SDA | I2C72-DIFF1 | PAIR | 5 | 5 | 5 | 10 | 5 | 14 | 6 | 10 | 12 | 12 | 12 | 12 | 15 |  |  |
| BMC_I2C6_C_FCB_SDA | I2C72-DIFF1 | PAIR | 6 | 5 | 5 | 10 | 5 | 14 | 6 | 10 | 12 | 12 | 12 | 12 | 15 |  |  |
| BMC_I2C6_C_FCB_SDA | I2C72-DIFF1 | PAIR | 7 | 5 | 5 | 10 | 5 | 14 | 6 | 10 | 12 | 12 | 12 | 12 | 15 |  |  |
| BMC_I2C6_C_FCB_SDA | I2C72-DIFF1 | PAIR | 8 | 4.75 | 5 | 10 | 5 | 14 | 6 | 9.5 | 12 | 12 | 12 | 12 | 15 |  |  |
| I2C_MUX_3A | I2C73-DIFF1 | PAIR | 1 | 4.75 | 5 | 10 | 5 | 14 | 6 | 9.5 | 12 | 12 | 12 | 12 | 15 |  |  |
| I2C_MUX_3A | I2C73-DIFF1 | PAIR | 2 | 5 | 5 | 10 | 5 | 14 | 6 | 10 | 12 | 12 | 12 | 12 | 15 |  |  |
| I2C_MUX_3A | I2C73-DIFF1 | PAIR | 3 | 5 | 5 | 10 | 5 | 14 | 6 | 10 | 12 | 12 | 12 | 12 | 15 |  |  |
| I2C_MUX_3A | I2C73-DIFF1 | PAIR | 4 | 5 | 5 | 10 | 5 | 14 | 6 | 10 | 12 | 12 | 12 | 12 | 15 |  |  |
| I2C_MUX_3A | I2C73-DIFF1 | PAIR | 5 | 5 | 5 | 10 | 5 | 14 | 6 | 10 | 12 | 12 | 12 | 12 | 15 |  |  |
| I2C_MUX_3A | I2C73-DIFF1 | PAIR | 6 | 5 | 5 | 10 | 5 | 14 | 6 | 10 | 12 | 12 | 12 | 12 | 15 |  |  |
| I2C_MUX_3A | I2C73-DIFF1 | PAIR | 7 | 5 | 5 | 10 | 5 | 14 | 6 | 10 | 12 | 12 | 12 | 12 | 15 |  |  |
| I2C_MUX_3A | I2C73-DIFF1 | PAIR | 8 | 4.75 | 5 | 10 | 5 | 14 | 6 | 9.5 | 12 | 12 | 12 | 12 | 15 |  |  |
| I2C_MUX_4A | I2C73-DIFF1 | PAIR | 1 | 4.75 | 5 | 10 | 5 | 14 | 6 | 9.5 | 12 | 12 | 12 | 12 | 15 |  |  |
| I2C_MUX_4A | I2C73-DIFF1 | PAIR | 2 | 5 | 5 | 10 | 5 | 14 | 6 | 10 | 12 | 12 | 12 | 12 | 15 |  |  |
| I2C_MUX_4A | I2C73-DIFF1 | PAIR | 3 | 5 | 5 | 10 | 5 | 14 | 6 | 10 | 12 | 12 | 12 | 12 | 15 |  |  |
| I2C_MUX_4A | I2C73-DIFF1 | PAIR | 4 | 5 | 5 | 10 | 5 | 14 | 6 | 10 | 12 | 12 | 12 | 12 | 15 |  |  |
| I2C_MUX_4A | I2C73-DIFF1 | PAIR | 5 | 5 | 5 | 10 | 5 | 14 | 6 | 10 | 12 | 12 | 12 | 12 | 15 |  |  |
| I2C_MUX_4A | I2C73-DIFF1 | PAIR | 6 | 5 | 5 | 10 | 5 | 14 | 6 | 10 | 12 | 12 | 12 | 12 | 15 |  |  |
| I2C_MUX_4A | I2C73-DIFF1 | PAIR | 7 | 5 | 5 | 10 | 5 | 14 | 6 | 10 | 12 | 12 | 12 | 12 | 15 |  |  |
| I2C_MUX_4A | I2C73-DIFF1 | PAIR | 8 | 4.75 | 5 | 10 | 5 | 14 | 6 | 9.5 | 12 | 12 | 12 | 12 | 15 |  |  |
| CLKGEN_SCL | I2C74-DIFF1 | PAIR | 1 | 4.75 | 5 | 10 | 5 | 14 | 6 | 9.5 | 12 | 12 | 12 | 12 | 15 |  |  |
| CLKGEN_SCL | I2C74-DIFF1 | PAIR | 2 | 5 | 5 | 10 | 5 | 14 | 6 | 10 | 12 | 12 | 12 | 12 | 15 |  |  |
| CLKGEN_SCL | I2C74-DIFF1 | PAIR | 3 | 5 | 5 | 10 | 5 | 14 | 6 | 10 | 12 | 12 | 12 | 12 | 15 |  |  |
| CLKGEN_SCL | I2C74-DIFF1 | PAIR | 4 | 5 | 5 | 10 | 5 | 14 | 6 | 10 | 12 | 12 | 12 | 12 | 15 |  |  |
| CLKGEN_SCL | I2C74-DIFF1 | PAIR | 5 | 5 | 5 | 10 | 5 | 14 | 6 | 10 | 12 | 12 | 12 | 12 | 15 |  |  |
| CLKGEN_SCL | I2C74-DIFF1 | PAIR | 6 | 5 | 5 | 10 | 5 | 14 | 6 | 10 | 12 | 12 | 12 | 12 | 15 |  |  |
| CLKGEN_SCL | I2C74-DIFF1 | PAIR | 7 | 5 | 5 | 10 | 5 | 14 | 6 | 10 | 12 | 12 | 12 | 12 | 15 |  |  |
| CLKGEN_SCL | I2C74-DIFF1 | PAIR | 8 | 4.75 | 5 | 10 | 5 | 14 | 6 | 9.5 | 12 | 12 | 12 | 12 | 15 |  |  |
| CLKGEN_SDA | I2C74-DIFF1 | PAIR | 1 | 4.75 | 5 | 10 | 5 | 14 | 6 | 9.5 | 12 | 12 | 12 | 12 | 15 |  |  |
| CLKGEN_SDA | I2C74-DIFF1 | PAIR | 2 | 5 | 5 | 10 | 5 | 14 | 6 | 10 | 12 | 12 | 12 | 12 | 15 |  |  |
| CLKGEN_SDA | I2C74-DIFF1 | PAIR | 3 | 5 | 5 | 10 | 5 | 14 | 6 | 10 | 12 | 12 | 12 | 12 | 15 |  |  |
| CLKGEN_SDA | I2C74-DIFF1 | PAIR | 4 | 5 | 5 | 10 | 5 | 14 | 6 | 10 | 12 | 12 | 12 | 12 | 15 |  |  |
| CLKGEN_SDA | I2C74-DIFF1 | PAIR | 5 | 5 | 5 | 10 | 5 | 14 | 6 | 10 | 12 | 12 | 12 | 12 | 15 |  |  |
| CLKGEN_SDA | I2C74-DIFF1 | PAIR | 6 | 5 | 5 | 10 | 5 | 14 | 6 | 10 | 12 | 12 | 12 | 12 | 15 |  |  |
| CLKGEN_SDA | I2C74-DIFF1 | PAIR | 7 | 5 | 5 | 10 | 5 | 14 | 6 | 10 | 12 | 12 | 12 | 12 | 15 |  |  |
| CLKGEN_SDA | I2C74-DIFF1 | PAIR | 8 | 4.75 | 5 | 10 | 5 | 14 | 6 | 9.5 | 12 | 12 | 12 | 12 | 15 |  |  |
| RTC_I2C_SCL | I2C76-DIFF1 | PAIR | 1 | 4.75 | 5 | 10 | 5 | 14 | 6 | 9.5 | 12 | 12 | 12 | 12 | 15 |  |  |
| RTC_I2C_SCL | I2C76-DIFF1 | PAIR | 2 | 5 | 5 | 10 | 5 | 14 | 6 | 10 | 12 | 12 | 12 | 12 | 15 |  |  |
| RTC_I2C_SCL | I2C76-DIFF1 | PAIR | 3 | 5 | 5 | 10 | 5 | 14 | 6 | 10 | 12 | 12 | 12 | 12 | 15 |  |  |
| RTC_I2C_SCL | I2C76-DIFF1 | PAIR | 4 | 5 | 5 | 10 | 5 | 14 | 6 | 10 | 12 | 12 | 12 | 12 | 15 |  |  |
| RTC_I2C_SCL | I2C76-DIFF1 | PAIR | 5 | 5 | 5 | 10 | 5 | 14 | 6 | 10 | 12 | 12 | 12 | 12 | 15 |  |  |
| RTC_I2C_SCL | I2C76-DIFF1 | PAIR | 6 | 5 | 5 | 10 | 5 | 14 | 6 | 10 | 12 | 12 | 12 | 12 | 15 |  |  |
| RTC_I2C_SCL | I2C76-DIFF1 | PAIR | 7 | 5 | 5 | 10 | 5 | 14 | 6 | 10 | 12 | 12 | 12 | 12 | 15 |  |  |
| RTC_I2C_SCL | I2C76-DIFF1 | PAIR | 8 | 4.75 | 5 | 10 | 5 | 14 | 6 | 9.5 | 12 | 12 | 12 | 12 | 15 |  |  |
| RTC_I2C_SDA | I2C76-DIFF1 | PAIR | 1 | 4.75 | 5 | 10 | 5 | 14 | 6 | 9.5 | 12 | 12 | 12 | 12 | 15 |  |  |
| RTC_I2C_SDA | I2C76-DIFF1 | PAIR | 2 | 5 | 5 | 10 | 5 | 14 | 6 | 10 | 12 | 12 | 12 | 12 | 15 |  |  |
| RTC_I2C_SDA | I2C76-DIFF1 | PAIR | 3 | 5 | 5 | 10 | 5 | 14 | 6 | 10 | 12 | 12 | 12 | 12 | 15 |  |  |
| RTC_I2C_SDA | I2C76-DIFF1 | PAIR | 4 | 5 | 5 | 10 | 5 | 14 | 6 | 10 | 12 | 12 | 12 | 12 | 15 |  |  |
| RTC_I2C_SDA | I2C76-DIFF1 | PAIR | 5 | 5 | 5 | 10 | 5 | 14 | 6 | 10 | 12 | 12 | 12 | 12 | 15 |  |  |
| RTC_I2C_SDA | I2C76-DIFF1 | PAIR | 6 | 5 | 5 | 10 | 5 | 14 | 6 | 10 | 12 | 12 | 12 | 12 | 15 |  |  |
| RTC_I2C_SDA | I2C76-DIFF1 | PAIR | 7 | 5 | 5 | 10 | 5 | 14 | 6 | 10 | 12 | 12 | 12 | 12 | 15 |  |  |
| RTC_I2C_SDA | I2C76-DIFF1 | PAIR | 8 | 4.75 | 5 | 10 | 5 | 14 | 6 | 9.5 | 12 | 12 | 12 | 12 | 15 |  |  |
| EEPROM_SCL | I2C77-DIFF1 | PAIR | 1 | 4.75 | 5 | 10 | 5 | 14 | 6 | 9.5 | 12 | 12 | 12 | 12 | 15 |  |  |
| EEPROM_SCL | I2C77-DIFF1 | PAIR | 2 | 5 | 5 | 10 | 5 | 14 | 6 | 10 | 12 | 12 | 12 | 12 | 15 |  |  |
| EEPROM_SCL | I2C77-DIFF1 | PAIR | 3 | 5 | 5 | 10 | 5 | 14 | 6 | 10 | 12 | 12 | 12 | 12 | 15 |  |  |
| EEPROM_SCL | I2C77-DIFF1 | PAIR | 4 | 5 | 5 | 10 | 5 | 14 | 6 | 10 | 12 | 12 | 12 | 12 | 15 |  |  |
| EEPROM_SCL | I2C77-DIFF1 | PAIR | 5 | 5 | 5 | 10 | 5 | 14 | 6 | 10 | 12 | 12 | 12 | 12 | 15 |  |  |
| EEPROM_SCL | I2C77-DIFF1 | PAIR | 6 | 5 | 5 | 10 | 5 | 14 | 6 | 10 | 12 | 12 | 12 | 12 | 15 |  |  |
| EEPROM_SCL | I2C77-DIFF1 | PAIR | 7 | 5 | 5 | 10 | 5 | 14 | 6 | 10 | 12 | 12 | 12 | 12 | 15 |  |  |
| EEPROM_SCL | I2C77-DIFF1 | PAIR | 8 | 4.75 | 5 | 10 | 5 | 14 | 6 | 9.5 | 12 | 12 | 12 | 12 | 15 |  |  |
| EEPROM_SDA | I2C77-DIFF1 | PAIR | 1 | 4.75 | 5 | 10 | 5 | 14 | 6 | 9.5 | 12 | 12 | 12 | 12 | 15 |  |  |
| EEPROM_SDA | I2C77-DIFF1 | PAIR | 2 | 5 | 5 | 10 | 5 | 14 | 6 | 10 | 12 | 12 | 12 | 12 | 15 |  |  |
| EEPROM_SDA | I2C77-DIFF1 | PAIR | 3 | 5 | 5 | 10 | 5 | 14 | 6 | 10 | 12 | 12 | 12 | 12 | 15 |  |  |
| EEPROM_SDA | I2C77-DIFF1 | PAIR | 4 | 5 | 5 | 10 | 5 | 14 | 6 | 10 | 12 | 12 | 12 | 12 | 15 |  |  |
| EEPROM_SDA | I2C77-DIFF1 | PAIR | 5 | 5 | 5 | 10 | 5 | 14 | 6 | 10 | 12 | 12 | 12 | 12 | 15 |  |  |
| EEPROM_SDA | I2C77-DIFF1 | PAIR | 6 | 5 | 5 | 10 | 5 | 14 | 6 | 10 | 12 | 12 | 12 | 12 | 15 |  |  |
| EEPROM_SDA | I2C77-DIFF1 | PAIR | 7 | 5 | 5 | 10 | 5 | 14 | 6 | 10 | 12 | 12 | 12 | 12 | 15 |  |  |
| EEPROM_SDA | I2C77-DIFF1 | PAIR | 8 | 4.75 | 5 | 10 | 5 | 14 | 6 | 9.5 | 12 | 12 | 12 | 12 | 15 |  |  |
| BMC_I2C5_D_PEB_DEVICE_SCL | I2C78-DIFF1 | PAIR | 1 | 4.75 | 5 | 10 | 5 | 14 | 6 | 9.5 | 12 | 12 | 12 | 12 | 15 |  |  |
| BMC_I2C5_D_PEB_DEVICE_SCL | I2C78-DIFF1 | PAIR | 2 | 5 | 5 | 10 | 5 | 14 | 6 | 10 | 12 | 12 | 12 | 12 | 15 |  |  |
| BMC_I2C5_D_PEB_DEVICE_SCL | I2C78-DIFF1 | PAIR | 3 | 5 | 5 | 10 | 5 | 14 | 6 | 10 | 12 | 12 | 12 | 12 | 15 |  |  |
| BMC_I2C5_D_PEB_DEVICE_SCL | I2C78-DIFF1 | PAIR | 4 | 5 | 5 | 10 | 5 | 14 | 6 | 10 | 12 | 12 | 12 | 12 | 15 |  |  |
| BMC_I2C5_D_PEB_DEVICE_SCL | I2C78-DIFF1 | PAIR | 5 | 5 | 5 | 10 | 5 | 14 | 6 | 10 | 12 | 12 | 12 | 12 | 15 |  |  |
| BMC_I2C5_D_PEB_DEVICE_SCL | I2C78-DIFF1 | PAIR | 6 | 5 | 5 | 10 | 5 | 14 | 6 | 10 | 12 | 12 | 12 | 12 | 15 |  |  |
| BMC_I2C5_D_PEB_DEVICE_SCL | I2C78-DIFF1 | PAIR | 7 | 5 | 5 | 10 | 5 | 14 | 6 | 10 | 12 | 12 | 12 | 12 | 15 |  |  |
| BMC_I2C5_D_PEB_DEVICE_SCL | I2C78-DIFF1 | PAIR | 8 | 4.75 | 5 | 10 | 5 | 14 | 6 | 9.5 | 12 | 12 | 12 | 12 | 15 |  |  |
| BMC_I2C5_D_PEB_DEVICE_SDA | I2C78-DIFF1 | PAIR | 1 | 4.75 | 5 | 10 | 5 | 14 | 6 | 9.5 | 12 | 12 | 12 | 12 | 15 |  |  |
| BMC_I2C5_D_PEB_DEVICE_SDA | I2C78-DIFF1 | PAIR | 2 | 5 | 5 | 10 | 5 | 14 | 6 | 10 | 12 | 12 | 12 | 12 | 15 |  |  |
| BMC_I2C5_D_PEB_DEVICE_SDA | I2C78-DIFF1 | PAIR | 3 | 5 | 5 | 10 | 5 | 14 | 6 | 10 | 12 | 12 | 12 | 12 | 15 |  |  |
| BMC_I2C5_D_PEB_DEVICE_SDA | I2C78-DIFF1 | PAIR | 4 | 5 | 5 | 10 | 5 | 14 | 6 | 10 | 12 | 12 | 12 | 12 | 15 |  |  |
| BMC_I2C5_D_PEB_DEVICE_SDA | I2C78-DIFF1 | PAIR | 5 | 5 | 5 | 10 | 5 | 14 | 6 | 10 | 12 | 12 | 12 | 12 | 15 |  |  |
| BMC_I2C5_D_PEB_DEVICE_SDA | I2C78-DIFF1 | PAIR | 6 | 5 | 5 | 10 | 5 | 14 | 6 | 10 | 12 | 12 | 12 | 12 | 15 |  |  |
| BMC_I2C5_D_PEB_DEVICE_SDA | I2C78-DIFF1 | PAIR | 7 | 5 | 5 | 10 | 5 | 14 | 6 | 10 | 12 | 12 | 12 | 12 | 15 |  |  |
| BMC_I2C5_D_PEB_DEVICE_SDA | I2C78-DIFF1 | PAIR | 8 | 4.75 | 5 | 10 | 5 | 14 | 6 | 9.5 | 12 | 12 | 12 | 12 | 15 |  |  |
| BUF_I2C5_SCL_R | I2C79-DIFF1 | PAIR | 1 | 4.75 | 5 | 10 | 5 | 14 | 6 | 9.5 | 12 | 12 | 12 | 12 | 15 |  |  |
| BUF_I2C5_SCL_R | I2C79-DIFF1 | PAIR | 2 | 5 | 5 | 10 | 5 | 14 | 6 | 10 | 12 | 12 | 12 | 12 | 15 |  |  |
| BUF_I2C5_SCL_R | I2C79-DIFF1 | PAIR | 3 | 5 | 5 | 10 | 5 | 14 | 6 | 10 | 12 | 12 | 12 | 12 | 15 |  |  |
| BUF_I2C5_SCL_R | I2C79-DIFF1 | PAIR | 4 | 5 | 5 | 10 | 5 | 14 | 6 | 10 | 12 | 12 | 12 | 12 | 15 |  |  |
| BUF_I2C5_SCL_R | I2C79-DIFF1 | PAIR | 5 | 5 | 5 | 10 | 5 | 14 | 6 | 10 | 12 | 12 | 12 | 12 | 15 |  |  |
| BUF_I2C5_SCL_R | I2C79-DIFF1 | PAIR | 6 | 5 | 5 | 10 | 5 | 14 | 6 | 10 | 12 | 12 | 12 | 12 | 15 |  |  |
| BUF_I2C5_SCL_R | I2C79-DIFF1 | PAIR | 7 | 5 | 5 | 10 | 5 | 14 | 6 | 10 | 12 | 12 | 12 | 12 | 15 |  |  |
| BUF_I2C5_SCL_R | I2C79-DIFF1 | PAIR | 8 | 4.75 | 5 | 10 | 5 | 14 | 6 | 9.5 | 12 | 12 | 12 | 12 | 15 |  |  |
| BUF_I2C5_SDA_R | I2C79-DIFF1 | PAIR | 1 | 4.75 | 5 | 10 | 5 | 14 | 6 | 9.5 | 12 | 12 | 12 | 12 | 15 |  |  |
| BUF_I2C5_SDA_R | I2C79-DIFF1 | PAIR | 2 | 5 | 5 | 10 | 5 | 14 | 6 | 10 | 12 | 12 | 12 | 12 | 15 |  |  |
| BUF_I2C5_SDA_R | I2C79-DIFF1 | PAIR | 3 | 5 | 5 | 10 | 5 | 14 | 6 | 10 | 12 | 12 | 12 | 12 | 15 |  |  |
| BUF_I2C5_SDA_R | I2C79-DIFF1 | PAIR | 4 | 5 | 5 | 10 | 5 | 14 | 6 | 10 | 12 | 12 | 12 | 12 | 15 |  |  |
| BUF_I2C5_SDA_R | I2C79-DIFF1 | PAIR | 5 | 5 | 5 | 10 | 5 | 14 | 6 | 10 | 12 | 12 | 12 | 12 | 15 |  |  |
| BUF_I2C5_SDA_R | I2C79-DIFF1 | PAIR | 6 | 5 | 5 | 10 | 5 | 14 | 6 | 10 | 12 | 12 | 12 | 12 | 15 |  |  |
| BUF_I2C5_SDA_R | I2C79-DIFF1 | PAIR | 7 | 5 | 5 | 10 | 5 | 14 | 6 | 10 | 12 | 12 | 12 | 12 | 15 |  |  |
| BUF_I2C5_SDA_R | I2C79-DIFF1 | PAIR | 8 | 4.75 | 5 | 10 | 5 | 14 | 6 | 9.5 | 12 | 12 | 12 | 12 | 15 |  |  |
| BMC_I2C5_SCL_R | I2C80-DIFF1 | PAIR | 1 | 4.75 | 5 | 10 | 5 | 14 | 6 | 9.5 | 12 | 12 | 12 | 12 | 15 |  |  |
| BMC_I2C5_SCL_R | I2C80-DIFF1 | PAIR | 2 | 5 | 5 | 10 | 5 | 14 | 6 | 10 | 12 | 12 | 12 | 12 | 15 |  |  |
| BMC_I2C5_SCL_R | I2C80-DIFF1 | PAIR | 3 | 5 | 5 | 10 | 5 | 14 | 6 | 10 | 12 | 12 | 12 | 12 | 15 |  |  |
| BMC_I2C5_SCL_R | I2C80-DIFF1 | PAIR | 4 | 5 | 5 | 10 | 5 | 14 | 6 | 10 | 12 | 12 | 12 | 12 | 15 |  |  |
| BMC_I2C5_SCL_R | I2C80-DIFF1 | PAIR | 5 | 5 | 5 | 10 | 5 | 14 | 6 | 10 | 12 | 12 | 12 | 12 | 15 |  |  |
| BMC_I2C5_SCL_R | I2C80-DIFF1 | PAIR | 6 | 5 | 5 | 10 | 5 | 14 | 6 | 10 | 12 | 12 | 12 | 12 | 15 |  |  |
| BMC_I2C5_SCL_R | I2C80-DIFF1 | PAIR | 7 | 5 | 5 | 10 | 5 | 14 | 6 | 10 | 12 | 12 | 12 | 12 | 15 |  |  |
| BMC_I2C5_SCL_R | I2C80-DIFF1 | PAIR | 8 | 4.75 | 5 | 10 | 5 | 14 | 6 | 9.5 | 12 | 12 | 12 | 12 | 15 |  |  |
| BMC_I2C5_SDA_R | I2C80-DIFF1 | PAIR | 1 | 4.75 | 5 | 10 | 5 | 14 | 6 | 9.5 | 12 | 12 | 12 | 12 | 15 |  |  |
| BMC_I2C5_SDA_R | I2C80-DIFF1 | PAIR | 2 | 5 | 5 | 10 | 5 | 14 | 6 | 10 | 12 | 12 | 12 | 12 | 15 |  |  |
| BMC_I2C5_SDA_R | I2C80-DIFF1 | PAIR | 3 | 5 | 5 | 10 | 5 | 14 | 6 | 10 | 12 | 12 | 12 | 12 | 15 |  |  |
| BMC_I2C5_SDA_R | I2C80-DIFF1 | PAIR | 4 | 5 | 5 | 10 | 5 | 14 | 6 | 10 | 12 | 12 | 12 | 12 | 15 |  |  |
| BMC_I2C5_SDA_R | I2C80-DIFF1 | PAIR | 5 | 5 | 5 | 10 | 5 | 14 | 6 | 10 | 12 | 12 | 12 | 12 | 15 |  |  |
| BMC_I2C5_SDA_R | I2C80-DIFF1 | PAIR | 6 | 5 | 5 | 10 | 5 | 14 | 6 | 10 | 12 | 12 | 12 | 12 | 15 |  |  |
| BMC_I2C5_SDA_R | I2C80-DIFF1 | PAIR | 7 | 5 | 5 | 10 | 5 | 14 | 6 | 10 | 12 | 12 | 12 | 12 | 15 |  |  |
| BMC_I2C5_SDA_R | I2C80-DIFF1 | PAIR | 8 | 4.75 | 5 | 10 | 5 | 14 | 6 | 9.5 | 12 | 12 | 12 | 12 | 15 |  |  |
| BMC_I2C1_MINI1_SCL_S | I2C81-DIFF1 | PAIR | 1 | 4.75 | 5 | 10 | 5 | 14 | 6 | 9.5 | 12 | 12 | 12 | 12 | 15 |  |  |
| BMC_I2C1_MINI1_SCL_S | I2C81-DIFF1 | PAIR | 2 | 5 | 5 | 10 | 5 | 14 | 6 | 10 | 12 | 12 | 12 | 12 | 15 |  |  |
| BMC_I2C1_MINI1_SCL_S | I2C81-DIFF1 | PAIR | 3 | 5 | 5 | 10 | 5 | 14 | 6 | 10 | 12 | 12 | 12 | 12 | 15 |  |  |
| BMC_I2C1_MINI1_SCL_S | I2C81-DIFF1 | PAIR | 4 | 5 | 5 | 10 | 5 | 14 | 6 | 10 | 12 | 12 | 12 | 12 | 15 |  |  |
| BMC_I2C1_MINI1_SCL_S | I2C81-DIFF1 | PAIR | 5 | 5 | 5 | 10 | 5 | 14 | 6 | 10 | 12 | 12 | 12 | 12 | 15 |  |  |
| BMC_I2C1_MINI1_SCL_S | I2C81-DIFF1 | PAIR | 6 | 5 | 5 | 10 | 5 | 14 | 6 | 10 | 12 | 12 | 12 | 12 | 15 |  |  |
| BMC_I2C1_MINI1_SCL_S | I2C81-DIFF1 | PAIR | 7 | 5 | 5 | 10 | 5 | 14 | 6 | 10 | 12 | 12 | 12 | 12 | 15 |  |  |
| BMC_I2C1_MINI1_SCL_S | I2C81-DIFF1 | PAIR | 8 | 4.75 | 5 | 10 | 5 | 14 | 6 | 9.5 | 12 | 12 | 12 | 12 | 15 |  |  |
| BMC_I2C1_MINI1_SDA_S | I2C81-DIFF1 | PAIR | 1 | 4.75 | 5 | 10 | 5 | 14 | 6 | 9.5 | 12 | 12 | 12 | 12 | 15 |  |  |
| BMC_I2C1_MINI1_SDA_S | I2C81-DIFF1 | PAIR | 2 | 5 | 5 | 10 | 5 | 14 | 6 | 10 | 12 | 12 | 12 | 12 | 15 |  |  |
| BMC_I2C1_MINI1_SDA_S | I2C81-DIFF1 | PAIR | 3 | 5 | 5 | 10 | 5 | 14 | 6 | 10 | 12 | 12 | 12 | 12 | 15 |  |  |
| BMC_I2C1_MINI1_SDA_S | I2C81-DIFF1 | PAIR | 4 | 5 | 5 | 10 | 5 | 14 | 6 | 10 | 12 | 12 | 12 | 12 | 15 |  |  |
| BMC_I2C1_MINI1_SDA_S | I2C81-DIFF1 | PAIR | 5 | 5 | 5 | 10 | 5 | 14 | 6 | 10 | 12 | 12 | 12 | 12 | 15 |  |  |
| BMC_I2C1_MINI1_SDA_S | I2C81-DIFF1 | PAIR | 6 | 5 | 5 | 10 | 5 | 14 | 6 | 10 | 12 | 12 | 12 | 12 | 15 |  |  |
| BMC_I2C1_MINI1_SDA_S | I2C81-DIFF1 | PAIR | 7 | 5 | 5 | 10 | 5 | 14 | 6 | 10 | 12 | 12 | 12 | 12 | 15 |  |  |
| BMC_I2C1_MINI1_SDA_S | I2C81-DIFF1 | PAIR | 8 | 4.75 | 5 | 10 | 5 | 14 | 6 | 9.5 | 12 | 12 | 12 | 12 | 15 |  |  |
| BMC_I2C2_MINI2_SCL_S | I2C82-DIFF1 | PAIR | 1 | 4.75 | 5 | 10 | 5 | 14 | 6 | 9.5 | 12 | 12 | 12 | 12 | 15 |  |  |
| BMC_I2C2_MINI2_SCL_S | I2C82-DIFF1 | PAIR | 2 | 5 | 5 | 10 | 5 | 14 | 6 | 10 | 12 | 12 | 12 | 12 | 15 |  |  |
| BMC_I2C2_MINI2_SCL_S | I2C82-DIFF1 | PAIR | 3 | 5 | 5 | 10 | 5 | 14 | 6 | 10 | 12 | 12 | 12 | 12 | 15 |  |  |
| BMC_I2C2_MINI2_SCL_S | I2C82-DIFF1 | PAIR | 4 | 5 | 5 | 10 | 5 | 14 | 6 | 10 | 12 | 12 | 12 | 12 | 15 |  |  |
| BMC_I2C2_MINI2_SCL_S | I2C82-DIFF1 | PAIR | 5 | 5 | 5 | 10 | 5 | 14 | 6 | 10 | 12 | 12 | 12 | 12 | 15 |  |  |
| BMC_I2C2_MINI2_SCL_S | I2C82-DIFF1 | PAIR | 6 | 5 | 5 | 10 | 5 | 14 | 6 | 10 | 12 | 12 | 12 | 12 | 15 |  |  |
| BMC_I2C2_MINI2_SCL_S | I2C82-DIFF1 | PAIR | 7 | 5 | 5 | 10 | 5 | 14 | 6 | 10 | 12 | 12 | 12 | 12 | 15 |  |  |
| BMC_I2C2_MINI2_SCL_S | I2C82-DIFF1 | PAIR | 8 | 4.75 | 5 | 10 | 5 | 14 | 6 | 9.5 | 12 | 12 | 12 | 12 | 15 |  |  |
| BMC_I2C2_MINI2_SDA_S | I2C82-DIFF1 | PAIR | 1 | 4.75 | 5 | 10 | 5 | 14 | 6 | 9.5 | 12 | 12 | 12 | 12 | 15 |  |  |
| BMC_I2C2_MINI2_SDA_S | I2C82-DIFF1 | PAIR | 2 | 5 | 5 | 10 | 5 | 14 | 6 | 10 | 12 | 12 | 12 | 12 | 15 |  |  |
| BMC_I2C2_MINI2_SDA_S | I2C82-DIFF1 | PAIR | 3 | 5 | 5 | 10 | 5 | 14 | 6 | 10 | 12 | 12 | 12 | 12 | 15 |  |  |
| BMC_I2C2_MINI2_SDA_S | I2C82-DIFF1 | PAIR | 4 | 5 | 5 | 10 | 5 | 14 | 6 | 10 | 12 | 12 | 12 | 12 | 15 |  |  |
| BMC_I2C2_MINI2_SDA_S | I2C82-DIFF1 | PAIR | 5 | 5 | 5 | 10 | 5 | 14 | 6 | 10 | 12 | 12 | 12 | 12 | 15 |  |  |
| BMC_I2C2_MINI2_SDA_S | I2C82-DIFF1 | PAIR | 6 | 5 | 5 | 10 | 5 | 14 | 6 | 10 | 12 | 12 | 12 | 12 | 15 |  |  |
| BMC_I2C2_MINI2_SDA_S | I2C82-DIFF1 | PAIR | 7 | 5 | 5 | 10 | 5 | 14 | 6 | 10 | 12 | 12 | 12 | 12 | 15 |  |  |
| BMC_I2C2_MINI2_SDA_S | I2C82-DIFF1 | PAIR | 8 | 4.75 | 5 | 10 | 5 | 14 | 6 | 9.5 | 12 | 12 | 12 | 12 | 15 |  |  |
| BMC_I2C3_MINI3_SCL_S | I2C83-DIFF1 | PAIR | 1 | 4.75 | 5 | 10 | 5 | 14 | 6 | 9.5 | 12 | 12 | 12 | 12 | 15 |  |  |
| BMC_I2C3_MINI3_SCL_S | I2C83-DIFF1 | PAIR | 2 | 5 | 5 | 10 | 5 | 14 | 6 | 10 | 12 | 12 | 12 | 12 | 15 |  |  |
| BMC_I2C3_MINI3_SCL_S | I2C83-DIFF1 | PAIR | 3 | 5 | 5 | 10 | 5 | 14 | 6 | 10 | 12 | 12 | 12 | 12 | 15 |  |  |
| BMC_I2C3_MINI3_SCL_S | I2C83-DIFF1 | PAIR | 4 | 5 | 5 | 10 | 5 | 14 | 6 | 10 | 12 | 12 | 12 | 12 | 15 |  |  |
| BMC_I2C3_MINI3_SCL_S | I2C83-DIFF1 | PAIR | 5 | 5 | 5 | 10 | 5 | 14 | 6 | 10 | 12 | 12 | 12 | 12 | 15 |  |  |
| BMC_I2C3_MINI3_SCL_S | I2C83-DIFF1 | PAIR | 6 | 5 | 5 | 10 | 5 | 14 | 6 | 10 | 12 | 12 | 12 | 12 | 15 |  |  |
| BMC_I2C3_MINI3_SCL_S | I2C83-DIFF1 | PAIR | 7 | 5 | 5 | 10 | 5 | 14 | 6 | 10 | 12 | 12 | 12 | 12 | 15 |  |  |
| BMC_I2C3_MINI3_SCL_S | I2C83-DIFF1 | PAIR | 8 | 4.75 | 5 | 10 | 5 | 14 | 6 | 9.5 | 12 | 12 | 12 | 12 | 15 |  |  |
| BMC_I2C3_MINI3_SDA_S | I2C83-DIFF1 | PAIR | 1 | 4.75 | 5 | 10 | 5 | 14 | 6 | 9.5 | 12 | 12 | 12 | 12 | 15 |  |  |
| BMC_I2C3_MINI3_SDA_S | I2C83-DIFF1 | PAIR | 2 | 5 | 5 | 10 | 5 | 14 | 6 | 10 | 12 | 12 | 12 | 12 | 15 |  |  |
| BMC_I2C3_MINI3_SDA_S | I2C83-DIFF1 | PAIR | 3 | 5 | 5 | 10 | 5 | 14 | 6 | 10 | 12 | 12 | 12 | 12 | 15 |  |  |
| BMC_I2C3_MINI3_SDA_S | I2C83-DIFF1 | PAIR | 4 | 5 | 5 | 10 | 5 | 14 | 6 | 10 | 12 | 12 | 12 | 12 | 15 |  |  |
| BMC_I2C3_MINI3_SDA_S | I2C83-DIFF1 | PAIR | 5 | 5 | 5 | 10 | 5 | 14 | 6 | 10 | 12 | 12 | 12 | 12 | 15 |  |  |
| BMC_I2C3_MINI3_SDA_S | I2C83-DIFF1 | PAIR | 6 | 5 | 5 | 10 | 5 | 14 | 6 | 10 | 12 | 12 | 12 | 12 | 15 |  |  |
| BMC_I2C3_MINI3_SDA_S | I2C83-DIFF1 | PAIR | 7 | 5 | 5 | 10 | 5 | 14 | 6 | 10 | 12 | 12 | 12 | 12 | 15 |  |  |
| BMC_I2C3_MINI3_SDA_S | I2C83-DIFF1 | PAIR | 8 | 4.75 | 5 | 10 | 5 | 14 | 6 | 9.5 | 12 | 12 | 12 | 12 | 15 |  |  |
| BMC_I2C4_MINI4_SCL_S | I2C84-DIFF1 | PAIR | 1 | 4.75 | 5 | 10 | 5 | 14 | 6 | 9.5 | 12 | 12 | 12 | 12 | 15 |  |  |
| BMC_I2C4_MINI4_SCL_S | I2C84-DIFF1 | PAIR | 2 | 5 | 5 | 10 | 5 | 14 | 6 | 10 | 12 | 12 | 12 | 12 | 15 |  |  |
| BMC_I2C4_MINI4_SCL_S | I2C84-DIFF1 | PAIR | 3 | 5 | 5 | 10 | 5 | 14 | 6 | 10 | 12 | 12 | 12 | 12 | 15 |  |  |
| BMC_I2C4_MINI4_SCL_S | I2C84-DIFF1 | PAIR | 4 | 5 | 5 | 10 | 5 | 14 | 6 | 10 | 12 | 12 | 12 | 12 | 15 |  |  |
| BMC_I2C4_MINI4_SCL_S | I2C84-DIFF1 | PAIR | 5 | 5 | 5 | 10 | 5 | 14 | 6 | 10 | 12 | 12 | 12 | 12 | 15 |  |  |
| BMC_I2C4_MINI4_SCL_S | I2C84-DIFF1 | PAIR | 6 | 5 | 5 | 10 | 5 | 14 | 6 | 10 | 12 | 12 | 12 | 12 | 15 |  |  |
| BMC_I2C4_MINI4_SCL_S | I2C84-DIFF1 | PAIR | 7 | 5 | 5 | 10 | 5 | 14 | 6 | 10 | 12 | 12 | 12 | 12 | 15 |  |  |
| BMC_I2C4_MINI4_SCL_S | I2C84-DIFF1 | PAIR | 8 | 4.75 | 5 | 10 | 5 | 14 | 6 | 9.5 | 12 | 12 | 12 | 12 | 15 |  |  |
| BMC_I2C4_MINI4_SDA_S | I2C84-DIFF1 | PAIR | 1 | 4.75 | 5 | 10 | 5 | 14 | 6 | 9.5 | 12 | 12 | 12 | 12 | 15 |  |  |
| BMC_I2C4_MINI4_SDA_S | I2C84-DIFF1 | PAIR | 2 | 5 | 5 | 10 | 5 | 14 | 6 | 10 | 12 | 12 | 12 | 12 | 15 |  |  |
| BMC_I2C4_MINI4_SDA_S | I2C84-DIFF1 | PAIR | 3 | 5 | 5 | 10 | 5 | 14 | 6 | 10 | 12 | 12 | 12 | 12 | 15 |  |  |
| BMC_I2C4_MINI4_SDA_S | I2C84-DIFF1 | PAIR | 4 | 5 | 5 | 10 | 5 | 14 | 6 | 10 | 12 | 12 | 12 | 12 | 15 |  |  |
| BMC_I2C4_MINI4_SDA_S | I2C84-DIFF1 | PAIR | 5 | 5 | 5 | 10 | 5 | 14 | 6 | 10 | 12 | 12 | 12 | 12 | 15 |  |  |
| BMC_I2C4_MINI4_SDA_S | I2C84-DIFF1 | PAIR | 6 | 5 | 5 | 10 | 5 | 14 | 6 | 10 | 12 | 12 | 12 | 12 | 15 |  |  |
| BMC_I2C4_MINI4_SDA_S | I2C84-DIFF1 | PAIR | 7 | 5 | 5 | 10 | 5 | 14 | 6 | 10 | 12 | 12 | 12 | 12 | 15 |  |  |
| BMC_I2C4_MINI4_SDA_S | I2C84-DIFF1 | PAIR | 8 | 4.75 | 5 | 10 | 5 | 14 | 6 | 9.5 | 12 | 12 | 12 | 12 | 15 |  |  |
| BMC_I2C11_MINI5_SCL_S | I2C85-DIFF1 | PAIR | 1 | 4.75 | 5 | 10 | 5 | 14 | 6 | 9.5 | 12 | 12 | 12 | 12 | 15 |  |  |
| BMC_I2C11_MINI5_SCL_S | I2C85-DIFF1 | PAIR | 2 | 5 | 5 | 10 | 5 | 14 | 6 | 10 | 12 | 12 | 12 | 12 | 15 |  |  |
| BMC_I2C11_MINI5_SCL_S | I2C85-DIFF1 | PAIR | 3 | 5 | 5 | 10 | 5 | 14 | 6 | 10 | 12 | 12 | 12 | 12 | 15 |  |  |
| BMC_I2C11_MINI5_SCL_S | I2C85-DIFF1 | PAIR | 4 | 5 | 5 | 10 | 5 | 14 | 6 | 10 | 12 | 12 | 12 | 12 | 15 |  |  |
| BMC_I2C11_MINI5_SCL_S | I2C85-DIFF1 | PAIR | 5 | 5 | 5 | 10 | 5 | 14 | 6 | 10 | 12 | 12 | 12 | 12 | 15 |  |  |
| BMC_I2C11_MINI5_SCL_S | I2C85-DIFF1 | PAIR | 6 | 5 | 5 | 10 | 5 | 14 | 6 | 10 | 12 | 12 | 12 | 12 | 15 |  |  |
| BMC_I2C11_MINI5_SCL_S | I2C85-DIFF1 | PAIR | 7 | 5 | 5 | 10 | 5 | 14 | 6 | 10 | 12 | 12 | 12 | 12 | 15 |  |  |
| BMC_I2C11_MINI5_SCL_S | I2C85-DIFF1 | PAIR | 8 | 4.75 | 5 | 10 | 5 | 14 | 6 | 9.5 | 12 | 12 | 12 | 12 | 15 |  |  |
| BMC_I2C11_MINI5_SDA_S | I2C85-DIFF1 | PAIR | 1 | 4.75 | 5 | 10 | 5 | 14 | 6 | 9.5 | 12 | 12 | 12 | 12 | 15 |  |  |
| BMC_I2C11_MINI5_SDA_S | I2C85-DIFF1 | PAIR | 2 | 5 | 5 | 10 | 5 | 14 | 6 | 10 | 12 | 12 | 12 | 12 | 15 |  |  |
| BMC_I2C11_MINI5_SDA_S | I2C85-DIFF1 | PAIR | 3 | 5 | 5 | 10 | 5 | 14 | 6 | 10 | 12 | 12 | 12 | 12 | 15 |  |  |
| BMC_I2C11_MINI5_SDA_S | I2C85-DIFF1 | PAIR | 4 | 5 | 5 | 10 | 5 | 14 | 6 | 10 | 12 | 12 | 12 | 12 | 15 |  |  |
| BMC_I2C11_MINI5_SDA_S | I2C85-DIFF1 | PAIR | 5 | 5 | 5 | 10 | 5 | 14 | 6 | 10 | 12 | 12 | 12 | 12 | 15 |  |  |
| BMC_I2C11_MINI5_SDA_S | I2C85-DIFF1 | PAIR | 6 | 5 | 5 | 10 | 5 | 14 | 6 | 10 | 12 | 12 | 12 | 12 | 15 |  |  |
| BMC_I2C11_MINI5_SDA_S | I2C85-DIFF1 | PAIR | 7 | 5 | 5 | 10 | 5 | 14 | 6 | 10 | 12 | 12 | 12 | 12 | 15 |  |  |
| BMC_I2C11_MINI5_SDA_S | I2C85-DIFF1 | PAIR | 8 | 4.75 | 5 | 10 | 5 | 14 | 6 | 9.5 | 12 | 12 | 12 | 12 | 15 |  |  |
| BMC_I2C12_MINI6_SCL_S | I2C86-DIFF1 | PAIR | 1 | 4.75 | 5 | 10 | 5 | 14 | 6 | 9.5 | 12 | 12 | 12 | 12 | 15 |  |  |
| BMC_I2C12_MINI6_SCL_S | I2C86-DIFF1 | PAIR | 2 | 5 | 5 | 10 | 5 | 14 | 6 | 10 | 12 | 12 | 12 | 12 | 15 |  |  |
| BMC_I2C12_MINI6_SCL_S | I2C86-DIFF1 | PAIR | 3 | 5 | 5 | 10 | 5 | 14 | 6 | 10 | 12 | 12 | 12 | 12 | 15 |  |  |
| BMC_I2C12_MINI6_SCL_S | I2C86-DIFF1 | PAIR | 4 | 5 | 5 | 10 | 5 | 14 | 6 | 10 | 12 | 12 | 12 | 12 | 15 |  |  |
| BMC_I2C12_MINI6_SCL_S | I2C86-DIFF1 | PAIR | 5 | 5 | 5 | 10 | 5 | 14 | 6 | 10 | 12 | 12 | 12 | 12 | 15 |  |  |
| BMC_I2C12_MINI6_SCL_S | I2C86-DIFF1 | PAIR | 6 | 5 | 5 | 10 | 5 | 14 | 6 | 10 | 12 | 12 | 12 | 12 | 15 |  |  |
| BMC_I2C12_MINI6_SCL_S | I2C86-DIFF1 | PAIR | 7 | 5 | 5 | 10 | 5 | 14 | 6 | 10 | 12 | 12 | 12 | 12 | 15 |  |  |
| BMC_I2C12_MINI6_SCL_S | I2C86-DIFF1 | PAIR | 8 | 4.75 | 5 | 10 | 5 | 14 | 6 | 9.5 | 12 | 12 | 12 | 12 | 15 |  |  |
| BMC_I2C12_MINI6_SDA_S | I2C86-DIFF1 | PAIR | 1 | 4.75 | 5 | 10 | 5 | 14 | 6 | 9.5 | 12 | 12 | 12 | 12 | 15 |  |  |
| BMC_I2C12_MINI6_SDA_S | I2C86-DIFF1 | PAIR | 2 | 5 | 5 | 10 | 5 | 14 | 6 | 10 | 12 | 12 | 12 | 12 | 15 |  |  |
| BMC_I2C12_MINI6_SDA_S | I2C86-DIFF1 | PAIR | 3 | 5 | 5 | 10 | 5 | 14 | 6 | 10 | 12 | 12 | 12 | 12 | 15 |  |  |
| BMC_I2C12_MINI6_SDA_S | I2C86-DIFF1 | PAIR | 4 | 5 | 5 | 10 | 5 | 14 | 6 | 10 | 12 | 12 | 12 | 12 | 15 |  |  |
| BMC_I2C12_MINI6_SDA_S | I2C86-DIFF1 | PAIR | 5 | 5 | 5 | 10 | 5 | 14 | 6 | 10 | 12 | 12 | 12 | 12 | 15 |  |  |
| BMC_I2C12_MINI6_SDA_S | I2C86-DIFF1 | PAIR | 6 | 5 | 5 | 10 | 5 | 14 | 6 | 10 | 12 | 12 | 12 | 12 | 15 |  |  |
| BMC_I2C12_MINI6_SDA_S | I2C86-DIFF1 | PAIR | 7 | 5 | 5 | 10 | 5 | 14 | 6 | 10 | 12 | 12 | 12 | 12 | 15 |  |  |
| BMC_I2C12_MINI6_SDA_S | I2C86-DIFF1 | PAIR | 8 | 4.75 | 5 | 10 | 5 | 14 | 6 | 9.5 | 12 | 12 | 12 | 12 | 15 |  |  |
| BMC_I2C13_MINI7_SCL_S | I2C87-DIFF1 | PAIR | 1 | 4.75 | 5 | 10 | 5 | 14 | 6 | 9.5 | 12 | 12 | 12 | 12 | 15 |  |  |
| BMC_I2C13_MINI7_SCL_S | I2C87-DIFF1 | PAIR | 2 | 5 | 5 | 10 | 5 | 14 | 6 | 10 | 12 | 12 | 12 | 12 | 15 |  |  |
| BMC_I2C13_MINI7_SCL_S | I2C87-DIFF1 | PAIR | 3 | 5 | 5 | 10 | 5 | 14 | 6 | 10 | 12 | 12 | 12 | 12 | 15 |  |  |
| BMC_I2C13_MINI7_SCL_S | I2C87-DIFF1 | PAIR | 4 | 5 | 5 | 10 | 5 | 14 | 6 | 10 | 12 | 12 | 12 | 12 | 15 |  |  |
| BMC_I2C13_MINI7_SCL_S | I2C87-DIFF1 | PAIR | 5 | 5 | 5 | 10 | 5 | 14 | 6 | 10 | 12 | 12 | 12 | 12 | 15 |  |  |
| BMC_I2C13_MINI7_SCL_S | I2C87-DIFF1 | PAIR | 6 | 5 | 5 | 10 | 5 | 14 | 6 | 10 | 12 | 12 | 12 | 12 | 15 |  |  |
| BMC_I2C13_MINI7_SCL_S | I2C87-DIFF1 | PAIR | 7 | 5 | 5 | 10 | 5 | 14 | 6 | 10 | 12 | 12 | 12 | 12 | 15 |  |  |
| BMC_I2C13_MINI7_SCL_S | I2C87-DIFF1 | PAIR | 8 | 4.75 | 5 | 10 | 5 | 14 | 6 | 9.5 | 12 | 12 | 12 | 12 | 15 |  |  |
| BMC_I2C13_MINI7_SDA_S | I2C87-DIFF1 | PAIR | 1 | 4.75 | 5 | 10 | 5 | 14 | 6 | 9.5 | 12 | 12 | 12 | 12 | 15 |  |  |
| BMC_I2C13_MINI7_SDA_S | I2C87-DIFF1 | PAIR | 2 | 5 | 5 | 10 | 5 | 14 | 6 | 10 | 12 | 12 | 12 | 12 | 15 |  |  |
| BMC_I2C13_MINI7_SDA_S | I2C87-DIFF1 | PAIR | 3 | 5 | 5 | 10 | 5 | 14 | 6 | 10 | 12 | 12 | 12 | 12 | 15 |  |  |
| BMC_I2C13_MINI7_SDA_S | I2C87-DIFF1 | PAIR | 4 | 5 | 5 | 10 | 5 | 14 | 6 | 10 | 12 | 12 | 12 | 12 | 15 |  |  |
| BMC_I2C13_MINI7_SDA_S | I2C87-DIFF1 | PAIR | 5 | 5 | 5 | 10 | 5 | 14 | 6 | 10 | 12 | 12 | 12 | 12 | 15 |  |  |
| BMC_I2C13_MINI7_SDA_S | I2C87-DIFF1 | PAIR | 6 | 5 | 5 | 10 | 5 | 14 | 6 | 10 | 12 | 12 | 12 | 12 | 15 |  |  |
| BMC_I2C13_MINI7_SDA_S | I2C87-DIFF1 | PAIR | 7 | 5 | 5 | 10 | 5 | 14 | 6 | 10 | 12 | 12 | 12 | 12 | 15 |  |  |
| BMC_I2C13_MINI7_SDA_S | I2C87-DIFF1 | PAIR | 8 | 4.75 | 5 | 10 | 5 | 14 | 6 | 9.5 | 12 | 12 | 12 | 12 | 15 |  |  |
| BMC_I2C14_MINI8_SCL_S | I2C88-DIFF1 | PAIR | 1 | 4.75 | 5 | 10 | 5 | 14 | 6 | 9.5 | 12 | 12 | 12 | 12 | 15 |  |  |
| BMC_I2C14_MINI8_SCL_S | I2C88-DIFF1 | PAIR | 2 | 5 | 5 | 10 | 5 | 14 | 6 | 10 | 12 | 12 | 12 | 12 | 15 |  |  |
| BMC_I2C14_MINI8_SCL_S | I2C88-DIFF1 | PAIR | 3 | 5 | 5 | 10 | 5 | 14 | 6 | 10 | 12 | 12 | 12 | 12 | 15 |  |  |
| BMC_I2C14_MINI8_SCL_S | I2C88-DIFF1 | PAIR | 4 | 5 | 5 | 10 | 5 | 14 | 6 | 10 | 12 | 12 | 12 | 12 | 15 |  |  |
| BMC_I2C14_MINI8_SCL_S | I2C88-DIFF1 | PAIR | 5 | 5 | 5 | 10 | 5 | 14 | 6 | 10 | 12 | 12 | 12 | 12 | 15 |  |  |
| BMC_I2C14_MINI8_SCL_S | I2C88-DIFF1 | PAIR | 6 | 5 | 5 | 10 | 5 | 14 | 6 | 10 | 12 | 12 | 12 | 12 | 15 |  |  |
| BMC_I2C14_MINI8_SCL_S | I2C88-DIFF1 | PAIR | 7 | 5 | 5 | 10 | 5 | 14 | 6 | 10 | 12 | 12 | 12 | 12 | 15 |  |  |
| BMC_I2C14_MINI8_SCL_S | I2C88-DIFF1 | PAIR | 8 | 4.75 | 5 | 10 | 5 | 14 | 6 | 9.5 | 12 | 12 | 12 | 12 | 15 |  |  |
| BMC_I2C14_MINI8_SDA_S | I2C88-DIFF1 | PAIR | 1 | 4.75 | 5 | 10 | 5 | 14 | 6 | 9.5 | 12 | 12 | 12 | 12 | 15 |  |  |
| BMC_I2C14_MINI8_SDA_S | I2C88-DIFF1 | PAIR | 2 | 5 | 5 | 10 | 5 | 14 | 6 | 10 | 12 | 12 | 12 | 12 | 15 |  |  |
| BMC_I2C14_MINI8_SDA_S | I2C88-DIFF1 | PAIR | 3 | 5 | 5 | 10 | 5 | 14 | 6 | 10 | 12 | 12 | 12 | 12 | 15 |  |  |
| BMC_I2C14_MINI8_SDA_S | I2C88-DIFF1 | PAIR | 4 | 5 | 5 | 10 | 5 | 14 | 6 | 10 | 12 | 12 | 12 | 12 | 15 |  |  |
| BMC_I2C14_MINI8_SDA_S | I2C88-DIFF1 | PAIR | 5 | 5 | 5 | 10 | 5 | 14 | 6 | 10 | 12 | 12 | 12 | 12 | 15 |  |  |
| BMC_I2C14_MINI8_SDA_S | I2C88-DIFF1 | PAIR | 6 | 5 | 5 | 10 | 5 | 14 | 6 | 10 | 12 | 12 | 12 | 12 | 15 |  |  |
| BMC_I2C14_MINI8_SDA_S | I2C88-DIFF1 | PAIR | 7 | 5 | 5 | 10 | 5 | 14 | 6 | 10 | 12 | 12 | 12 | 12 | 15 |  |  |
| BMC_I2C14_MINI8_SDA_S | I2C88-DIFF1 | PAIR | 8 | 4.75 | 5 | 10 | 5 | 14 | 6 | 9.5 | 12 | 12 | 12 | 12 | 15 |  |  |
| TWI_SCL3 | I2C89-DIFF1 | PAIR | 1 | 4.75 | 5 | 10 | 5 | 14 | 6 | 9.5 | 12 | 12 | 12 | 12 | 15 |  |  |
| TWI_SCL3 | I2C89-DIFF1 | PAIR | 2 | 5 | 5 | 10 | 5 | 14 | 6 | 10 | 12 | 12 | 12 | 12 | 15 |  |  |
| TWI_SCL3 | I2C89-DIFF1 | PAIR | 3 | 5 | 5 | 10 | 5 | 14 | 6 | 10 | 12 | 12 | 12 | 12 | 15 |  |  |
| TWI_SCL3 | I2C89-DIFF1 | PAIR | 4 | 5 | 5 | 10 | 5 | 14 | 6 | 10 | 12 | 12 | 12 | 12 | 15 |  |  |
| TWI_SCL3 | I2C89-DIFF1 | PAIR | 5 | 5 | 5 | 10 | 5 | 14 | 6 | 10 | 12 | 12 | 12 | 12 | 15 |  |  |
| TWI_SCL3 | I2C89-DIFF1 | PAIR | 6 | 5 | 5 | 10 | 5 | 14 | 6 | 10 | 12 | 12 | 12 | 12 | 15 |  |  |
| TWI_SCL3 | I2C89-DIFF1 | PAIR | 7 | 5 | 5 | 10 | 5 | 14 | 6 | 10 | 12 | 12 | 12 | 12 | 15 |  |  |
| TWI_SCL3 | I2C89-DIFF1 | PAIR | 8 | 4.75 | 5 | 10 | 5 | 14 | 6 | 9.5 | 12 | 12 | 12 | 12 | 15 |  |  |
| TWI_SDA3 | I2C89-DIFF1 | PAIR | 1 | 4.75 | 5 | 10 | 5 | 14 | 6 | 9.5 | 12 | 12 | 12 | 12 | 15 |  |  |
| TWI_SDA3 | I2C89-DIFF1 | PAIR | 2 | 5 | 5 | 10 | 5 | 14 | 6 | 10 | 12 | 12 | 12 | 12 | 15 |  |  |
| TWI_SDA3 | I2C89-DIFF1 | PAIR | 3 | 5 | 5 | 10 | 5 | 14 | 6 | 10 | 12 | 12 | 12 | 12 | 15 |  |  |
| TWI_SDA3 | I2C89-DIFF1 | PAIR | 4 | 5 | 5 | 10 | 5 | 14 | 6 | 10 | 12 | 12 | 12 | 12 | 15 |  |  |
| TWI_SDA3 | I2C89-DIFF1 | PAIR | 5 | 5 | 5 | 10 | 5 | 14 | 6 | 10 | 12 | 12 | 12 | 12 | 15 |  |  |
| TWI_SDA3 | I2C89-DIFF1 | PAIR | 6 | 5 | 5 | 10 | 5 | 14 | 6 | 10 | 12 | 12 | 12 | 12 | 15 |  |  |
| TWI_SDA3 | I2C89-DIFF1 | PAIR | 7 | 5 | 5 | 10 | 5 | 14 | 6 | 10 | 12 | 12 | 12 | 12 | 15 |  |  |
| TWI_SDA3 | I2C89-DIFF1 | PAIR | 8 | 4.75 | 5 | 10 | 5 | 14 | 6 | 9.5 | 12 | 12 | 12 | 12 | 15 |  |  |
| TWI_SCL5 | I2C90-DIFF1 | PAIR | 1 | 4.75 | 5 | 10 | 5 | 14 | 6 | 9.5 | 12 | 12 | 12 | 12 | 15 |  |  |
| TWI_SCL5 | I2C90-DIFF1 | PAIR | 2 | 5 | 5 | 10 | 5 | 14 | 6 | 10 | 12 | 12 | 12 | 12 | 15 |  |  |
| TWI_SCL5 | I2C90-DIFF1 | PAIR | 3 | 5 | 5 | 10 | 5 | 14 | 6 | 10 | 12 | 12 | 12 | 12 | 15 |  |  |
| TWI_SCL5 | I2C90-DIFF1 | PAIR | 4 | 5 | 5 | 10 | 5 | 14 | 6 | 10 | 12 | 12 | 12 | 12 | 15 |  |  |
| TWI_SCL5 | I2C90-DIFF1 | PAIR | 5 | 5 | 5 | 10 | 5 | 14 | 6 | 10 | 12 | 12 | 12 | 12 | 15 |  |  |
| TWI_SCL5 | I2C90-DIFF1 | PAIR | 6 | 5 | 5 | 10 | 5 | 14 | 6 | 10 | 12 | 12 | 12 | 12 | 15 |  |  |
| TWI_SCL5 | I2C90-DIFF1 | PAIR | 7 | 5 | 5 | 10 | 5 | 14 | 6 | 10 | 12 | 12 | 12 | 12 | 15 |  |  |
| TWI_SCL5 | I2C90-DIFF1 | PAIR | 8 | 4.75 | 5 | 10 | 5 | 14 | 6 | 9.5 | 12 | 12 | 12 | 12 | 15 |  |  |
| TWI_SDA5 | I2C90-DIFF1 | PAIR | 1 | 4.75 | 5 | 10 | 5 | 14 | 6 | 9.5 | 12 | 12 | 12 | 12 | 15 |  |  |
| TWI_SDA5 | I2C90-DIFF1 | PAIR | 2 | 5 | 5 | 10 | 5 | 14 | 6 | 10 | 12 | 12 | 12 | 12 | 15 |  |  |
| TWI_SDA5 | I2C90-DIFF1 | PAIR | 3 | 5 | 5 | 10 | 5 | 14 | 6 | 10 | 12 | 12 | 12 | 12 | 15 |  |  |
| TWI_SDA5 | I2C90-DIFF1 | PAIR | 4 | 5 | 5 | 10 | 5 | 14 | 6 | 10 | 12 | 12 | 12 | 12 | 15 |  |  |
| TWI_SDA5 | I2C90-DIFF1 | PAIR | 5 | 5 | 5 | 10 | 5 | 14 | 6 | 10 | 12 | 12 | 12 | 12 | 15 |  |  |
| TWI_SDA5 | I2C90-DIFF1 | PAIR | 6 | 5 | 5 | 10 | 5 | 14 | 6 | 10 | 12 | 12 | 12 | 12 | 15 |  |  |
| TWI_SDA5 | I2C90-DIFF1 | PAIR | 7 | 5 | 5 | 10 | 5 | 14 | 6 | 10 | 12 | 12 | 12 | 12 | 15 |  |  |
| TWI_SDA5 | I2C90-DIFF1 | PAIR | 8 | 4.75 | 5 | 10 | 5 | 14 | 6 | 9.5 | 12 | 12 | 12 | 12 | 15 |  |  |
| TWI_SCL6 | I2C91-DIFF1 | PAIR | 1 | 4.75 | 5 | 10 | 5 | 14 | 6 | 9.5 | 12 | 12 | 12 | 12 | 15 |  |  |
| TWI_SCL6 | I2C91-DIFF1 | PAIR | 2 | 5 | 5 | 10 | 5 | 14 | 6 | 10 | 12 | 12 | 12 | 12 | 15 |  |  |
| TWI_SCL6 | I2C91-DIFF1 | PAIR | 3 | 5 | 5 | 10 | 5 | 14 | 6 | 10 | 12 | 12 | 12 | 12 | 15 |  |  |
| TWI_SCL6 | I2C91-DIFF1 | PAIR | 4 | 5 | 5 | 10 | 5 | 14 | 6 | 10 | 12 | 12 | 12 | 12 | 15 |  |  |
| TWI_SCL6 | I2C91-DIFF1 | PAIR | 5 | 5 | 5 | 10 | 5 | 14 | 6 | 10 | 12 | 12 | 12 | 12 | 15 |  |  |
| TWI_SCL6 | I2C91-DIFF1 | PAIR | 6 | 5 | 5 | 10 | 5 | 14 | 6 | 10 | 12 | 12 | 12 | 12 | 15 |  |  |
| TWI_SCL6 | I2C91-DIFF1 | PAIR | 7 | 5 | 5 | 10 | 5 | 14 | 6 | 10 | 12 | 12 | 12 | 12 | 15 |  |  |
| TWI_SCL6 | I2C91-DIFF1 | PAIR | 8 | 4.75 | 5 | 10 | 5 | 14 | 6 | 9.5 | 12 | 12 | 12 | 12 | 15 |  |  |
| TWI_SDA6 | I2C91-DIFF1 | PAIR | 1 | 4.75 | 5 | 10 | 5 | 14 | 6 | 9.5 | 12 | 12 | 12 | 12 | 15 |  |  |
| TWI_SDA6 | I2C91-DIFF1 | PAIR | 2 | 5 | 5 | 10 | 5 | 14 | 6 | 10 | 12 | 12 | 12 | 12 | 15 |  |  |
| TWI_SDA6 | I2C91-DIFF1 | PAIR | 3 | 5 | 5 | 10 | 5 | 14 | 6 | 10 | 12 | 12 | 12 | 12 | 15 |  |  |
| TWI_SDA6 | I2C91-DIFF1 | PAIR | 4 | 5 | 5 | 10 | 5 | 14 | 6 | 10 | 12 | 12 | 12 | 12 | 15 |  |  |
| TWI_SDA6 | I2C91-DIFF1 | PAIR | 5 | 5 | 5 | 10 | 5 | 14 | 6 | 10 | 12 | 12 | 12 | 12 | 15 |  |  |
| TWI_SDA6 | I2C91-DIFF1 | PAIR | 6 | 5 | 5 | 10 | 5 | 14 | 6 | 10 | 12 | 12 | 12 | 12 | 15 |  |  |
| TWI_SDA6 | I2C91-DIFF1 | PAIR | 7 | 5 | 5 | 10 | 5 | 14 | 6 | 10 | 12 | 12 | 12 | 12 | 15 |  |  |
| TWI_SDA6 | I2C91-DIFF1 | PAIR | 8 | 4.75 | 5 | 10 | 5 | 14 | 6 | 9.5 | 12 | 12 | 12 | 12 | 15 |  |  |
| IOEXP_TWI_SCL3 | I2C92-DIFF1 | PAIR | 1 | 4.75 | 5 | 10 | 5 | 14 | 6 | 9.5 | 12 | 12 | 12 | 12 | 15 |  |  |
| IOEXP_TWI_SCL3 | I2C92-DIFF1 | PAIR | 2 | 5 | 5 | 10 | 5 | 14 | 6 | 10 | 12 | 12 | 12 | 12 | 15 |  |  |
| IOEXP_TWI_SCL3 | I2C92-DIFF1 | PAIR | 3 | 5 | 5 | 10 | 5 | 14 | 6 | 10 | 12 | 12 | 12 | 12 | 15 |  |  |
| IOEXP_TWI_SCL3 | I2C92-DIFF1 | PAIR | 4 | 5 | 5 | 10 | 5 | 14 | 6 | 10 | 12 | 12 | 12 | 12 | 15 |  |  |
| IOEXP_TWI_SCL3 | I2C92-DIFF1 | PAIR | 5 | 5 | 5 | 10 | 5 | 14 | 6 | 10 | 12 | 12 | 12 | 12 | 15 |  |  |
| IOEXP_TWI_SCL3 | I2C92-DIFF1 | PAIR | 6 | 5 | 5 | 10 | 5 | 14 | 6 | 10 | 12 | 12 | 12 | 12 | 15 |  |  |
| IOEXP_TWI_SCL3 | I2C92-DIFF1 | PAIR | 7 | 5 | 5 | 10 | 5 | 14 | 6 | 10 | 12 | 12 | 12 | 12 | 15 |  |  |
| IOEXP_TWI_SCL3 | I2C92-DIFF1 | PAIR | 8 | 4.75 | 5 | 10 | 5 | 14 | 6 | 9.5 | 12 | 12 | 12 | 12 | 15 |  |  |
| IOEXP_TWI_SDA3 | I2C92-DIFF1 | PAIR | 1 | 4.75 | 5 | 10 | 5 | 14 | 6 | 9.5 | 12 | 12 | 12 | 12 | 15 |  |  |
| IOEXP_TWI_SDA3 | I2C92-DIFF1 | PAIR | 2 | 5 | 5 | 10 | 5 | 14 | 6 | 10 | 12 | 12 | 12 | 12 | 15 |  |  |
| IOEXP_TWI_SDA3 | I2C92-DIFF1 | PAIR | 3 | 5 | 5 | 10 | 5 | 14 | 6 | 10 | 12 | 12 | 12 | 12 | 15 |  |  |
| IOEXP_TWI_SDA3 | I2C92-DIFF1 | PAIR | 4 | 5 | 5 | 10 | 5 | 14 | 6 | 10 | 12 | 12 | 12 | 12 | 15 |  |  |
| IOEXP_TWI_SDA3 | I2C92-DIFF1 | PAIR | 5 | 5 | 5 | 10 | 5 | 14 | 6 | 10 | 12 | 12 | 12 | 12 | 15 |  |  |
| IOEXP_TWI_SDA3 | I2C92-DIFF1 | PAIR | 6 | 5 | 5 | 10 | 5 | 14 | 6 | 10 | 12 | 12 | 12 | 12 | 15 |  |  |
| IOEXP_TWI_SDA3 | I2C92-DIFF1 | PAIR | 7 | 5 | 5 | 10 | 5 | 14 | 6 | 10 | 12 | 12 | 12 | 12 | 15 |  |  |
| IOEXP_TWI_SDA3 | I2C92-DIFF1 | PAIR | 8 | 4.75 | 5 | 10 | 5 | 14 | 6 | 9.5 | 12 | 12 | 12 | 12 | 15 |  |  |
| I2C_TPM_SCL | I2C93-DIFF1 | PAIR | 1 | 4.75 | 5 | 10 | 5 | 14 | 6 | 9.5 | 12 | 12 | 12 | 12 | 15 |  |  |
| I2C_TPM_SCL | I2C93-DIFF1 | PAIR | 2 | 5 | 5 | 10 | 5 | 14 | 6 | 10 | 12 | 12 | 12 | 12 | 15 |  |  |
| I2C_TPM_SCL | I2C93-DIFF1 | PAIR | 3 | 5 | 5 | 10 | 5 | 14 | 6 | 10 | 12 | 12 | 12 | 12 | 15 |  |  |
| I2C_TPM_SCL | I2C93-DIFF1 | PAIR | 4 | 5 | 5 | 10 | 5 | 14 | 6 | 10 | 12 | 12 | 12 | 12 | 15 |  |  |
| I2C_TPM_SCL | I2C93-DIFF1 | PAIR | 5 | 5 | 5 | 10 | 5 | 14 | 6 | 10 | 12 | 12 | 12 | 12 | 15 |  |  |
| I2C_TPM_SCL | I2C93-DIFF1 | PAIR | 6 | 5 | 5 | 10 | 5 | 14 | 6 | 10 | 12 | 12 | 12 | 12 | 15 |  |  |
| I2C_TPM_SCL | I2C93-DIFF1 | PAIR | 7 | 5 | 5 | 10 | 5 | 14 | 6 | 10 | 12 | 12 | 12 | 12 | 15 |  |  |
| I2C_TPM_SCL | I2C93-DIFF1 | PAIR | 8 | 4.75 | 5 | 10 | 5 | 14 | 6 | 9.5 | 12 | 12 | 12 | 12 | 15 |  |  |
| I2C_TPM_SDA | I2C93-DIFF1 | PAIR | 1 | 4.75 | 5 | 10 | 5 | 14 | 6 | 9.5 | 12 | 12 | 12 | 12 | 15 |  |  |
| I2C_TPM_SDA | I2C93-DIFF1 | PAIR | 2 | 5 | 5 | 10 | 5 | 14 | 6 | 10 | 12 | 12 | 12 | 12 | 15 |  |  |
| I2C_TPM_SDA | I2C93-DIFF1 | PAIR | 3 | 5 | 5 | 10 | 5 | 14 | 6 | 10 | 12 | 12 | 12 | 12 | 15 |  |  |
| I2C_TPM_SDA | I2C93-DIFF1 | PAIR | 4 | 5 | 5 | 10 | 5 | 14 | 6 | 10 | 12 | 12 | 12 | 12 | 15 |  |  |
| I2C_TPM_SDA | I2C93-DIFF1 | PAIR | 5 | 5 | 5 | 10 | 5 | 14 | 6 | 10 | 12 | 12 | 12 | 12 | 15 |  |  |
| I2C_TPM_SDA | I2C93-DIFF1 | PAIR | 6 | 5 | 5 | 10 | 5 | 14 | 6 | 10 | 12 | 12 | 12 | 12 | 15 |  |  |
| I2C_TPM_SDA | I2C93-DIFF1 | PAIR | 7 | 5 | 5 | 10 | 5 | 14 | 6 | 10 | 12 | 12 | 12 | 12 | 15 |  |  |
| I2C_TPM_SDA | I2C93-DIFF1 | PAIR | 8 | 4.75 | 5 | 10 | 5 | 14 | 6 | 9.5 | 12 | 12 | 12 | 12 | 15 |  |  |
| LAN_SMB_CLK | I2C94-DIFF1 | PAIR | 1 | 4.75 | 5 | 10 | 5 | 14 | 6 | 9.5 | 12 | 12 | 12 | 12 | 15 |  |  |
| LAN_SMB_CLK | I2C94-DIFF1 | PAIR | 2 | 5 | 5 | 10 | 5 | 14 | 6 | 10 | 12 | 12 | 12 | 12 | 15 |  |  |
| LAN_SMB_CLK | I2C94-DIFF1 | PAIR | 3 | 5 | 5 | 10 | 5 | 14 | 6 | 10 | 12 | 12 | 12 | 12 | 15 |  |  |
| LAN_SMB_CLK | I2C94-DIFF1 | PAIR | 4 | 5 | 5 | 10 | 5 | 14 | 6 | 10 | 12 | 12 | 12 | 12 | 15 |  |  |
| LAN_SMB_CLK | I2C94-DIFF1 | PAIR | 5 | 5 | 5 | 10 | 5 | 14 | 6 | 10 | 12 | 12 | 12 | 12 | 15 |  |  |
| LAN_SMB_CLK | I2C94-DIFF1 | PAIR | 6 | 5 | 5 | 10 | 5 | 14 | 6 | 10 | 12 | 12 | 12 | 12 | 15 |  |  |
| LAN_SMB_CLK | I2C94-DIFF1 | PAIR | 7 | 5 | 5 | 10 | 5 | 14 | 6 | 10 | 12 | 12 | 12 | 12 | 15 |  |  |
| LAN_SMB_CLK | I2C94-DIFF1 | PAIR | 8 | 4.75 | 5 | 10 | 5 | 14 | 6 | 9.5 | 12 | 12 | 12 | 12 | 15 |  |  |
| LAN_SMB_DAT | I2C94-DIFF1 | PAIR | 1 | 4.75 | 5 | 10 | 5 | 14 | 6 | 9.5 | 12 | 12 | 12 | 12 | 15 |  |  |
| LAN_SMB_DAT | I2C94-DIFF1 | PAIR | 2 | 5 | 5 | 10 | 5 | 14 | 6 | 10 | 12 | 12 | 12 | 12 | 15 |  |  |
| LAN_SMB_DAT | I2C94-DIFF1 | PAIR | 3 | 5 | 5 | 10 | 5 | 14 | 6 | 10 | 12 | 12 | 12 | 12 | 15 |  |  |
| LAN_SMB_DAT | I2C94-DIFF1 | PAIR | 4 | 5 | 5 | 10 | 5 | 14 | 6 | 10 | 12 | 12 | 12 | 12 | 15 |  |  |
| LAN_SMB_DAT | I2C94-DIFF1 | PAIR | 5 | 5 | 5 | 10 | 5 | 14 | 6 | 10 | 12 | 12 | 12 | 12 | 15 |  |  |
| LAN_SMB_DAT | I2C94-DIFF1 | PAIR | 6 | 5 | 5 | 10 | 5 | 14 | 6 | 10 | 12 | 12 | 12 | 12 | 15 |  |  |
| LAN_SMB_DAT | I2C94-DIFF1 | PAIR | 7 | 5 | 5 | 10 | 5 | 14 | 6 | 10 | 12 | 12 | 12 | 12 | 15 |  |  |
| LAN_SMB_DAT | I2C94-DIFF1 | PAIR | 8 | 4.75 | 5 | 10 | 5 | 14 | 6 | 9.5 | 12 | 12 | 12 | 12 | 15 |  |  |
| BMC0_SMB3_CLK | I2C95-DIFF1 | PAIR | 1 | 4.75 | 5 | 10 | 5 | 14 | 6 | 9.5 | 12 | 12 | 12 | 12 | 15 |  |  |
| BMC0_SMB3_CLK | I2C95-DIFF1 | PAIR | 2 | 5 | 5 | 10 | 5 | 14 | 6 | 10 | 12 | 12 | 12 | 12 | 15 |  |  |
| BMC0_SMB3_CLK | I2C95-DIFF1 | PAIR | 3 | 5 | 5 | 10 | 5 | 14 | 6 | 10 | 12 | 12 | 12 | 12 | 15 |  |  |
| BMC0_SMB3_CLK | I2C95-DIFF1 | PAIR | 4 | 5 | 5 | 10 | 5 | 14 | 6 | 10 | 12 | 12 | 12 | 12 | 15 |  |  |
| BMC0_SMB3_CLK | I2C95-DIFF1 | PAIR | 5 | 5 | 5 | 10 | 5 | 14 | 6 | 10 | 12 | 12 | 12 | 12 | 15 |  |  |
| BMC0_SMB3_CLK | I2C95-DIFF1 | PAIR | 6 | 5 | 5 | 10 | 5 | 14 | 6 | 10 | 12 | 12 | 12 | 12 | 15 |  |  |
| BMC0_SMB3_CLK | I2C95-DIFF1 | PAIR | 7 | 5 | 5 | 10 | 5 | 14 | 6 | 10 | 12 | 12 | 12 | 12 | 15 |  |  |
| BMC0_SMB3_CLK | I2C95-DIFF1 | PAIR | 8 | 4.75 | 5 | 10 | 5 | 14 | 6 | 9.5 | 12 | 12 | 12 | 12 | 15 |  |  |
| BMC0_SMB3_DAT | I2C95-DIFF1 | PAIR | 1 | 4.75 | 5 | 10 | 5 | 14 | 6 | 9.5 | 12 | 12 | 12 | 12 | 15 |  |  |
| BMC0_SMB3_DAT | I2C95-DIFF1 | PAIR | 2 | 5 | 5 | 10 | 5 | 14 | 6 | 10 | 12 | 12 | 12 | 12 | 15 |  |  |
| BMC0_SMB3_DAT | I2C95-DIFF1 | PAIR | 3 | 5 | 5 | 10 | 5 | 14 | 6 | 10 | 12 | 12 | 12 | 12 | 15 |  |  |
| BMC0_SMB3_DAT | I2C95-DIFF1 | PAIR | 4 | 5 | 5 | 10 | 5 | 14 | 6 | 10 | 12 | 12 | 12 | 12 | 15 |  |  |
| BMC0_SMB3_DAT | I2C95-DIFF1 | PAIR | 5 | 5 | 5 | 10 | 5 | 14 | 6 | 10 | 12 | 12 | 12 | 12 | 15 |  |  |
| BMC0_SMB3_DAT | I2C95-DIFF1 | PAIR | 6 | 5 | 5 | 10 | 5 | 14 | 6 | 10 | 12 | 12 | 12 | 12 | 15 |  |  |
| BMC0_SMB3_DAT | I2C95-DIFF1 | PAIR | 7 | 5 | 5 | 10 | 5 | 14 | 6 | 10 | 12 | 12 | 12 | 12 | 15 |  |  |
| BMC0_SMB3_DAT | I2C95-DIFF1 | PAIR | 8 | 4.75 | 5 | 10 | 5 | 14 | 6 | 9.5 | 12 | 12 | 12 | 12 | 15 |  |  |
| U56_SCL | I2C96-DIFF1 | PAIR | 1 | 4.75 | 5 | 10 | 5 | 14 | 6 | 9.5 | 12 | 12 | 12 | 12 | 15 |  |  |
| U56_SCL | I2C96-DIFF1 | PAIR | 2 | 5 | 5 | 10 | 5 | 14 | 6 | 10 | 12 | 12 | 12 | 12 | 15 |  |  |
| U56_SCL | I2C96-DIFF1 | PAIR | 3 | 5 | 5 | 10 | 5 | 14 | 6 | 10 | 12 | 12 | 12 | 12 | 15 |  |  |
| U56_SCL | I2C96-DIFF1 | PAIR | 4 | 5 | 5 | 10 | 5 | 14 | 6 | 10 | 12 | 12 | 12 | 12 | 15 |  |  |
| U56_SCL | I2C96-DIFF1 | PAIR | 5 | 5 | 5 | 10 | 5 | 14 | 6 | 10 | 12 | 12 | 12 | 12 | 15 |  |  |
| U56_SCL | I2C96-DIFF1 | PAIR | 6 | 5 | 5 | 10 | 5 | 14 | 6 | 10 | 12 | 12 | 12 | 12 | 15 |  |  |
| U56_SCL | I2C96-DIFF1 | PAIR | 7 | 5 | 5 | 10 | 5 | 14 | 6 | 10 | 12 | 12 | 12 | 12 | 15 |  |  |
| U56_SCL | I2C96-DIFF1 | PAIR | 8 | 4.75 | 5 | 10 | 5 | 14 | 6 | 9.5 | 12 | 12 | 12 | 12 | 15 |  |  |
| U56_SDA | I2C96-DIFF1 | PAIR | 1 | 4.75 | 5 | 10 | 5 | 14 | 6 | 9.5 | 12 | 12 | 12 | 12 | 15 |  |  |
| U56_SDA | I2C96-DIFF1 | PAIR | 2 | 5 | 5 | 10 | 5 | 14 | 6 | 10 | 12 | 12 | 12 | 12 | 15 |  |  |
| U56_SDA | I2C96-DIFF1 | PAIR | 3 | 5 | 5 | 10 | 5 | 14 | 6 | 10 | 12 | 12 | 12 | 12 | 15 |  |  |
| U56_SDA | I2C96-DIFF1 | PAIR | 4 | 5 | 5 | 10 | 5 | 14 | 6 | 10 | 12 | 12 | 12 | 12 | 15 |  |  |
| U56_SDA | I2C96-DIFF1 | PAIR | 5 | 5 | 5 | 10 | 5 | 14 | 6 | 10 | 12 | 12 | 12 | 12 | 15 |  |  |
| U56_SDA | I2C96-DIFF1 | PAIR | 6 | 5 | 5 | 10 | 5 | 14 | 6 | 10 | 12 | 12 | 12 | 12 | 15 |  |  |
| U56_SDA | I2C96-DIFF1 | PAIR | 7 | 5 | 5 | 10 | 5 | 14 | 6 | 10 | 12 | 12 | 12 | 12 | 15 |  |  |
| U56_SDA | I2C96-DIFF1 | PAIR | 8 | 4.75 | 5 | 10 | 5 | 14 | 6 | 9.5 | 12 | 12 | 12 | 12 | 15 |  |  |
| MNG_TX_DN | LAN_RX10-DIFF1 | PAIR | 1 | 4.13 | 5 | 10 | 5 | 12 | 6 | 33 | 12 | 12 | 12 | 12 | 9.37 | 100 Ohms | TOP=L2:L3=L2/L4:L6=L5/L7:BOTTOM=L7 |
| MNG_TX_DN | LAN_RX10-DIFF1 | PAIR | 2 | 4 | 5 | 10 | 5 | 12 | 6 | 20 | 12 | 12 | 12 | 12 | 8 | 100 Ohms | TOP=L2:L3=L2/L4:L6=L5/L7:BOTTOM=L7 |
| MNG_TX_DN | LAN_RX10-DIFF1 | PAIR | 3 | 4 | 5 | 10 | 5 | 12 | 6 | 20 | 12 | 12 | 12 | 12 | 8 | 100 Ohms | TOP=L2:L3=L2/L4:L6=L5/L7:BOTTOM=L7 |
| MNG_TX_DN | LAN_RX10-DIFF1 | PAIR | 4 | 4 | 5 | 10 | 5 | 12 | 6 | 20 | 12 | 12 | 12 | 12 | 8 | 100 Ohms | TOP=L2:L3=L2/L4:L6=L5/L7:BOTTOM=L7 |
| MNG_TX_DN | LAN_RX10-DIFF1 | PAIR | 5 | 4 | 5 | 10 | 5 | 12 | 6 | 20 | 12 | 12 | 12 | 12 | 8 | 100 Ohms | TOP=L2:L3=L2/L4:L6=L5/L7:BOTTOM=L7 |
| MNG_TX_DN | LAN_RX10-DIFF1 | PAIR | 6 | 4 | 5 | 10 | 5 | 12 | 6 | 20 | 12 | 12 | 12 | 12 | 8 | 100 Ohms | TOP=L2:L3=L2/L4:L6=L5/L7:BOTTOM=L7 |
| MNG_TX_DN | LAN_RX10-DIFF1 | PAIR | 7 | 4 | 5 | 10 | 5 | 12 | 6 | 20 | 12 | 12 | 12 | 12 | 8 | 100 Ohms | TOP=L2:L3=L2/L4:L6=L5/L7:BOTTOM=L7 |
| MNG_TX_DN | LAN_RX10-DIFF1 | PAIR | 8 | 4.13 | 5 | 10 | 5 | 12 | 6 | 33 | 12 | 12 | 12 | 12 | 9.37 | 100 Ohms | TOP=L2:L3=L2/L4:L6=L5/L7:BOTTOM=L7 |
| MNG_TX_DP | LAN_RX10-DIFF1 | PAIR | 1 | 4.13 | 5 | 10 | 5 | 12 | 6 | 33 | 12 | 12 | 12 | 12 | 9.37 | 100 Ohms | TOP=L2:L3=L2/L4:L6=L5/L7:BOTTOM=L7 |
| MNG_TX_DP | LAN_RX10-DIFF1 | PAIR | 2 | 4 | 5 | 10 | 5 | 12 | 6 | 20 | 12 | 12 | 12 | 12 | 8 | 100 Ohms | TOP=L2:L3=L2/L4:L6=L5/L7:BOTTOM=L7 |
| MNG_TX_DP | LAN_RX10-DIFF1 | PAIR | 3 | 4 | 5 | 10 | 5 | 12 | 6 | 20 | 12 | 12 | 12 | 12 | 8 | 100 Ohms | TOP=L2:L3=L2/L4:L6=L5/L7:BOTTOM=L7 |
| MNG_TX_DP | LAN_RX10-DIFF1 | PAIR | 4 | 4 | 5 | 10 | 5 | 12 | 6 | 20 | 12 | 12 | 12 | 12 | 8 | 100 Ohms | TOP=L2:L3=L2/L4:L6=L5/L7:BOTTOM=L7 |
| MNG_TX_DP | LAN_RX10-DIFF1 | PAIR | 5 | 4 | 5 | 10 | 5 | 12 | 6 | 20 | 12 | 12 | 12 | 12 | 8 | 100 Ohms | TOP=L2:L3=L2/L4:L6=L5/L7:BOTTOM=L7 |
| MNG_TX_DP | LAN_RX10-DIFF1 | PAIR | 6 | 4 | 5 | 10 | 5 | 12 | 6 | 20 | 12 | 12 | 12 | 12 | 8 | 100 Ohms | TOP=L2:L3=L2/L4:L6=L5/L7:BOTTOM=L7 |
| MNG_TX_DP | LAN_RX10-DIFF1 | PAIR | 7 | 4 | 5 | 10 | 5 | 12 | 6 | 20 | 12 | 12 | 12 | 12 | 8 | 100 Ohms | TOP=L2:L3=L2/L4:L6=L5/L7:BOTTOM=L7 |
| MNG_TX_DP | LAN_RX10-DIFF1 | PAIR | 8 | 4.13 | 5 | 10 | 5 | 12 | 6 | 33 | 12 | 12 | 12 | 12 | 9.37 | 100 Ohms | TOP=L2:L3=L2/L4:L6=L5/L7:BOTTOM=L7 |
| NIC0_MDI0_N0 | LAN_RX1-DIFF1 | PAIR | 1 | 4.13 | 5 | 10 | 5 | 12 | 6 | 33 | 12 | 12 | 12 | 12 | 9.37 | 100 Ohms | TOP=L2:L3=L2/L4:L6=L5/L7:BOTTOM=L7 |
| NIC0_MDI0_N0 | LAN_RX1-DIFF1 | PAIR | 2 | 4 | 5 | 10 | 5 | 12 | 6 | 20 | 12 | 12 | 12 | 12 | 8 | 100 Ohms | TOP=L2:L3=L2/L4:L6=L5/L7:BOTTOM=L7 |
| NIC0_MDI0_N0 | LAN_RX1-DIFF1 | PAIR | 3 | 4 | 5 | 10 | 5 | 12 | 6 | 20 | 12 | 12 | 12 | 12 | 8 | 100 Ohms | TOP=L2:L3=L2/L4:L6=L5/L7:BOTTOM=L7 |
| NIC0_MDI0_N0 | LAN_RX1-DIFF1 | PAIR | 4 | 4 | 5 | 10 | 5 | 12 | 6 | 20 | 12 | 12 | 12 | 12 | 8 | 100 Ohms | TOP=L2:L3=L2/L4:L6=L5/L7:BOTTOM=L7 |
| NIC0_MDI0_N0 | LAN_RX1-DIFF1 | PAIR | 5 | 4 | 5 | 10 | 5 | 12 | 6 | 20 | 12 | 12 | 12 | 12 | 8 | 100 Ohms | TOP=L2:L3=L2/L4:L6=L5/L7:BOTTOM=L7 |
| NIC0_MDI0_N0 | LAN_RX1-DIFF1 | PAIR | 6 | 4 | 5 | 10 | 5 | 12 | 6 | 20 | 12 | 12 | 12 | 12 | 8 | 100 Ohms | TOP=L2:L3=L2/L4:L6=L5/L7:BOTTOM=L7 |
| NIC0_MDI0_N0 | LAN_RX1-DIFF1 | PAIR | 7 | 4 | 5 | 10 | 5 | 12 | 6 | 20 | 12 | 12 | 12 | 12 | 8 | 100 Ohms | TOP=L2:L3=L2/L4:L6=L5/L7:BOTTOM=L7 |
| NIC0_MDI0_N0 | LAN_RX1-DIFF1 | PAIR | 8 | 4.13 | 5 | 10 | 5 | 12 | 6 | 33 | 12 | 12 | 12 | 12 | 9.37 | 100 Ohms | TOP=L2:L3=L2/L4:L6=L5/L7:BOTTOM=L7 |
| NIC0_MDI0_P0 | LAN_RX1-DIFF1 | PAIR | 1 | 4.13 | 5 | 10 | 5 | 12 | 6 | 33 | 12 | 12 | 12 | 12 | 9.37 | 100 Ohms | TOP=L2:L3=L2/L4:L6=L5/L7:BOTTOM=L7 |
| NIC0_MDI0_P0 | LAN_RX1-DIFF1 | PAIR | 2 | 4 | 5 | 10 | 5 | 12 | 6 | 20 | 12 | 12 | 12 | 12 | 8 | 100 Ohms | TOP=L2:L3=L2/L4:L6=L5/L7:BOTTOM=L7 |
| NIC0_MDI0_P0 | LAN_RX1-DIFF1 | PAIR | 3 | 4 | 5 | 10 | 5 | 12 | 6 | 20 | 12 | 12 | 12 | 12 | 8 | 100 Ohms | TOP=L2:L3=L2/L4:L6=L5/L7:BOTTOM=L7 |
| NIC0_MDI0_P0 | LAN_RX1-DIFF1 | PAIR | 4 | 4 | 5 | 10 | 5 | 12 | 6 | 20 | 12 | 12 | 12 | 12 | 8 | 100 Ohms | TOP=L2:L3=L2/L4:L6=L5/L7:BOTTOM=L7 |
| NIC0_MDI0_P0 | LAN_RX1-DIFF1 | PAIR | 5 | 4 | 5 | 10 | 5 | 12 | 6 | 20 | 12 | 12 | 12 | 12 | 8 | 100 Ohms | TOP=L2:L3=L2/L4:L6=L5/L7:BOTTOM=L7 |
| NIC0_MDI0_P0 | LAN_RX1-DIFF1 | PAIR | 6 | 4 | 5 | 10 | 5 | 12 | 6 | 20 | 12 | 12 | 12 | 12 | 8 | 100 Ohms | TOP=L2:L3=L2/L4:L6=L5/L7:BOTTOM=L7 |
| NIC0_MDI0_P0 | LAN_RX1-DIFF1 | PAIR | 7 | 4 | 5 | 10 | 5 | 12 | 6 | 20 | 12 | 12 | 12 | 12 | 8 | 100 Ohms | TOP=L2:L3=L2/L4:L6=L5/L7:BOTTOM=L7 |
| NIC0_MDI0_P0 | LAN_RX1-DIFF1 | PAIR | 8 | 4.13 | 5 | 10 | 5 | 12 | 6 | 33 | 12 | 12 | 12 | 12 | 9.37 | 100 Ohms | TOP=L2:L3=L2/L4:L6=L5/L7:BOTTOM=L7 |
| NIC0_MDI0_N1 | LAN_RX2-DIFF1 | PAIR | 1 | 4.13 | 5 | 10 | 5 | 12 | 6 | 33 | 12 | 12 | 12 | 12 | 9.37 | 100 Ohms | TOP=L2:L3=L2/L4:L6=L5/L7:BOTTOM=L7 |
| NIC0_MDI0_N1 | LAN_RX2-DIFF1 | PAIR | 2 | 4 | 5 | 10 | 5 | 12 | 6 | 20 | 12 | 12 | 12 | 12 | 8 | 100 Ohms | TOP=L2:L3=L2/L4:L6=L5/L7:BOTTOM=L7 |
| NIC0_MDI0_N1 | LAN_RX2-DIFF1 | PAIR | 3 | 4 | 5 | 10 | 5 | 12 | 6 | 20 | 12 | 12 | 12 | 12 | 8 | 100 Ohms | TOP=L2:L3=L2/L4:L6=L5/L7:BOTTOM=L7 |
| NIC0_MDI0_N1 | LAN_RX2-DIFF1 | PAIR | 4 | 4 | 5 | 10 | 5 | 12 | 6 | 20 | 12 | 12 | 12 | 12 | 8 | 100 Ohms | TOP=L2:L3=L2/L4:L6=L5/L7:BOTTOM=L7 |
| NIC0_MDI0_N1 | LAN_RX2-DIFF1 | PAIR | 5 | 4 | 5 | 10 | 5 | 12 | 6 | 20 | 12 | 12 | 12 | 12 | 8 | 100 Ohms | TOP=L2:L3=L2/L4:L6=L5/L7:BOTTOM=L7 |
| NIC0_MDI0_N1 | LAN_RX2-DIFF1 | PAIR | 6 | 4 | 5 | 10 | 5 | 12 | 6 | 20 | 12 | 12 | 12 | 12 | 8 | 100 Ohms | TOP=L2:L3=L2/L4:L6=L5/L7:BOTTOM=L7 |
| NIC0_MDI0_N1 | LAN_RX2-DIFF1 | PAIR | 7 | 4 | 5 | 10 | 5 | 12 | 6 | 20 | 12 | 12 | 12 | 12 | 8 | 100 Ohms | TOP=L2:L3=L2/L4:L6=L5/L7:BOTTOM=L7 |
| NIC0_MDI0_N1 | LAN_RX2-DIFF1 | PAIR | 8 | 4.13 | 5 | 10 | 5 | 12 | 6 | 33 | 12 | 12 | 12 | 12 | 9.37 | 100 Ohms | TOP=L2:L3=L2/L4:L6=L5/L7:BOTTOM=L7 |
| NIC0_MDI0_P1 | LAN_RX2-DIFF1 | PAIR | 1 | 4.13 | 5 | 10 | 5 | 12 | 6 | 33 | 12 | 12 | 12 | 12 | 9.37 | 100 Ohms | TOP=L2:L3=L2/L4:L6=L5/L7:BOTTOM=L7 |
| NIC0_MDI0_P1 | LAN_RX2-DIFF1 | PAIR | 2 | 4 | 5 | 10 | 5 | 12 | 6 | 20 | 12 | 12 | 12 | 12 | 8 | 100 Ohms | TOP=L2:L3=L2/L4:L6=L5/L7:BOTTOM=L7 |
| NIC0_MDI0_P1 | LAN_RX2-DIFF1 | PAIR | 3 | 4 | 5 | 10 | 5 | 12 | 6 | 20 | 12 | 12 | 12 | 12 | 8 | 100 Ohms | TOP=L2:L3=L2/L4:L6=L5/L7:BOTTOM=L7 |
| NIC0_MDI0_P1 | LAN_RX2-DIFF1 | PAIR | 4 | 4 | 5 | 10 | 5 | 12 | 6 | 20 | 12 | 12 | 12 | 12 | 8 | 100 Ohms | TOP=L2:L3=L2/L4:L6=L5/L7:BOTTOM=L7 |
| NIC0_MDI0_P1 | LAN_RX2-DIFF1 | PAIR | 5 | 4 | 5 | 10 | 5 | 12 | 6 | 20 | 12 | 12 | 12 | 12 | 8 | 100 Ohms | TOP=L2:L3=L2/L4:L6=L5/L7:BOTTOM=L7 |
| NIC0_MDI0_P1 | LAN_RX2-DIFF1 | PAIR | 6 | 4 | 5 | 10 | 5 | 12 | 6 | 20 | 12 | 12 | 12 | 12 | 8 | 100 Ohms | TOP=L2:L3=L2/L4:L6=L5/L7:BOTTOM=L7 |
| NIC0_MDI0_P1 | LAN_RX2-DIFF1 | PAIR | 7 | 4 | 5 | 10 | 5 | 12 | 6 | 20 | 12 | 12 | 12 | 12 | 8 | 100 Ohms | TOP=L2:L3=L2/L4:L6=L5/L7:BOTTOM=L7 |
| NIC0_MDI0_P1 | LAN_RX2-DIFF1 | PAIR | 8 | 4.13 | 5 | 10 | 5 | 12 | 6 | 33 | 12 | 12 | 12 | 12 | 9.37 | 100 Ohms | TOP=L2:L3=L2/L4:L6=L5/L7:BOTTOM=L7 |
| NIC0_MDI0_N2 | LAN_RX3-DIFF1 | PAIR | 1 | 4.13 | 5 | 10 | 5 | 12 | 6 | 33 | 12 | 12 | 12 | 12 | 9.37 | 100 Ohms | TOP=L2:L3=L2/L4:L6=L5/L7:BOTTOM=L7 |
| NIC0_MDI0_N2 | LAN_RX3-DIFF1 | PAIR | 2 | 4 | 5 | 10 | 5 | 12 | 6 | 20 | 12 | 12 | 12 | 12 | 8 | 100 Ohms | TOP=L2:L3=L2/L4:L6=L5/L7:BOTTOM=L7 |
| NIC0_MDI0_N2 | LAN_RX3-DIFF1 | PAIR | 3 | 4 | 5 | 10 | 5 | 12 | 6 | 20 | 12 | 12 | 12 | 12 | 8 | 100 Ohms | TOP=L2:L3=L2/L4:L6=L5/L7:BOTTOM=L7 |
| NIC0_MDI0_N2 | LAN_RX3-DIFF1 | PAIR | 4 | 4 | 5 | 10 | 5 | 12 | 6 | 20 | 12 | 12 | 12 | 12 | 8 | 100 Ohms | TOP=L2:L3=L2/L4:L6=L5/L7:BOTTOM=L7 |
| NIC0_MDI0_N2 | LAN_RX3-DIFF1 | PAIR | 5 | 4 | 5 | 10 | 5 | 12 | 6 | 20 | 12 | 12 | 12 | 12 | 8 | 100 Ohms | TOP=L2:L3=L2/L4:L6=L5/L7:BOTTOM=L7 |
| NIC0_MDI0_N2 | LAN_RX3-DIFF1 | PAIR | 6 | 4 | 5 | 10 | 5 | 12 | 6 | 20 | 12 | 12 | 12 | 12 | 8 | 100 Ohms | TOP=L2:L3=L2/L4:L6=L5/L7:BOTTOM=L7 |
| NIC0_MDI0_N2 | LAN_RX3-DIFF1 | PAIR | 7 | 4 | 5 | 10 | 5 | 12 | 6 | 20 | 12 | 12 | 12 | 12 | 8 | 100 Ohms | TOP=L2:L3=L2/L4:L6=L5/L7:BOTTOM=L7 |
| NIC0_MDI0_N2 | LAN_RX3-DIFF1 | PAIR | 8 | 4.13 | 5 | 10 | 5 | 12 | 6 | 33 | 12 | 12 | 12 | 12 | 9.37 | 100 Ohms | TOP=L2:L3=L2/L4:L6=L5/L7:BOTTOM=L7 |
| NIC0_MDI0_P2 | LAN_RX3-DIFF1 | PAIR | 1 | 4.13 | 5 | 10 | 5 | 12 | 6 | 33 | 12 | 12 | 12 | 12 | 9.37 | 100 Ohms | TOP=L2:L3=L2/L4:L6=L5/L7:BOTTOM=L7 |
| NIC0_MDI0_P2 | LAN_RX3-DIFF1 | PAIR | 2 | 4 | 5 | 10 | 5 | 12 | 6 | 20 | 12 | 12 | 12 | 12 | 8 | 100 Ohms | TOP=L2:L3=L2/L4:L6=L5/L7:BOTTOM=L7 |
| NIC0_MDI0_P2 | LAN_RX3-DIFF1 | PAIR | 3 | 4 | 5 | 10 | 5 | 12 | 6 | 20 | 12 | 12 | 12 | 12 | 8 | 100 Ohms | TOP=L2:L3=L2/L4:L6=L5/L7:BOTTOM=L7 |
| NIC0_MDI0_P2 | LAN_RX3-DIFF1 | PAIR | 4 | 4 | 5 | 10 | 5 | 12 | 6 | 20 | 12 | 12 | 12 | 12 | 8 | 100 Ohms | TOP=L2:L3=L2/L4:L6=L5/L7:BOTTOM=L7 |
| NIC0_MDI0_P2 | LAN_RX3-DIFF1 | PAIR | 5 | 4 | 5 | 10 | 5 | 12 | 6 | 20 | 12 | 12 | 12 | 12 | 8 | 100 Ohms | TOP=L2:L3=L2/L4:L6=L5/L7:BOTTOM=L7 |
| NIC0_MDI0_P2 | LAN_RX3-DIFF1 | PAIR | 6 | 4 | 5 | 10 | 5 | 12 | 6 | 20 | 12 | 12 | 12 | 12 | 8 | 100 Ohms | TOP=L2:L3=L2/L4:L6=L5/L7:BOTTOM=L7 |
| NIC0_MDI0_P2 | LAN_RX3-DIFF1 | PAIR | 7 | 4 | 5 | 10 | 5 | 12 | 6 | 20 | 12 | 12 | 12 | 12 | 8 | 100 Ohms | TOP=L2:L3=L2/L4:L6=L5/L7:BOTTOM=L7 |
| NIC0_MDI0_P2 | LAN_RX3-DIFF1 | PAIR | 8 | 4.13 | 5 | 10 | 5 | 12 | 6 | 33 | 12 | 12 | 12 | 12 | 9.37 | 100 Ohms | TOP=L2:L3=L2/L4:L6=L5/L7:BOTTOM=L7 |
| NIC0_MDI0_N3 | LAN_RX4-DIFF1 | PAIR | 1 | 4.13 | 5 | 10 | 5 | 12 | 6 | 33 | 12 | 12 | 12 | 12 | 9.37 | 100 Ohms | TOP=L2:L3=L2/L4:L6=L5/L7:BOTTOM=L7 |
| NIC0_MDI0_N3 | LAN_RX4-DIFF1 | PAIR | 2 | 4 | 5 | 10 | 5 | 12 | 6 | 20 | 12 | 12 | 12 | 12 | 8 | 100 Ohms | TOP=L2:L3=L2/L4:L6=L5/L7:BOTTOM=L7 |
| NIC0_MDI0_N3 | LAN_RX4-DIFF1 | PAIR | 3 | 4 | 5 | 10 | 5 | 12 | 6 | 20 | 12 | 12 | 12 | 12 | 8 | 100 Ohms | TOP=L2:L3=L2/L4:L6=L5/L7:BOTTOM=L7 |
| NIC0_MDI0_N3 | LAN_RX4-DIFF1 | PAIR | 4 | 4 | 5 | 10 | 5 | 12 | 6 | 20 | 12 | 12 | 12 | 12 | 8 | 100 Ohms | TOP=L2:L3=L2/L4:L6=L5/L7:BOTTOM=L7 |
| NIC0_MDI0_N3 | LAN_RX4-DIFF1 | PAIR | 5 | 4 | 5 | 10 | 5 | 12 | 6 | 20 | 12 | 12 | 12 | 12 | 8 | 100 Ohms | TOP=L2:L3=L2/L4:L6=L5/L7:BOTTOM=L7 |
| NIC0_MDI0_N3 | LAN_RX4-DIFF1 | PAIR | 6 | 4 | 5 | 10 | 5 | 12 | 6 | 20 | 12 | 12 | 12 | 12 | 8 | 100 Ohms | TOP=L2:L3=L2/L4:L6=L5/L7:BOTTOM=L7 |
| NIC0_MDI0_N3 | LAN_RX4-DIFF1 | PAIR | 7 | 4 | 5 | 10 | 5 | 12 | 6 | 20 | 12 | 12 | 12 | 12 | 8 | 100 Ohms | TOP=L2:L3=L2/L4:L6=L5/L7:BOTTOM=L7 |
| NIC0_MDI0_N3 | LAN_RX4-DIFF1 | PAIR | 8 | 4.13 | 5 | 10 | 5 | 12 | 6 | 33 | 12 | 12 | 12 | 12 | 9.37 | 100 Ohms | TOP=L2:L3=L2/L4:L6=L5/L7:BOTTOM=L7 |
| NIC0_MDI0_P3 | LAN_RX4-DIFF1 | PAIR | 1 | 4.13 | 5 | 10 | 5 | 12 | 6 | 33 | 12 | 12 | 12 | 12 | 9.37 | 100 Ohms | TOP=L2:L3=L2/L4:L6=L5/L7:BOTTOM=L7 |
| NIC0_MDI0_P3 | LAN_RX4-DIFF1 | PAIR | 2 | 4 | 5 | 10 | 5 | 12 | 6 | 20 | 12 | 12 | 12 | 12 | 8 | 100 Ohms | TOP=L2:L3=L2/L4:L6=L5/L7:BOTTOM=L7 |
| NIC0_MDI0_P3 | LAN_RX4-DIFF1 | PAIR | 3 | 4 | 5 | 10 | 5 | 12 | 6 | 20 | 12 | 12 | 12 | 12 | 8 | 100 Ohms | TOP=L2:L3=L2/L4:L6=L5/L7:BOTTOM=L7 |
| NIC0_MDI0_P3 | LAN_RX4-DIFF1 | PAIR | 4 | 4 | 5 | 10 | 5 | 12 | 6 | 20 | 12 | 12 | 12 | 12 | 8 | 100 Ohms | TOP=L2:L3=L2/L4:L6=L5/L7:BOTTOM=L7 |
| NIC0_MDI0_P3 | LAN_RX4-DIFF1 | PAIR | 5 | 4 | 5 | 10 | 5 | 12 | 6 | 20 | 12 | 12 | 12 | 12 | 8 | 100 Ohms | TOP=L2:L3=L2/L4:L6=L5/L7:BOTTOM=L7 |
| NIC0_MDI0_P3 | LAN_RX4-DIFF1 | PAIR | 6 | 4 | 5 | 10 | 5 | 12 | 6 | 20 | 12 | 12 | 12 | 12 | 8 | 100 Ohms | TOP=L2:L3=L2/L4:L6=L5/L7:BOTTOM=L7 |
| NIC0_MDI0_P3 | LAN_RX4-DIFF1 | PAIR | 7 | 4 | 5 | 10 | 5 | 12 | 6 | 20 | 12 | 12 | 12 | 12 | 8 | 100 Ohms | TOP=L2:L3=L2/L4:L6=L5/L7:BOTTOM=L7 |
| NIC0_MDI0_P3 | LAN_RX4-DIFF1 | PAIR | 8 | 4.13 | 5 | 10 | 5 | 12 | 6 | 33 | 12 | 12 | 12 | 12 | 9.37 | 100 Ohms | TOP=L2:L3=L2/L4:L6=L5/L7:BOTTOM=L7 |
| NIC0_MDI0_N0_R | LAN_RX5-DIFF1 | PAIR | 1 | 4.13 | 5 | 10 | 5 | 12 | 6 | 33 | 12 | 12 | 12 | 12 | 9.37 | 100 Ohms | TOP=L2:L3=L2/L4:L6=L5/L7:BOTTOM=L7 |
| NIC0_MDI0_N0_R | LAN_RX5-DIFF1 | PAIR | 2 | 4 | 5 | 10 | 5 | 12 | 6 | 20 | 12 | 12 | 12 | 12 | 8 | 100 Ohms | TOP=L2:L3=L2/L4:L6=L5/L7:BOTTOM=L7 |
| NIC0_MDI0_N0_R | LAN_RX5-DIFF1 | PAIR | 3 | 4 | 5 | 10 | 5 | 12 | 6 | 20 | 12 | 12 | 12 | 12 | 8 | 100 Ohms | TOP=L2:L3=L2/L4:L6=L5/L7:BOTTOM=L7 |
| NIC0_MDI0_N0_R | LAN_RX5-DIFF1 | PAIR | 4 | 4 | 5 | 10 | 5 | 12 | 6 | 20 | 12 | 12 | 12 | 12 | 8 | 100 Ohms | TOP=L2:L3=L2/L4:L6=L5/L7:BOTTOM=L7 |
| NIC0_MDI0_N0_R | LAN_RX5-DIFF1 | PAIR | 5 | 4 | 5 | 10 | 5 | 12 | 6 | 20 | 12 | 12 | 12 | 12 | 8 | 100 Ohms | TOP=L2:L3=L2/L4:L6=L5/L7:BOTTOM=L7 |
| NIC0_MDI0_N0_R | LAN_RX5-DIFF1 | PAIR | 6 | 4 | 5 | 10 | 5 | 12 | 6 | 20 | 12 | 12 | 12 | 12 | 8 | 100 Ohms | TOP=L2:L3=L2/L4:L6=L5/L7:BOTTOM=L7 |
| NIC0_MDI0_N0_R | LAN_RX5-DIFF1 | PAIR | 7 | 4 | 5 | 10 | 5 | 12 | 6 | 20 | 12 | 12 | 12 | 12 | 8 | 100 Ohms | TOP=L2:L3=L2/L4:L6=L5/L7:BOTTOM=L7 |
| NIC0_MDI0_N0_R | LAN_RX5-DIFF1 | PAIR | 8 | 4.13 | 5 | 10 | 5 | 12 | 6 | 33 | 12 | 12 | 12 | 12 | 9.37 | 100 Ohms | TOP=L2:L3=L2/L4:L6=L5/L7:BOTTOM=L7 |
| NIC0_MDI0_P0_R | LAN_RX5-DIFF1 | PAIR | 1 | 4.13 | 5 | 10 | 5 | 12 | 6 | 33 | 12 | 12 | 12 | 12 | 9.37 | 100 Ohms | TOP=L2:L3=L2/L4:L6=L5/L7:BOTTOM=L7 |
| NIC0_MDI0_P0_R | LAN_RX5-DIFF1 | PAIR | 2 | 4 | 5 | 10 | 5 | 12 | 6 | 20 | 12 | 12 | 12 | 12 | 8 | 100 Ohms | TOP=L2:L3=L2/L4:L6=L5/L7:BOTTOM=L7 |
| NIC0_MDI0_P0_R | LAN_RX5-DIFF1 | PAIR | 3 | 4 | 5 | 10 | 5 | 12 | 6 | 20 | 12 | 12 | 12 | 12 | 8 | 100 Ohms | TOP=L2:L3=L2/L4:L6=L5/L7:BOTTOM=L7 |
| NIC0_MDI0_P0_R | LAN_RX5-DIFF1 | PAIR | 4 | 4 | 5 | 10 | 5 | 12 | 6 | 20 | 12 | 12 | 12 | 12 | 8 | 100 Ohms | TOP=L2:L3=L2/L4:L6=L5/L7:BOTTOM=L7 |
| NIC0_MDI0_P0_R | LAN_RX5-DIFF1 | PAIR | 5 | 4 | 5 | 10 | 5 | 12 | 6 | 20 | 12 | 12 | 12 | 12 | 8 | 100 Ohms | TOP=L2:L3=L2/L4:L6=L5/L7:BOTTOM=L7 |
| NIC0_MDI0_P0_R | LAN_RX5-DIFF1 | PAIR | 6 | 4 | 5 | 10 | 5 | 12 | 6 | 20 | 12 | 12 | 12 | 12 | 8 | 100 Ohms | TOP=L2:L3=L2/L4:L6=L5/L7:BOTTOM=L7 |
| NIC0_MDI0_P0_R | LAN_RX5-DIFF1 | PAIR | 7 | 4 | 5 | 10 | 5 | 12 | 6 | 20 | 12 | 12 | 12 | 12 | 8 | 100 Ohms | TOP=L2:L3=L2/L4:L6=L5/L7:BOTTOM=L7 |
| NIC0_MDI0_P0_R | LAN_RX5-DIFF1 | PAIR | 8 | 4.13 | 5 | 10 | 5 | 12 | 6 | 33 | 12 | 12 | 12 | 12 | 9.37 | 100 Ohms | TOP=L2:L3=L2/L4:L6=L5/L7:BOTTOM=L7 |
| NIC0_MDI0_N1_R | LAN_RX6-DIFF1 | PAIR | 1 | 4.13 | 5 | 10 | 5 | 12 | 6 | 33 | 12 | 12 | 12 | 12 | 9.37 | 100 Ohms | TOP=L2:L3=L2/L4:L6=L5/L7:BOTTOM=L7 |
| NIC0_MDI0_N1_R | LAN_RX6-DIFF1 | PAIR | 2 | 4 | 5 | 10 | 5 | 12 | 6 | 20 | 12 | 12 | 12 | 12 | 8 | 100 Ohms | TOP=L2:L3=L2/L4:L6=L5/L7:BOTTOM=L7 |
| NIC0_MDI0_N1_R | LAN_RX6-DIFF1 | PAIR | 3 | 4 | 5 | 10 | 5 | 12 | 6 | 20 | 12 | 12 | 12 | 12 | 8 | 100 Ohms | TOP=L2:L3=L2/L4:L6=L5/L7:BOTTOM=L7 |
| NIC0_MDI0_N1_R | LAN_RX6-DIFF1 | PAIR | 4 | 4 | 5 | 10 | 5 | 12 | 6 | 20 | 12 | 12 | 12 | 12 | 8 | 100 Ohms | TOP=L2:L3=L2/L4:L6=L5/L7:BOTTOM=L7 |
| NIC0_MDI0_N1_R | LAN_RX6-DIFF1 | PAIR | 5 | 4 | 5 | 10 | 5 | 12 | 6 | 20 | 12 | 12 | 12 | 12 | 8 | 100 Ohms | TOP=L2:L3=L2/L4:L6=L5/L7:BOTTOM=L7 |
| NIC0_MDI0_N1_R | LAN_RX6-DIFF1 | PAIR | 6 | 4 | 5 | 10 | 5 | 12 | 6 | 20 | 12 | 12 | 12 | 12 | 8 | 100 Ohms | TOP=L2:L3=L2/L4:L6=L5/L7:BOTTOM=L7 |
| NIC0_MDI0_N1_R | LAN_RX6-DIFF1 | PAIR | 7 | 4 | 5 | 10 | 5 | 12 | 6 | 20 | 12 | 12 | 12 | 12 | 8 | 100 Ohms | TOP=L2:L3=L2/L4:L6=L5/L7:BOTTOM=L7 |
| NIC0_MDI0_N1_R | LAN_RX6-DIFF1 | PAIR | 8 | 4.13 | 5 | 10 | 5 | 12 | 6 | 33 | 12 | 12 | 12 | 12 | 9.37 | 100 Ohms | TOP=L2:L3=L2/L4:L6=L5/L7:BOTTOM=L7 |
| NIC0_MDI0_P1_R | LAN_RX6-DIFF1 | PAIR | 1 | 4.13 | 5 | 10 | 5 | 12 | 6 | 33 | 12 | 12 | 12 | 12 | 9.37 | 100 Ohms | TOP=L2:L3=L2/L4:L6=L5/L7:BOTTOM=L7 |
| NIC0_MDI0_P1_R | LAN_RX6-DIFF1 | PAIR | 2 | 4 | 5 | 10 | 5 | 12 | 6 | 20 | 12 | 12 | 12 | 12 | 8 | 100 Ohms | TOP=L2:L3=L2/L4:L6=L5/L7:BOTTOM=L7 |
| NIC0_MDI0_P1_R | LAN_RX6-DIFF1 | PAIR | 3 | 4 | 5 | 10 | 5 | 12 | 6 | 20 | 12 | 12 | 12 | 12 | 8 | 100 Ohms | TOP=L2:L3=L2/L4:L6=L5/L7:BOTTOM=L7 |
| NIC0_MDI0_P1_R | LAN_RX6-DIFF1 | PAIR | 4 | 4 | 5 | 10 | 5 | 12 | 6 | 20 | 12 | 12 | 12 | 12 | 8 | 100 Ohms | TOP=L2:L3=L2/L4:L6=L5/L7:BOTTOM=L7 |
| NIC0_MDI0_P1_R | LAN_RX6-DIFF1 | PAIR | 5 | 4 | 5 | 10 | 5 | 12 | 6 | 20 | 12 | 12 | 12 | 12 | 8 | 100 Ohms | TOP=L2:L3=L2/L4:L6=L5/L7:BOTTOM=L7 |
| NIC0_MDI0_P1_R | LAN_RX6-DIFF1 | PAIR | 6 | 4 | 5 | 10 | 5 | 12 | 6 | 20 | 12 | 12 | 12 | 12 | 8 | 100 Ohms | TOP=L2:L3=L2/L4:L6=L5/L7:BOTTOM=L7 |
| NIC0_MDI0_P1_R | LAN_RX6-DIFF1 | PAIR | 7 | 4 | 5 | 10 | 5 | 12 | 6 | 20 | 12 | 12 | 12 | 12 | 8 | 100 Ohms | TOP=L2:L3=L2/L4:L6=L5/L7:BOTTOM=L7 |
| NIC0_MDI0_P1_R | LAN_RX6-DIFF1 | PAIR | 8 | 4.13 | 5 | 10 | 5 | 12 | 6 | 33 | 12 | 12 | 12 | 12 | 9.37 | 100 Ohms | TOP=L2:L3=L2/L4:L6=L5/L7:BOTTOM=L7 |
| NIC0_MDI0_N2_R | LAN_RX7-DIFF1 | PAIR | 1 | 4.13 | 5 | 10 | 5 | 12 | 6 | 33 | 12 | 12 | 12 | 12 | 9.37 | 100 Ohms | TOP=L2:L3=L2/L4:L6=L5/L7:BOTTOM=L7 |
| NIC0_MDI0_N2_R | LAN_RX7-DIFF1 | PAIR | 2 | 4 | 5 | 10 | 5 | 12 | 6 | 20 | 12 | 12 | 12 | 12 | 8 | 100 Ohms | TOP=L2:L3=L2/L4:L6=L5/L7:BOTTOM=L7 |
| NIC0_MDI0_N2_R | LAN_RX7-DIFF1 | PAIR | 3 | 4 | 5 | 10 | 5 | 12 | 6 | 20 | 12 | 12 | 12 | 12 | 8 | 100 Ohms | TOP=L2:L3=L2/L4:L6=L5/L7:BOTTOM=L7 |
| NIC0_MDI0_N2_R | LAN_RX7-DIFF1 | PAIR | 4 | 4 | 5 | 10 | 5 | 12 | 6 | 20 | 12 | 12 | 12 | 12 | 8 | 100 Ohms | TOP=L2:L3=L2/L4:L6=L5/L7:BOTTOM=L7 |
| NIC0_MDI0_N2_R | LAN_RX7-DIFF1 | PAIR | 5 | 4 | 5 | 10 | 5 | 12 | 6 | 20 | 12 | 12 | 12 | 12 | 8 | 100 Ohms | TOP=L2:L3=L2/L4:L6=L5/L7:BOTTOM=L7 |
| NIC0_MDI0_N2_R | LAN_RX7-DIFF1 | PAIR | 6 | 4 | 5 | 10 | 5 | 12 | 6 | 20 | 12 | 12 | 12 | 12 | 8 | 100 Ohms | TOP=L2:L3=L2/L4:L6=L5/L7:BOTTOM=L7 |
| NIC0_MDI0_N2_R | LAN_RX7-DIFF1 | PAIR | 7 | 4 | 5 | 10 | 5 | 12 | 6 | 20 | 12 | 12 | 12 | 12 | 8 | 100 Ohms | TOP=L2:L3=L2/L4:L6=L5/L7:BOTTOM=L7 |
| NIC0_MDI0_N2_R | LAN_RX7-DIFF1 | PAIR | 8 | 4.13 | 5 | 10 | 5 | 12 | 6 | 33 | 12 | 12 | 12 | 12 | 9.37 | 100 Ohms | TOP=L2:L3=L2/L4:L6=L5/L7:BOTTOM=L7 |
| NIC0_MDI0_P2_R | LAN_RX7-DIFF1 | PAIR | 1 | 4.13 | 5 | 10 | 5 | 12 | 6 | 33 | 12 | 12 | 12 | 12 | 9.37 | 100 Ohms | TOP=L2:L3=L2/L4:L6=L5/L7:BOTTOM=L7 |
| NIC0_MDI0_P2_R | LAN_RX7-DIFF1 | PAIR | 2 | 4 | 5 | 10 | 5 | 12 | 6 | 20 | 12 | 12 | 12 | 12 | 8 | 100 Ohms | TOP=L2:L3=L2/L4:L6=L5/L7:BOTTOM=L7 |
| NIC0_MDI0_P2_R | LAN_RX7-DIFF1 | PAIR | 3 | 4 | 5 | 10 | 5 | 12 | 6 | 20 | 12 | 12 | 12 | 12 | 8 | 100 Ohms | TOP=L2:L3=L2/L4:L6=L5/L7:BOTTOM=L7 |
| NIC0_MDI0_P2_R | LAN_RX7-DIFF1 | PAIR | 4 | 4 | 5 | 10 | 5 | 12 | 6 | 20 | 12 | 12 | 12 | 12 | 8 | 100 Ohms | TOP=L2:L3=L2/L4:L6=L5/L7:BOTTOM=L7 |
| NIC0_MDI0_P2_R | LAN_RX7-DIFF1 | PAIR | 5 | 4 | 5 | 10 | 5 | 12 | 6 | 20 | 12 | 12 | 12 | 12 | 8 | 100 Ohms | TOP=L2:L3=L2/L4:L6=L5/L7:BOTTOM=L7 |
| NIC0_MDI0_P2_R | LAN_RX7-DIFF1 | PAIR | 6 | 4 | 5 | 10 | 5 | 12 | 6 | 20 | 12 | 12 | 12 | 12 | 8 | 100 Ohms | TOP=L2:L3=L2/L4:L6=L5/L7:BOTTOM=L7 |
| NIC0_MDI0_P2_R | LAN_RX7-DIFF1 | PAIR | 7 | 4 | 5 | 10 | 5 | 12 | 6 | 20 | 12 | 12 | 12 | 12 | 8 | 100 Ohms | TOP=L2:L3=L2/L4:L6=L5/L7:BOTTOM=L7 |
| NIC0_MDI0_P2_R | LAN_RX7-DIFF1 | PAIR | 8 | 4.13 | 5 | 10 | 5 | 12 | 6 | 33 | 12 | 12 | 12 | 12 | 9.37 | 100 Ohms | TOP=L2:L3=L2/L4:L6=L5/L7:BOTTOM=L7 |
| NIC0_MDI0_N3_R | LAN_RX8-DIFF1 | PAIR | 1 | 4.13 | 5 | 10 | 5 | 12 | 6 | 33 | 12 | 12 | 12 | 12 | 9.37 | 100 Ohms | TOP=L2:L3=L2/L4:L6=L5/L7:BOTTOM=L7 |
| NIC0_MDI0_N3_R | LAN_RX8-DIFF1 | PAIR | 2 | 4 | 5 | 10 | 5 | 12 | 6 | 20 | 12 | 12 | 12 | 12 | 8 | 100 Ohms | TOP=L2:L3=L2/L4:L6=L5/L7:BOTTOM=L7 |
| NIC0_MDI0_N3_R | LAN_RX8-DIFF1 | PAIR | 3 | 4 | 5 | 10 | 5 | 12 | 6 | 20 | 12 | 12 | 12 | 12 | 8 | 100 Ohms | TOP=L2:L3=L2/L4:L6=L5/L7:BOTTOM=L7 |
| NIC0_MDI0_N3_R | LAN_RX8-DIFF1 | PAIR | 4 | 4 | 5 | 10 | 5 | 12 | 6 | 20 | 12 | 12 | 12 | 12 | 8 | 100 Ohms | TOP=L2:L3=L2/L4:L6=L5/L7:BOTTOM=L7 |
| NIC0_MDI0_N3_R | LAN_RX8-DIFF1 | PAIR | 5 | 4 | 5 | 10 | 5 | 12 | 6 | 20 | 12 | 12 | 12 | 12 | 8 | 100 Ohms | TOP=L2:L3=L2/L4:L6=L5/L7:BOTTOM=L7 |
| NIC0_MDI0_N3_R | LAN_RX8-DIFF1 | PAIR | 6 | 4 | 5 | 10 | 5 | 12 | 6 | 20 | 12 | 12 | 12 | 12 | 8 | 100 Ohms | TOP=L2:L3=L2/L4:L6=L5/L7:BOTTOM=L7 |
| NIC0_MDI0_N3_R | LAN_RX8-DIFF1 | PAIR | 7 | 4 | 5 | 10 | 5 | 12 | 6 | 20 | 12 | 12 | 12 | 12 | 8 | 100 Ohms | TOP=L2:L3=L2/L4:L6=L5/L7:BOTTOM=L7 |
| NIC0_MDI0_N3_R | LAN_RX8-DIFF1 | PAIR | 8 | 4.13 | 5 | 10 | 5 | 12 | 6 | 33 | 12 | 12 | 12 | 12 | 9.37 | 100 Ohms | TOP=L2:L3=L2/L4:L6=L5/L7:BOTTOM=L7 |
| NIC0_MDI0_P3_R | LAN_RX8-DIFF1 | PAIR | 1 | 4.13 | 5 | 10 | 5 | 12 | 6 | 33 | 12 | 12 | 12 | 12 | 9.37 | 100 Ohms | TOP=L2:L3=L2/L4:L6=L5/L7:BOTTOM=L7 |
| NIC0_MDI0_P3_R | LAN_RX8-DIFF1 | PAIR | 2 | 4 | 5 | 10 | 5 | 12 | 6 | 20 | 12 | 12 | 12 | 12 | 8 | 100 Ohms | TOP=L2:L3=L2/L4:L6=L5/L7:BOTTOM=L7 |
| NIC0_MDI0_P3_R | LAN_RX8-DIFF1 | PAIR | 3 | 4 | 5 | 10 | 5 | 12 | 6 | 20 | 12 | 12 | 12 | 12 | 8 | 100 Ohms | TOP=L2:L3=L2/L4:L6=L5/L7:BOTTOM=L7 |
| NIC0_MDI0_P3_R | LAN_RX8-DIFF1 | PAIR | 4 | 4 | 5 | 10 | 5 | 12 | 6 | 20 | 12 | 12 | 12 | 12 | 8 | 100 Ohms | TOP=L2:L3=L2/L4:L6=L5/L7:BOTTOM=L7 |
| NIC0_MDI0_P3_R | LAN_RX8-DIFF1 | PAIR | 5 | 4 | 5 | 10 | 5 | 12 | 6 | 20 | 12 | 12 | 12 | 12 | 8 | 100 Ohms | TOP=L2:L3=L2/L4:L6=L5/L7:BOTTOM=L7 |
| NIC0_MDI0_P3_R | LAN_RX8-DIFF1 | PAIR | 6 | 4 | 5 | 10 | 5 | 12 | 6 | 20 | 12 | 12 | 12 | 12 | 8 | 100 Ohms | TOP=L2:L3=L2/L4:L6=L5/L7:BOTTOM=L7 |
| NIC0_MDI0_P3_R | LAN_RX8-DIFF1 | PAIR | 7 | 4 | 5 | 10 | 5 | 12 | 6 | 20 | 12 | 12 | 12 | 12 | 8 | 100 Ohms | TOP=L2:L3=L2/L4:L6=L5/L7:BOTTOM=L7 |
| NIC0_MDI0_P3_R | LAN_RX8-DIFF1 | PAIR | 8 | 4.13 | 5 | 10 | 5 | 12 | 6 | 33 | 12 | 12 | 12 | 12 | 9.37 | 100 Ohms | TOP=L2:L3=L2/L4:L6=L5/L7:BOTTOM=L7 |
| MNG_RX_DN | LAN_RX9-DIFF1 | PAIR | 1 | 4.13 | 5 | 10 | 5 | 12 | 6 | 33 | 12 | 12 | 12 | 12 | 9.37 | 100 Ohms | TOP=L2:L3=L2/L4:L6=L5/L7:BOTTOM=L7 |
| MNG_RX_DN | LAN_RX9-DIFF1 | PAIR | 2 | 4 | 5 | 10 | 5 | 12 | 6 | 20 | 12 | 12 | 12 | 12 | 8 | 100 Ohms | TOP=L2:L3=L2/L4:L6=L5/L7:BOTTOM=L7 |
| MNG_RX_DN | LAN_RX9-DIFF1 | PAIR | 3 | 4 | 5 | 10 | 5 | 12 | 6 | 20 | 12 | 12 | 12 | 12 | 8 | 100 Ohms | TOP=L2:L3=L2/L4:L6=L5/L7:BOTTOM=L7 |
| MNG_RX_DN | LAN_RX9-DIFF1 | PAIR | 4 | 4 | 5 | 10 | 5 | 12 | 6 | 20 | 12 | 12 | 12 | 12 | 8 | 100 Ohms | TOP=L2:L3=L2/L4:L6=L5/L7:BOTTOM=L7 |
| MNG_RX_DN | LAN_RX9-DIFF1 | PAIR | 5 | 4 | 5 | 10 | 5 | 12 | 6 | 20 | 12 | 12 | 12 | 12 | 8 | 100 Ohms | TOP=L2:L3=L2/L4:L6=L5/L7:BOTTOM=L7 |
| MNG_RX_DN | LAN_RX9-DIFF1 | PAIR | 6 | 4 | 5 | 10 | 5 | 12 | 6 | 20 | 12 | 12 | 12 | 12 | 8 | 100 Ohms | TOP=L2:L3=L2/L4:L6=L5/L7:BOTTOM=L7 |
| MNG_RX_DN | LAN_RX9-DIFF1 | PAIR | 7 | 4 | 5 | 10 | 5 | 12 | 6 | 20 | 12 | 12 | 12 | 12 | 8 | 100 Ohms | TOP=L2:L3=L2/L4:L6=L5/L7:BOTTOM=L7 |
| MNG_RX_DN | LAN_RX9-DIFF1 | PAIR | 8 | 4.13 | 5 | 10 | 5 | 12 | 6 | 33 | 12 | 12 | 12 | 12 | 9.37 | 100 Ohms | TOP=L2:L3=L2/L4:L6=L5/L7:BOTTOM=L7 |
| MNG_RX_DP | LAN_RX9-DIFF1 | PAIR | 1 | 4.13 | 5 | 10 | 5 | 12 | 6 | 33 | 12 | 12 | 12 | 12 | 9.37 | 100 Ohms | TOP=L2:L3=L2/L4:L6=L5/L7:BOTTOM=L7 |
| MNG_RX_DP | LAN_RX9-DIFF1 | PAIR | 2 | 4 | 5 | 10 | 5 | 12 | 6 | 20 | 12 | 12 | 12 | 12 | 8 | 100 Ohms | TOP=L2:L3=L2/L4:L6=L5/L7:BOTTOM=L7 |
| MNG_RX_DP | LAN_RX9-DIFF1 | PAIR | 3 | 4 | 5 | 10 | 5 | 12 | 6 | 20 | 12 | 12 | 12 | 12 | 8 | 100 Ohms | TOP=L2:L3=L2/L4:L6=L5/L7:BOTTOM=L7 |
| MNG_RX_DP | LAN_RX9-DIFF1 | PAIR | 4 | 4 | 5 | 10 | 5 | 12 | 6 | 20 | 12 | 12 | 12 | 12 | 8 | 100 Ohms | TOP=L2:L3=L2/L4:L6=L5/L7:BOTTOM=L7 |
| MNG_RX_DP | LAN_RX9-DIFF1 | PAIR | 5 | 4 | 5 | 10 | 5 | 12 | 6 | 20 | 12 | 12 | 12 | 12 | 8 | 100 Ohms | TOP=L2:L3=L2/L4:L6=L5/L7:BOTTOM=L7 |
| MNG_RX_DP | LAN_RX9-DIFF1 | PAIR | 6 | 4 | 5 | 10 | 5 | 12 | 6 | 20 | 12 | 12 | 12 | 12 | 8 | 100 Ohms | TOP=L2:L3=L2/L4:L6=L5/L7:BOTTOM=L7 |
| MNG_RX_DP | LAN_RX9-DIFF1 | PAIR | 7 | 4 | 5 | 10 | 5 | 12 | 6 | 20 | 12 | 12 | 12 | 12 | 8 | 100 Ohms | TOP=L2:L3=L2/L4:L6=L5/L7:BOTTOM=L7 |
| MNG_RX_DP | LAN_RX9-DIFF1 | PAIR | 8 | 4.13 | 5 | 10 | 5 | 12 | 6 | 33 | 12 | 12 | 12 | 12 | 9.37 | 100 Ohms | TOP=L2:L3=L2/L4:L6=L5/L7:BOTTOM=L7 |
| MEMCK_N | MEM01-DIFF1 | PAIR | 1 | 5.38 | 5 | 10 | 5 | 50 | 6 | 20 | 12 | 12 | 12 | 12 | 6.62 |  |  |
| MEMCK_N | MEM01-DIFF1 | PAIR | 2 | 5.5 | 5 | 10 | 5 | 50 | 6 | 12 | 12 | 12 | 12 | 12 | 7.5 |  |  |
| MEMCK_N | MEM01-DIFF1 | PAIR | 3 | 5.5 | 5 | 10 | 5 | 50 | 6 | 12 | 12 | 12 | 12 | 12 | 7.5 |  |  |
| MEMCK_N | MEM01-DIFF1 | PAIR | 4 | 5.5 | 5 | 10 | 5 | 50 | 6 | 12 | 12 | 12 | 12 | 12 | 7.5 |  |  |
| MEMCK_N | MEM01-DIFF1 | PAIR | 5 | 5.5 | 5 | 10 | 5 | 50 | 6 | 12 | 12 | 12 | 12 | 12 | 7.5 |  |  |
| MEMCK_N | MEM01-DIFF1 | PAIR | 6 | 5.5 | 5 | 10 | 5 | 50 | 6 | 12 | 12 | 12 | 12 | 12 | 7.5 |  |  |
| MEMCK_N | MEM01-DIFF1 | PAIR | 7 | 5.5 | 5 | 10 | 5 | 50 | 6 | 12 | 12 | 12 | 12 | 12 | 7.5 |  |  |
| MEMCK_N | MEM01-DIFF1 | PAIR | 8 | 5.38 | 5 | 10 | 5 | 50 | 6 | 20 | 12 | 12 | 12 | 12 | 6.62 |  |  |
| MEMCK_P | MEM01-DIFF1 | PAIR | 1 | 5.38 | 5 | 10 | 5 | 50 | 6 | 20 | 12 | 12 | 12 | 12 | 6.62 |  |  |
| MEMCK_P | MEM01-DIFF1 | PAIR | 2 | 5.5 | 5 | 10 | 5 | 50 | 6 | 12 | 12 | 12 | 12 | 12 | 7.5 |  |  |
| MEMCK_P | MEM01-DIFF1 | PAIR | 3 | 5.5 | 5 | 10 | 5 | 50 | 6 | 12 | 12 | 12 | 12 | 12 | 7.5 |  |  |
| MEMCK_P | MEM01-DIFF1 | PAIR | 4 | 5.5 | 5 | 10 | 5 | 50 | 6 | 12 | 12 | 12 | 12 | 12 | 7.5 |  |  |
| MEMCK_P | MEM01-DIFF1 | PAIR | 5 | 5.5 | 5 | 10 | 5 | 50 | 6 | 12 | 12 | 12 | 12 | 12 | 7.5 |  |  |
| MEMCK_P | MEM01-DIFF1 | PAIR | 6 | 5.5 | 5 | 10 | 5 | 50 | 6 | 12 | 12 | 12 | 12 | 12 | 7.5 |  |  |
| MEMCK_P | MEM01-DIFF1 | PAIR | 7 | 5.5 | 5 | 10 | 5 | 50 | 6 | 12 | 12 | 12 | 12 | 12 | 7.5 |  |  |
| MEMCK_P | MEM01-DIFF1 | PAIR | 8 | 5.38 | 5 | 10 | 5 | 50 | 6 | 20 | 12 | 12 | 12 | 12 | 6.62 |  |  |
| MEMDQS_N0 | MEM02-DIFF1 | PAIR | 1 | 5.38 | 5 | 10 | 5 | 50 | 6 | 20 | 12 | 12 | 12 | 12 | 6.62 |  |  |
| MEMDQS_N0 | MEM02-DIFF1 | PAIR | 2 | 5.5 | 5 | 10 | 5 | 50 | 6 | 12 | 12 | 12 | 12 | 12 | 7.5 |  |  |
| MEMDQS_N0 | MEM02-DIFF1 | PAIR | 3 | 5.5 | 5 | 10 | 5 | 50 | 6 | 12 | 12 | 12 | 12 | 12 | 7.5 |  |  |
| MEMDQS_N0 | MEM02-DIFF1 | PAIR | 4 | 5.5 | 5 | 10 | 5 | 50 | 6 | 12 | 12 | 12 | 12 | 12 | 7.5 |  |  |
| MEMDQS_N0 | MEM02-DIFF1 | PAIR | 5 | 5.5 | 5 | 10 | 5 | 50 | 6 | 12 | 12 | 12 | 12 | 12 | 7.5 |  |  |
| MEMDQS_N0 | MEM02-DIFF1 | PAIR | 6 | 5.5 | 5 | 10 | 5 | 50 | 6 | 12 | 12 | 12 | 12 | 12 | 7.5 |  |  |
| MEMDQS_N0 | MEM02-DIFF1 | PAIR | 7 | 5.5 | 5 | 10 | 5 | 50 | 6 | 12 | 12 | 12 | 12 | 12 | 7.5 |  |  |
| MEMDQS_N0 | MEM02-DIFF1 | PAIR | 8 | 5.38 | 5 | 10 | 5 | 50 | 6 | 20 | 12 | 12 | 12 | 12 | 6.62 |  |  |
| MEMDQS_P0 | MEM02-DIFF1 | PAIR | 1 | 5.38 | 5 | 10 | 5 | 50 | 6 | 20 | 12 | 12 | 12 | 12 | 6.62 |  |  |
| MEMDQS_P0 | MEM02-DIFF1 | PAIR | 2 | 5.5 | 5 | 10 | 5 | 50 | 6 | 12 | 12 | 12 | 12 | 12 | 7.5 |  |  |
| MEMDQS_P0 | MEM02-DIFF1 | PAIR | 3 | 5.5 | 5 | 10 | 5 | 50 | 6 | 12 | 12 | 12 | 12 | 12 | 7.5 |  |  |
| MEMDQS_P0 | MEM02-DIFF1 | PAIR | 4 | 5.5 | 5 | 10 | 5 | 50 | 6 | 12 | 12 | 12 | 12 | 12 | 7.5 |  |  |
| MEMDQS_P0 | MEM02-DIFF1 | PAIR | 5 | 5.5 | 5 | 10 | 5 | 50 | 6 | 12 | 12 | 12 | 12 | 12 | 7.5 |  |  |
| MEMDQS_P0 | MEM02-DIFF1 | PAIR | 6 | 5.5 | 5 | 10 | 5 | 50 | 6 | 12 | 12 | 12 | 12 | 12 | 7.5 |  |  |
| MEMDQS_P0 | MEM02-DIFF1 | PAIR | 7 | 5.5 | 5 | 10 | 5 | 50 | 6 | 12 | 12 | 12 | 12 | 12 | 7.5 |  |  |
| MEMDQS_P0 | MEM02-DIFF1 | PAIR | 8 | 5.38 | 5 | 10 | 5 | 50 | 6 | 20 | 12 | 12 | 12 | 12 | 6.62 |  |  |
| MEMDQS_N1 | MEM03-DIFF1 | PAIR | 1 | 5.38 | 5 | 10 | 5 | 50 | 6 | 20 | 12 | 12 | 12 | 12 | 6.62 |  |  |
| MEMDQS_N1 | MEM03-DIFF1 | PAIR | 2 | 5.5 | 5 | 10 | 5 | 50 | 6 | 12 | 12 | 12 | 12 | 12 | 7.5 |  |  |
| MEMDQS_N1 | MEM03-DIFF1 | PAIR | 3 | 5.5 | 5 | 10 | 5 | 50 | 6 | 12 | 12 | 12 | 12 | 12 | 7.5 |  |  |
| MEMDQS_N1 | MEM03-DIFF1 | PAIR | 4 | 5.5 | 5 | 10 | 5 | 50 | 6 | 12 | 12 | 12 | 12 | 12 | 7.5 |  |  |
| MEMDQS_N1 | MEM03-DIFF1 | PAIR | 5 | 5.5 | 5 | 10 | 5 | 50 | 6 | 12 | 12 | 12 | 12 | 12 | 7.5 |  |  |
| MEMDQS_N1 | MEM03-DIFF1 | PAIR | 6 | 5.5 | 5 | 10 | 5 | 50 | 6 | 12 | 12 | 12 | 12 | 12 | 7.5 |  |  |
| MEMDQS_N1 | MEM03-DIFF1 | PAIR | 7 | 5.5 | 5 | 10 | 5 | 50 | 6 | 12 | 12 | 12 | 12 | 12 | 7.5 |  |  |
| MEMDQS_N1 | MEM03-DIFF1 | PAIR | 8 | 5.38 | 5 | 10 | 5 | 50 | 6 | 20 | 12 | 12 | 12 | 12 | 6.62 |  |  |
| MEMDQS_P1 | MEM03-DIFF1 | PAIR | 1 | 5.38 | 5 | 10 | 5 | 50 | 6 | 20 | 12 | 12 | 12 | 12 | 6.62 |  |  |
| MEMDQS_P1 | MEM03-DIFF1 | PAIR | 2 | 5.5 | 5 | 10 | 5 | 50 | 6 | 12 | 12 | 12 | 12 | 12 | 7.5 |  |  |
| MEMDQS_P1 | MEM03-DIFF1 | PAIR | 3 | 5.5 | 5 | 10 | 5 | 50 | 6 | 12 | 12 | 12 | 12 | 12 | 7.5 |  |  |
| MEMDQS_P1 | MEM03-DIFF1 | PAIR | 4 | 5.5 | 5 | 10 | 5 | 50 | 6 | 12 | 12 | 12 | 12 | 12 | 7.5 |  |  |
| MEMDQS_P1 | MEM03-DIFF1 | PAIR | 5 | 5.5 | 5 | 10 | 5 | 50 | 6 | 12 | 12 | 12 | 12 | 12 | 7.5 |  |  |
| MEMDQS_P1 | MEM03-DIFF1 | PAIR | 6 | 5.5 | 5 | 10 | 5 | 50 | 6 | 12 | 12 | 12 | 12 | 12 | 7.5 |  |  |
| MEMDQS_P1 | MEM03-DIFF1 | PAIR | 7 | 5.5 | 5 | 10 | 5 | 50 | 6 | 12 | 12 | 12 | 12 | 12 | 7.5 |  |  |
| MEMDQS_P1 | MEM03-DIFF1 | PAIR | 8 | 5.38 | 5 | 10 | 5 | 50 | 6 | 20 | 12 | 12 | 12 | 12 | 6.62 |  |  |
| PCIE_RX_N0 | RXS0-DIFF1 | PAIR | 1 | 5.38 | 5 | 10 | 5 | 50 | 6 | 33 | 12 | 12 | 12 | 12 | 6.62 | 85 Ohms | TOP=L2:L3=L2/L4:L6=L5/L7:BOTTOM=L7 |
| PCIE_RX_N0 | RXS0-DIFF1 | PAIR | 2 | 5.5 | 5 | 10 | 5 | 50 | 6 | 20 | 12 | 12 | 12 | 12 | 7.5 | 85 Ohms | TOP=L2:L3=L2/L4:L6=L5/L7:BOTTOM=L7 |
| PCIE_RX_N0 | RXS0-DIFF1 | PAIR | 3 | 5.5 | 5 | 10 | 5 | 50 | 6 | 20 | 12 | 12 | 12 | 12 | 7.5 | 85 Ohms | TOP=L2:L3=L2/L4:L6=L5/L7:BOTTOM=L7 |
| PCIE_RX_N0 | RXS0-DIFF1 | PAIR | 4 | 5.5 | 5 | 10 | 5 | 50 | 6 | 20 | 12 | 12 | 12 | 12 | 7.5 | 85 Ohms | TOP=L2:L3=L2/L4:L6=L5/L7:BOTTOM=L7 |
| PCIE_RX_N0 | RXS0-DIFF1 | PAIR | 5 | 5.5 | 5 | 10 | 5 | 50 | 6 | 20 | 12 | 12 | 12 | 12 | 7.5 | 85 Ohms | TOP=L2:L3=L2/L4:L6=L5/L7:BOTTOM=L7 |
| PCIE_RX_N0 | RXS0-DIFF1 | PAIR | 6 | 5.5 | 5 | 10 | 5 | 50 | 6 | 20 | 12 | 12 | 12 | 12 | 7.5 | 85 Ohms | TOP=L2:L3=L2/L4:L6=L5/L7:BOTTOM=L7 |
| PCIE_RX_N0 | RXS0-DIFF1 | PAIR | 7 | 5.5 | 5 | 10 | 5 | 50 | 6 | 20 | 12 | 12 | 12 | 12 | 7.5 | 85 Ohms | TOP=L2:L3=L2/L4:L6=L5/L7:BOTTOM=L7 |
| PCIE_RX_N0 | RXS0-DIFF1 | PAIR | 8 | 5.38 | 5 | 10 | 5 | 50 | 6 | 33 | 12 | 12 | 12 | 12 | 6.62 | 85 Ohms | TOP=L2:L3=L2/L4:L6=L5/L7:BOTTOM=L7 |
| PCIE_RX_P0 | RXS0-DIFF1 | PAIR | 1 | 5.38 | 5 | 10 | 5 | 50 | 6 | 33 | 12 | 12 | 12 | 12 | 6.62 | 85 Ohms | TOP=L2:L3=L2/L4:L6=L5/L7:BOTTOM=L7 |
| PCIE_RX_P0 | RXS0-DIFF1 | PAIR | 2 | 5.5 | 5 | 10 | 5 | 50 | 6 | 20 | 12 | 12 | 12 | 12 | 7.5 | 85 Ohms | TOP=L2:L3=L2/L4:L6=L5/L7:BOTTOM=L7 |
| PCIE_RX_P0 | RXS0-DIFF1 | PAIR | 3 | 5.5 | 5 | 10 | 5 | 50 | 6 | 20 | 12 | 12 | 12 | 12 | 7.5 | 85 Ohms | TOP=L2:L3=L2/L4:L6=L5/L7:BOTTOM=L7 |
| PCIE_RX_P0 | RXS0-DIFF1 | PAIR | 4 | 5.5 | 5 | 10 | 5 | 50 | 6 | 20 | 12 | 12 | 12 | 12 | 7.5 | 85 Ohms | TOP=L2:L3=L2/L4:L6=L5/L7:BOTTOM=L7 |
| PCIE_RX_P0 | RXS0-DIFF1 | PAIR | 5 | 5.5 | 5 | 10 | 5 | 50 | 6 | 20 | 12 | 12 | 12 | 12 | 7.5 | 85 Ohms | TOP=L2:L3=L2/L4:L6=L5/L7:BOTTOM=L7 |
| PCIE_RX_P0 | RXS0-DIFF1 | PAIR | 6 | 5.5 | 5 | 10 | 5 | 50 | 6 | 20 | 12 | 12 | 12 | 12 | 7.5 | 85 Ohms | TOP=L2:L3=L2/L4:L6=L5/L7:BOTTOM=L7 |
| PCIE_RX_P0 | RXS0-DIFF1 | PAIR | 7 | 5.5 | 5 | 10 | 5 | 50 | 6 | 20 | 12 | 12 | 12 | 12 | 7.5 | 85 Ohms | TOP=L2:L3=L2/L4:L6=L5/L7:BOTTOM=L7 |
| PCIE_RX_P0 | RXS0-DIFF1 | PAIR | 8 | 5.38 | 5 | 10 | 5 | 50 | 6 | 33 | 12 | 12 | 12 | 12 | 6.62 | 85 Ohms | TOP=L2:L3=L2/L4:L6=L5/L7:BOTTOM=L7 |
| PCIE_RX_N10 | RXS10-DIFF1 | PAIR | 1 | 5.38 | 5 | 10 | 5 | 50 | 6 | 33 | 12 | 12 | 12 | 12 | 6.62 | 85 Ohms | TOP=L2:L3=L2/L4:L6=L5/L7:BOTTOM=L7 |
| PCIE_RX_N10 | RXS10-DIFF1 | PAIR | 2 | 5.5 | 5 | 10 | 5 | 50 | 6 | 20 | 12 | 12 | 12 | 12 | 7.5 | 85 Ohms | TOP=L2:L3=L2/L4:L6=L5/L7:BOTTOM=L7 |
| PCIE_RX_N10 | RXS10-DIFF1 | PAIR | 3 | 5.5 | 5 | 10 | 5 | 50 | 6 | 20 | 12 | 12 | 12 | 12 | 7.5 | 85 Ohms | TOP=L2:L3=L2/L4:L6=L5/L7:BOTTOM=L7 |
| PCIE_RX_N10 | RXS10-DIFF1 | PAIR | 4 | 5.5 | 5 | 10 | 5 | 50 | 6 | 20 | 12 | 12 | 12 | 12 | 7.5 | 85 Ohms | TOP=L2:L3=L2/L4:L6=L5/L7:BOTTOM=L7 |
| PCIE_RX_N10 | RXS10-DIFF1 | PAIR | 5 | 5.5 | 5 | 10 | 5 | 50 | 6 | 20 | 12 | 12 | 12 | 12 | 7.5 | 85 Ohms | TOP=L2:L3=L2/L4:L6=L5/L7:BOTTOM=L7 |
| PCIE_RX_N10 | RXS10-DIFF1 | PAIR | 6 | 5.5 | 5 | 10 | 5 | 50 | 6 | 20 | 12 | 12 | 12 | 12 | 7.5 | 85 Ohms | TOP=L2:L3=L2/L4:L6=L5/L7:BOTTOM=L7 |
| PCIE_RX_N10 | RXS10-DIFF1 | PAIR | 7 | 5.5 | 5 | 10 | 5 | 50 | 6 | 20 | 12 | 12 | 12 | 12 | 7.5 | 85 Ohms | TOP=L2:L3=L2/L4:L6=L5/L7:BOTTOM=L7 |
| PCIE_RX_N10 | RXS10-DIFF1 | PAIR | 8 | 5.38 | 5 | 10 | 5 | 50 | 6 | 33 | 12 | 12 | 12 | 12 | 6.62 | 85 Ohms | TOP=L2:L3=L2/L4:L6=L5/L7:BOTTOM=L7 |
| PCIE_RX_P10 | RXS10-DIFF1 | PAIR | 1 | 5.38 | 5 | 10 | 5 | 50 | 6 | 33 | 12 | 12 | 12 | 12 | 6.62 | 85 Ohms | TOP=L2:L3=L2/L4:L6=L5/L7:BOTTOM=L7 |
| PCIE_RX_P10 | RXS10-DIFF1 | PAIR | 2 | 5.5 | 5 | 10 | 5 | 50 | 6 | 20 | 12 | 12 | 12 | 12 | 7.5 | 85 Ohms | TOP=L2:L3=L2/L4:L6=L5/L7:BOTTOM=L7 |
| PCIE_RX_P10 | RXS10-DIFF1 | PAIR | 3 | 5.5 | 5 | 10 | 5 | 50 | 6 | 20 | 12 | 12 | 12 | 12 | 7.5 | 85 Ohms | TOP=L2:L3=L2/L4:L6=L5/L7:BOTTOM=L7 |
| PCIE_RX_P10 | RXS10-DIFF1 | PAIR | 4 | 5.5 | 5 | 10 | 5 | 50 | 6 | 20 | 12 | 12 | 12 | 12 | 7.5 | 85 Ohms | TOP=L2:L3=L2/L4:L6=L5/L7:BOTTOM=L7 |
| PCIE_RX_P10 | RXS10-DIFF1 | PAIR | 5 | 5.5 | 5 | 10 | 5 | 50 | 6 | 20 | 12 | 12 | 12 | 12 | 7.5 | 85 Ohms | TOP=L2:L3=L2/L4:L6=L5/L7:BOTTOM=L7 |
| PCIE_RX_P10 | RXS10-DIFF1 | PAIR | 6 | 5.5 | 5 | 10 | 5 | 50 | 6 | 20 | 12 | 12 | 12 | 12 | 7.5 | 85 Ohms | TOP=L2:L3=L2/L4:L6=L5/L7:BOTTOM=L7 |
| PCIE_RX_P10 | RXS10-DIFF1 | PAIR | 7 | 5.5 | 5 | 10 | 5 | 50 | 6 | 20 | 12 | 12 | 12 | 12 | 7.5 | 85 Ohms | TOP=L2:L3=L2/L4:L6=L5/L7:BOTTOM=L7 |
| PCIE_RX_P10 | RXS10-DIFF1 | PAIR | 8 | 5.38 | 5 | 10 | 5 | 50 | 6 | 33 | 12 | 12 | 12 | 12 | 6.62 | 85 Ohms | TOP=L2:L3=L2/L4:L6=L5/L7:BOTTOM=L7 |
| PCIE_RX_N11 | RXS11-DIFF1 | PAIR | 1 | 5.38 | 5 | 10 | 5 | 50 | 6 | 33 | 12 | 12 | 12 | 12 | 6.62 | 85 Ohms | TOP=L2:L3=L2/L4:L6=L5/L7:BOTTOM=L7 |
| PCIE_RX_N11 | RXS11-DIFF1 | PAIR | 2 | 5.5 | 5 | 10 | 5 | 50 | 6 | 20 | 12 | 12 | 12 | 12 | 7.5 | 85 Ohms | TOP=L2:L3=L2/L4:L6=L5/L7:BOTTOM=L7 |
| PCIE_RX_N11 | RXS11-DIFF1 | PAIR | 3 | 5.5 | 5 | 10 | 5 | 50 | 6 | 20 | 12 | 12 | 12 | 12 | 7.5 | 85 Ohms | TOP=L2:L3=L2/L4:L6=L5/L7:BOTTOM=L7 |
| PCIE_RX_N11 | RXS11-DIFF1 | PAIR | 4 | 5.5 | 5 | 10 | 5 | 50 | 6 | 20 | 12 | 12 | 12 | 12 | 7.5 | 85 Ohms | TOP=L2:L3=L2/L4:L6=L5/L7:BOTTOM=L7 |
| PCIE_RX_N11 | RXS11-DIFF1 | PAIR | 5 | 5.5 | 5 | 10 | 5 | 50 | 6 | 20 | 12 | 12 | 12 | 12 | 7.5 | 85 Ohms | TOP=L2:L3=L2/L4:L6=L5/L7:BOTTOM=L7 |
| PCIE_RX_N11 | RXS11-DIFF1 | PAIR | 6 | 5.5 | 5 | 10 | 5 | 50 | 6 | 20 | 12 | 12 | 12 | 12 | 7.5 | 85 Ohms | TOP=L2:L3=L2/L4:L6=L5/L7:BOTTOM=L7 |
| PCIE_RX_N11 | RXS11-DIFF1 | PAIR | 7 | 5.5 | 5 | 10 | 5 | 50 | 6 | 20 | 12 | 12 | 12 | 12 | 7.5 | 85 Ohms | TOP=L2:L3=L2/L4:L6=L5/L7:BOTTOM=L7 |
| PCIE_RX_N11 | RXS11-DIFF1 | PAIR | 8 | 5.38 | 5 | 10 | 5 | 50 | 6 | 33 | 12 | 12 | 12 | 12 | 6.62 | 85 Ohms | TOP=L2:L3=L2/L4:L6=L5/L7:BOTTOM=L7 |
| PCIE_RX_P11 | RXS11-DIFF1 | PAIR | 1 | 5.38 | 5 | 10 | 5 | 50 | 6 | 33 | 12 | 12 | 12 | 12 | 6.62 | 85 Ohms | TOP=L2:L3=L2/L4:L6=L5/L7:BOTTOM=L7 |
| PCIE_RX_P11 | RXS11-DIFF1 | PAIR | 2 | 5.5 | 5 | 10 | 5 | 50 | 6 | 20 | 12 | 12 | 12 | 12 | 7.5 | 85 Ohms | TOP=L2:L3=L2/L4:L6=L5/L7:BOTTOM=L7 |
| PCIE_RX_P11 | RXS11-DIFF1 | PAIR | 3 | 5.5 | 5 | 10 | 5 | 50 | 6 | 20 | 12 | 12 | 12 | 12 | 7.5 | 85 Ohms | TOP=L2:L3=L2/L4:L6=L5/L7:BOTTOM=L7 |
| PCIE_RX_P11 | RXS11-DIFF1 | PAIR | 4 | 5.5 | 5 | 10 | 5 | 50 | 6 | 20 | 12 | 12 | 12 | 12 | 7.5 | 85 Ohms | TOP=L2:L3=L2/L4:L6=L5/L7:BOTTOM=L7 |
| PCIE_RX_P11 | RXS11-DIFF1 | PAIR | 5 | 5.5 | 5 | 10 | 5 | 50 | 6 | 20 | 12 | 12 | 12 | 12 | 7.5 | 85 Ohms | TOP=L2:L3=L2/L4:L6=L5/L7:BOTTOM=L7 |
| PCIE_RX_P11 | RXS11-DIFF1 | PAIR | 6 | 5.5 | 5 | 10 | 5 | 50 | 6 | 20 | 12 | 12 | 12 | 12 | 7.5 | 85 Ohms | TOP=L2:L3=L2/L4:L6=L5/L7:BOTTOM=L7 |
| PCIE_RX_P11 | RXS11-DIFF1 | PAIR | 7 | 5.5 | 5 | 10 | 5 | 50 | 6 | 20 | 12 | 12 | 12 | 12 | 7.5 | 85 Ohms | TOP=L2:L3=L2/L4:L6=L5/L7:BOTTOM=L7 |
| PCIE_RX_P11 | RXS11-DIFF1 | PAIR | 8 | 5.38 | 5 | 10 | 5 | 50 | 6 | 33 | 12 | 12 | 12 | 12 | 6.62 | 85 Ohms | TOP=L2:L3=L2/L4:L6=L5/L7:BOTTOM=L7 |
| PCIE_RX_N12 | RXS12-DIFF1 | PAIR | 1 | 5.38 | 5 | 10 | 5 | 50 | 6 | 33 | 12 | 12 | 12 | 12 | 6.62 | 85 Ohms | TOP=L2:L3=L2/L4:L6=L5/L7:BOTTOM=L7 |
| PCIE_RX_N12 | RXS12-DIFF1 | PAIR | 2 | 5.5 | 5 | 10 | 5 | 50 | 6 | 20 | 12 | 12 | 12 | 12 | 7.5 | 85 Ohms | TOP=L2:L3=L2/L4:L6=L5/L7:BOTTOM=L7 |
| PCIE_RX_N12 | RXS12-DIFF1 | PAIR | 3 | 5.5 | 5 | 10 | 5 | 50 | 6 | 20 | 12 | 12 | 12 | 12 | 7.5 | 85 Ohms | TOP=L2:L3=L2/L4:L6=L5/L7:BOTTOM=L7 |
| PCIE_RX_N12 | RXS12-DIFF1 | PAIR | 4 | 5.5 | 5 | 10 | 5 | 50 | 6 | 20 | 12 | 12 | 12 | 12 | 7.5 | 85 Ohms | TOP=L2:L3=L2/L4:L6=L5/L7:BOTTOM=L7 |
| PCIE_RX_N12 | RXS12-DIFF1 | PAIR | 5 | 5.5 | 5 | 10 | 5 | 50 | 6 | 20 | 12 | 12 | 12 | 12 | 7.5 | 85 Ohms | TOP=L2:L3=L2/L4:L6=L5/L7:BOTTOM=L7 |
| PCIE_RX_N12 | RXS12-DIFF1 | PAIR | 6 | 5.5 | 5 | 10 | 5 | 50 | 6 | 20 | 12 | 12 | 12 | 12 | 7.5 | 85 Ohms | TOP=L2:L3=L2/L4:L6=L5/L7:BOTTOM=L7 |
| PCIE_RX_N12 | RXS12-DIFF1 | PAIR | 7 | 5.5 | 5 | 10 | 5 | 50 | 6 | 20 | 12 | 12 | 12 | 12 | 7.5 | 85 Ohms | TOP=L2:L3=L2/L4:L6=L5/L7:BOTTOM=L7 |
| PCIE_RX_N12 | RXS12-DIFF1 | PAIR | 8 | 5.38 | 5 | 10 | 5 | 50 | 6 | 33 | 12 | 12 | 12 | 12 | 6.62 | 85 Ohms | TOP=L2:L3=L2/L4:L6=L5/L7:BOTTOM=L7 |
| PCIE_RX_P12 | RXS12-DIFF1 | PAIR | 1 | 5.38 | 5 | 10 | 5 | 50 | 6 | 33 | 12 | 12 | 12 | 12 | 6.62 | 85 Ohms | TOP=L2:L3=L2/L4:L6=L5/L7:BOTTOM=L7 |
| PCIE_RX_P12 | RXS12-DIFF1 | PAIR | 2 | 5.5 | 5 | 10 | 5 | 50 | 6 | 20 | 12 | 12 | 12 | 12 | 7.5 | 85 Ohms | TOP=L2:L3=L2/L4:L6=L5/L7:BOTTOM=L7 |
| PCIE_RX_P12 | RXS12-DIFF1 | PAIR | 3 | 5.5 | 5 | 10 | 5 | 50 | 6 | 20 | 12 | 12 | 12 | 12 | 7.5 | 85 Ohms | TOP=L2:L3=L2/L4:L6=L5/L7:BOTTOM=L7 |
| PCIE_RX_P12 | RXS12-DIFF1 | PAIR | 4 | 5.5 | 5 | 10 | 5 | 50 | 6 | 20 | 12 | 12 | 12 | 12 | 7.5 | 85 Ohms | TOP=L2:L3=L2/L4:L6=L5/L7:BOTTOM=L7 |
| PCIE_RX_P12 | RXS12-DIFF1 | PAIR | 5 | 5.5 | 5 | 10 | 5 | 50 | 6 | 20 | 12 | 12 | 12 | 12 | 7.5 | 85 Ohms | TOP=L2:L3=L2/L4:L6=L5/L7:BOTTOM=L7 |
| PCIE_RX_P12 | RXS12-DIFF1 | PAIR | 6 | 5.5 | 5 | 10 | 5 | 50 | 6 | 20 | 12 | 12 | 12 | 12 | 7.5 | 85 Ohms | TOP=L2:L3=L2/L4:L6=L5/L7:BOTTOM=L7 |
| PCIE_RX_P12 | RXS12-DIFF1 | PAIR | 7 | 5.5 | 5 | 10 | 5 | 50 | 6 | 20 | 12 | 12 | 12 | 12 | 7.5 | 85 Ohms | TOP=L2:L3=L2/L4:L6=L5/L7:BOTTOM=L7 |
| PCIE_RX_P12 | RXS12-DIFF1 | PAIR | 8 | 5.38 | 5 | 10 | 5 | 50 | 6 | 33 | 12 | 12 | 12 | 12 | 6.62 | 85 Ohms | TOP=L2:L3=L2/L4:L6=L5/L7:BOTTOM=L7 |
| PCIE_RX_N13 | RXS13-DIFF1 | PAIR | 1 | 5.38 | 5 | 10 | 5 | 50 | 6 | 33 | 12 | 12 | 12 | 12 | 6.62 | 85 Ohms | TOP=L2:L3=L2/L4:L6=L5/L7:BOTTOM=L7 |
| PCIE_RX_N13 | RXS13-DIFF1 | PAIR | 2 | 5.5 | 5 | 10 | 5 | 50 | 6 | 20 | 12 | 12 | 12 | 12 | 7.5 | 85 Ohms | TOP=L2:L3=L2/L4:L6=L5/L7:BOTTOM=L7 |
| PCIE_RX_N13 | RXS13-DIFF1 | PAIR | 3 | 5.5 | 5 | 10 | 5 | 50 | 6 | 20 | 12 | 12 | 12 | 12 | 7.5 | 85 Ohms | TOP=L2:L3=L2/L4:L6=L5/L7:BOTTOM=L7 |
| PCIE_RX_N13 | RXS13-DIFF1 | PAIR | 4 | 5.5 | 5 | 10 | 5 | 50 | 6 | 20 | 12 | 12 | 12 | 12 | 7.5 | 85 Ohms | TOP=L2:L3=L2/L4:L6=L5/L7:BOTTOM=L7 |
| PCIE_RX_N13 | RXS13-DIFF1 | PAIR | 5 | 5.5 | 5 | 10 | 5 | 50 | 6 | 20 | 12 | 12 | 12 | 12 | 7.5 | 85 Ohms | TOP=L2:L3=L2/L4:L6=L5/L7:BOTTOM=L7 |
| PCIE_RX_N13 | RXS13-DIFF1 | PAIR | 6 | 5.5 | 5 | 10 | 5 | 50 | 6 | 20 | 12 | 12 | 12 | 12 | 7.5 | 85 Ohms | TOP=L2:L3=L2/L4:L6=L5/L7:BOTTOM=L7 |
| PCIE_RX_N13 | RXS13-DIFF1 | PAIR | 7 | 5.5 | 5 | 10 | 5 | 50 | 6 | 20 | 12 | 12 | 12 | 12 | 7.5 | 85 Ohms | TOP=L2:L3=L2/L4:L6=L5/L7:BOTTOM=L7 |
| PCIE_RX_N13 | RXS13-DIFF1 | PAIR | 8 | 5.38 | 5 | 10 | 5 | 50 | 6 | 33 | 12 | 12 | 12 | 12 | 6.62 | 85 Ohms | TOP=L2:L3=L2/L4:L6=L5/L7:BOTTOM=L7 |
| PCIE_RX_P13 | RXS13-DIFF1 | PAIR | 1 | 5.38 | 5 | 10 | 5 | 50 | 6 | 33 | 12 | 12 | 12 | 12 | 6.62 | 85 Ohms | TOP=L2:L3=L2/L4:L6=L5/L7:BOTTOM=L7 |
| PCIE_RX_P13 | RXS13-DIFF1 | PAIR | 2 | 5.5 | 5 | 10 | 5 | 50 | 6 | 20 | 12 | 12 | 12 | 12 | 7.5 | 85 Ohms | TOP=L2:L3=L2/L4:L6=L5/L7:BOTTOM=L7 |
| PCIE_RX_P13 | RXS13-DIFF1 | PAIR | 3 | 5.5 | 5 | 10 | 5 | 50 | 6 | 20 | 12 | 12 | 12 | 12 | 7.5 | 85 Ohms | TOP=L2:L3=L2/L4:L6=L5/L7:BOTTOM=L7 |
| PCIE_RX_P13 | RXS13-DIFF1 | PAIR | 4 | 5.5 | 5 | 10 | 5 | 50 | 6 | 20 | 12 | 12 | 12 | 12 | 7.5 | 85 Ohms | TOP=L2:L3=L2/L4:L6=L5/L7:BOTTOM=L7 |
| PCIE_RX_P13 | RXS13-DIFF1 | PAIR | 5 | 5.5 | 5 | 10 | 5 | 50 | 6 | 20 | 12 | 12 | 12 | 12 | 7.5 | 85 Ohms | TOP=L2:L3=L2/L4:L6=L5/L7:BOTTOM=L7 |
| PCIE_RX_P13 | RXS13-DIFF1 | PAIR | 6 | 5.5 | 5 | 10 | 5 | 50 | 6 | 20 | 12 | 12 | 12 | 12 | 7.5 | 85 Ohms | TOP=L2:L3=L2/L4:L6=L5/L7:BOTTOM=L7 |
| PCIE_RX_P13 | RXS13-DIFF1 | PAIR | 7 | 5.5 | 5 | 10 | 5 | 50 | 6 | 20 | 12 | 12 | 12 | 12 | 7.5 | 85 Ohms | TOP=L2:L3=L2/L4:L6=L5/L7:BOTTOM=L7 |
| PCIE_RX_P13 | RXS13-DIFF1 | PAIR | 8 | 5.38 | 5 | 10 | 5 | 50 | 6 | 33 | 12 | 12 | 12 | 12 | 6.62 | 85 Ohms | TOP=L2:L3=L2/L4:L6=L5/L7:BOTTOM=L7 |
| PCIE_RX_N14 | RXS14-DIFF1 | PAIR | 1 | 5.38 | 5 | 10 | 5 | 50 | 6 | 33 | 12 | 12 | 12 | 12 | 6.62 | 85 Ohms | TOP=L2:L3=L2/L4:L6=L5/L7:BOTTOM=L7 |
| PCIE_RX_N14 | RXS14-DIFF1 | PAIR | 2 | 5.5 | 5 | 10 | 5 | 50 | 6 | 20 | 12 | 12 | 12 | 12 | 7.5 | 85 Ohms | TOP=L2:L3=L2/L4:L6=L5/L7:BOTTOM=L7 |
| PCIE_RX_N14 | RXS14-DIFF1 | PAIR | 3 | 5.5 | 5 | 10 | 5 | 50 | 6 | 20 | 12 | 12 | 12 | 12 | 7.5 | 85 Ohms | TOP=L2:L3=L2/L4:L6=L5/L7:BOTTOM=L7 |
| PCIE_RX_N14 | RXS14-DIFF1 | PAIR | 4 | 5.5 | 5 | 10 | 5 | 50 | 6 | 20 | 12 | 12 | 12 | 12 | 7.5 | 85 Ohms | TOP=L2:L3=L2/L4:L6=L5/L7:BOTTOM=L7 |
| PCIE_RX_N14 | RXS14-DIFF1 | PAIR | 5 | 5.5 | 5 | 10 | 5 | 50 | 6 | 20 | 12 | 12 | 12 | 12 | 7.5 | 85 Ohms | TOP=L2:L3=L2/L4:L6=L5/L7:BOTTOM=L7 |
| PCIE_RX_N14 | RXS14-DIFF1 | PAIR | 6 | 5.5 | 5 | 10 | 5 | 50 | 6 | 20 | 12 | 12 | 12 | 12 | 7.5 | 85 Ohms | TOP=L2:L3=L2/L4:L6=L5/L7:BOTTOM=L7 |
| PCIE_RX_N14 | RXS14-DIFF1 | PAIR | 7 | 5.5 | 5 | 10 | 5 | 50 | 6 | 20 | 12 | 12 | 12 | 12 | 7.5 | 85 Ohms | TOP=L2:L3=L2/L4:L6=L5/L7:BOTTOM=L7 |
| PCIE_RX_N14 | RXS14-DIFF1 | PAIR | 8 | 5.38 | 5 | 10 | 5 | 50 | 6 | 33 | 12 | 12 | 12 | 12 | 6.62 | 85 Ohms | TOP=L2:L3=L2/L4:L6=L5/L7:BOTTOM=L7 |
| PCIE_RX_P14 | RXS14-DIFF1 | PAIR | 1 | 5.38 | 5 | 10 | 5 | 50 | 6 | 33 | 12 | 12 | 12 | 12 | 6.62 | 85 Ohms | TOP=L2:L3=L2/L4:L6=L5/L7:BOTTOM=L7 |
| PCIE_RX_P14 | RXS14-DIFF1 | PAIR | 2 | 5.5 | 5 | 10 | 5 | 50 | 6 | 20 | 12 | 12 | 12 | 12 | 7.5 | 85 Ohms | TOP=L2:L3=L2/L4:L6=L5/L7:BOTTOM=L7 |
| PCIE_RX_P14 | RXS14-DIFF1 | PAIR | 3 | 5.5 | 5 | 10 | 5 | 50 | 6 | 20 | 12 | 12 | 12 | 12 | 7.5 | 85 Ohms | TOP=L2:L3=L2/L4:L6=L5/L7:BOTTOM=L7 |
| PCIE_RX_P14 | RXS14-DIFF1 | PAIR | 4 | 5.5 | 5 | 10 | 5 | 50 | 6 | 20 | 12 | 12 | 12 | 12 | 7.5 | 85 Ohms | TOP=L2:L3=L2/L4:L6=L5/L7:BOTTOM=L7 |
| PCIE_RX_P14 | RXS14-DIFF1 | PAIR | 5 | 5.5 | 5 | 10 | 5 | 50 | 6 | 20 | 12 | 12 | 12 | 12 | 7.5 | 85 Ohms | TOP=L2:L3=L2/L4:L6=L5/L7:BOTTOM=L7 |
| PCIE_RX_P14 | RXS14-DIFF1 | PAIR | 6 | 5.5 | 5 | 10 | 5 | 50 | 6 | 20 | 12 | 12 | 12 | 12 | 7.5 | 85 Ohms | TOP=L2:L3=L2/L4:L6=L5/L7:BOTTOM=L7 |
| PCIE_RX_P14 | RXS14-DIFF1 | PAIR | 7 | 5.5 | 5 | 10 | 5 | 50 | 6 | 20 | 12 | 12 | 12 | 12 | 7.5 | 85 Ohms | TOP=L2:L3=L2/L4:L6=L5/L7:BOTTOM=L7 |
| PCIE_RX_P14 | RXS14-DIFF1 | PAIR | 8 | 5.38 | 5 | 10 | 5 | 50 | 6 | 33 | 12 | 12 | 12 | 12 | 6.62 | 85 Ohms | TOP=L2:L3=L2/L4:L6=L5/L7:BOTTOM=L7 |
| PCIE_RX_N15 | RXS15-DIFF1 | PAIR | 1 | 5.38 | 5 | 10 | 5 | 50 | 6 | 33 | 12 | 12 | 12 | 12 | 6.62 | 85 Ohms | TOP=L2:L3=L2/L4:L6=L5/L7:BOTTOM=L7 |
| PCIE_RX_N15 | RXS15-DIFF1 | PAIR | 2 | 5.5 | 5 | 10 | 5 | 50 | 6 | 20 | 12 | 12 | 12 | 12 | 7.5 | 85 Ohms | TOP=L2:L3=L2/L4:L6=L5/L7:BOTTOM=L7 |
| PCIE_RX_N15 | RXS15-DIFF1 | PAIR | 3 | 5.5 | 5 | 10 | 5 | 50 | 6 | 20 | 12 | 12 | 12 | 12 | 7.5 | 85 Ohms | TOP=L2:L3=L2/L4:L6=L5/L7:BOTTOM=L7 |
| PCIE_RX_N15 | RXS15-DIFF1 | PAIR | 4 | 5.5 | 5 | 10 | 5 | 50 | 6 | 20 | 12 | 12 | 12 | 12 | 7.5 | 85 Ohms | TOP=L2:L3=L2/L4:L6=L5/L7:BOTTOM=L7 |
| PCIE_RX_N15 | RXS15-DIFF1 | PAIR | 5 | 5.5 | 5 | 10 | 5 | 50 | 6 | 20 | 12 | 12 | 12 | 12 | 7.5 | 85 Ohms | TOP=L2:L3=L2/L4:L6=L5/L7:BOTTOM=L7 |
| PCIE_RX_N15 | RXS15-DIFF1 | PAIR | 6 | 5.5 | 5 | 10 | 5 | 50 | 6 | 20 | 12 | 12 | 12 | 12 | 7.5 | 85 Ohms | TOP=L2:L3=L2/L4:L6=L5/L7:BOTTOM=L7 |
| PCIE_RX_N15 | RXS15-DIFF1 | PAIR | 7 | 5.5 | 5 | 10 | 5 | 50 | 6 | 20 | 12 | 12 | 12 | 12 | 7.5 | 85 Ohms | TOP=L2:L3=L2/L4:L6=L5/L7:BOTTOM=L7 |
| PCIE_RX_N15 | RXS15-DIFF1 | PAIR | 8 | 5.38 | 5 | 10 | 5 | 50 | 6 | 33 | 12 | 12 | 12 | 12 | 6.62 | 85 Ohms | TOP=L2:L3=L2/L4:L6=L5/L7:BOTTOM=L7 |
| PCIE_RX_P15 | RXS15-DIFF1 | PAIR | 1 | 5.38 | 5 | 10 | 5 | 50 | 6 | 33 | 12 | 12 | 12 | 12 | 6.62 | 85 Ohms | TOP=L2:L3=L2/L4:L6=L5/L7:BOTTOM=L7 |
| PCIE_RX_P15 | RXS15-DIFF1 | PAIR | 2 | 5.5 | 5 | 10 | 5 | 50 | 6 | 20 | 12 | 12 | 12 | 12 | 7.5 | 85 Ohms | TOP=L2:L3=L2/L4:L6=L5/L7:BOTTOM=L7 |
| PCIE_RX_P15 | RXS15-DIFF1 | PAIR | 3 | 5.5 | 5 | 10 | 5 | 50 | 6 | 20 | 12 | 12 | 12 | 12 | 7.5 | 85 Ohms | TOP=L2:L3=L2/L4:L6=L5/L7:BOTTOM=L7 |
| PCIE_RX_P15 | RXS15-DIFF1 | PAIR | 4 | 5.5 | 5 | 10 | 5 | 50 | 6 | 20 | 12 | 12 | 12 | 12 | 7.5 | 85 Ohms | TOP=L2:L3=L2/L4:L6=L5/L7:BOTTOM=L7 |
| PCIE_RX_P15 | RXS15-DIFF1 | PAIR | 5 | 5.5 | 5 | 10 | 5 | 50 | 6 | 20 | 12 | 12 | 12 | 12 | 7.5 | 85 Ohms | TOP=L2:L3=L2/L4:L6=L5/L7:BOTTOM=L7 |
| PCIE_RX_P15 | RXS15-DIFF1 | PAIR | 6 | 5.5 | 5 | 10 | 5 | 50 | 6 | 20 | 12 | 12 | 12 | 12 | 7.5 | 85 Ohms | TOP=L2:L3=L2/L4:L6=L5/L7:BOTTOM=L7 |
| PCIE_RX_P15 | RXS15-DIFF1 | PAIR | 7 | 5.5 | 5 | 10 | 5 | 50 | 6 | 20 | 12 | 12 | 12 | 12 | 7.5 | 85 Ohms | TOP=L2:L3=L2/L4:L6=L5/L7:BOTTOM=L7 |
| PCIE_RX_P15 | RXS15-DIFF1 | PAIR | 8 | 5.38 | 5 | 10 | 5 | 50 | 6 | 33 | 12 | 12 | 12 | 12 | 6.62 | 85 Ohms | TOP=L2:L3=L2/L4:L6=L5/L7:BOTTOM=L7 |
| PCIE_RX_N16 | RXS16-DIFF1 | PAIR | 1 | 5.38 | 5 | 10 | 5 | 50 | 6 | 33 | 12 | 12 | 12 | 12 | 6.62 | 85 Ohms | TOP=L2:L3=L2/L4:L6=L5/L7:BOTTOM=L7 |
| PCIE_RX_N16 | RXS16-DIFF1 | PAIR | 2 | 5.5 | 5 | 10 | 5 | 50 | 6 | 20 | 12 | 12 | 12 | 12 | 7.5 | 85 Ohms | TOP=L2:L3=L2/L4:L6=L5/L7:BOTTOM=L7 |
| PCIE_RX_N16 | RXS16-DIFF1 | PAIR | 3 | 5.5 | 5 | 10 | 5 | 50 | 6 | 20 | 12 | 12 | 12 | 12 | 7.5 | 85 Ohms | TOP=L2:L3=L2/L4:L6=L5/L7:BOTTOM=L7 |
| PCIE_RX_N16 | RXS16-DIFF1 | PAIR | 4 | 5.5 | 5 | 10 | 5 | 50 | 6 | 20 | 12 | 12 | 12 | 12 | 7.5 | 85 Ohms | TOP=L2:L3=L2/L4:L6=L5/L7:BOTTOM=L7 |
| PCIE_RX_N16 | RXS16-DIFF1 | PAIR | 5 | 5.5 | 5 | 10 | 5 | 50 | 6 | 20 | 12 | 12 | 12 | 12 | 7.5 | 85 Ohms | TOP=L2:L3=L2/L4:L6=L5/L7:BOTTOM=L7 |
| PCIE_RX_N16 | RXS16-DIFF1 | PAIR | 6 | 5.5 | 5 | 10 | 5 | 50 | 6 | 20 | 12 | 12 | 12 | 12 | 7.5 | 85 Ohms | TOP=L2:L3=L2/L4:L6=L5/L7:BOTTOM=L7 |
| PCIE_RX_N16 | RXS16-DIFF1 | PAIR | 7 | 5.5 | 5 | 10 | 5 | 50 | 6 | 20 | 12 | 12 | 12 | 12 | 7.5 | 85 Ohms | TOP=L2:L3=L2/L4:L6=L5/L7:BOTTOM=L7 |
| PCIE_RX_N16 | RXS16-DIFF1 | PAIR | 8 | 5.38 | 5 | 10 | 5 | 50 | 6 | 33 | 12 | 12 | 12 | 12 | 6.62 | 85 Ohms | TOP=L2:L3=L2/L4:L6=L5/L7:BOTTOM=L7 |
| PCIE_RX_P16 | RXS16-DIFF1 | PAIR | 1 | 5.38 | 5 | 10 | 5 | 50 | 6 | 33 | 12 | 12 | 12 | 12 | 6.62 | 85 Ohms | TOP=L2:L3=L2/L4:L6=L5/L7:BOTTOM=L7 |
| PCIE_RX_P16 | RXS16-DIFF1 | PAIR | 2 | 5.5 | 5 | 10 | 5 | 50 | 6 | 20 | 12 | 12 | 12 | 12 | 7.5 | 85 Ohms | TOP=L2:L3=L2/L4:L6=L5/L7:BOTTOM=L7 |
| PCIE_RX_P16 | RXS16-DIFF1 | PAIR | 3 | 5.5 | 5 | 10 | 5 | 50 | 6 | 20 | 12 | 12 | 12 | 12 | 7.5 | 85 Ohms | TOP=L2:L3=L2/L4:L6=L5/L7:BOTTOM=L7 |
| PCIE_RX_P16 | RXS16-DIFF1 | PAIR | 4 | 5.5 | 5 | 10 | 5 | 50 | 6 | 20 | 12 | 12 | 12 | 12 | 7.5 | 85 Ohms | TOP=L2:L3=L2/L4:L6=L5/L7:BOTTOM=L7 |
| PCIE_RX_P16 | RXS16-DIFF1 | PAIR | 5 | 5.5 | 5 | 10 | 5 | 50 | 6 | 20 | 12 | 12 | 12 | 12 | 7.5 | 85 Ohms | TOP=L2:L3=L2/L4:L6=L5/L7:BOTTOM=L7 |
| PCIE_RX_P16 | RXS16-DIFF1 | PAIR | 6 | 5.5 | 5 | 10 | 5 | 50 | 6 | 20 | 12 | 12 | 12 | 12 | 7.5 | 85 Ohms | TOP=L2:L3=L2/L4:L6=L5/L7:BOTTOM=L7 |
| PCIE_RX_P16 | RXS16-DIFF1 | PAIR | 7 | 5.5 | 5 | 10 | 5 | 50 | 6 | 20 | 12 | 12 | 12 | 12 | 7.5 | 85 Ohms | TOP=L2:L3=L2/L4:L6=L5/L7:BOTTOM=L7 |
| PCIE_RX_P16 | RXS16-DIFF1 | PAIR | 8 | 5.38 | 5 | 10 | 5 | 50 | 6 | 33 | 12 | 12 | 12 | 12 | 6.62 | 85 Ohms | TOP=L2:L3=L2/L4:L6=L5/L7:BOTTOM=L7 |
| PCIE_RX_N17 | RXS17-DIFF1 | PAIR | 1 | 5.38 | 5 | 10 | 5 | 50 | 6 | 33 | 12 | 12 | 12 | 12 | 6.62 | 85 Ohms | TOP=L2:L3=L2/L4:L6=L5/L7:BOTTOM=L7 |
| PCIE_RX_N17 | RXS17-DIFF1 | PAIR | 2 | 5.5 | 5 | 10 | 5 | 50 | 6 | 20 | 12 | 12 | 12 | 12 | 7.5 | 85 Ohms | TOP=L2:L3=L2/L4:L6=L5/L7:BOTTOM=L7 |
| PCIE_RX_N17 | RXS17-DIFF1 | PAIR | 3 | 5.5 | 5 | 10 | 5 | 50 | 6 | 20 | 12 | 12 | 12 | 12 | 7.5 | 85 Ohms | TOP=L2:L3=L2/L4:L6=L5/L7:BOTTOM=L7 |
| PCIE_RX_N17 | RXS17-DIFF1 | PAIR | 4 | 5.5 | 5 | 10 | 5 | 50 | 6 | 20 | 12 | 12 | 12 | 12 | 7.5 | 85 Ohms | TOP=L2:L3=L2/L4:L6=L5/L7:BOTTOM=L7 |
| PCIE_RX_N17 | RXS17-DIFF1 | PAIR | 5 | 5.5 | 5 | 10 | 5 | 50 | 6 | 20 | 12 | 12 | 12 | 12 | 7.5 | 85 Ohms | TOP=L2:L3=L2/L4:L6=L5/L7:BOTTOM=L7 |
| PCIE_RX_N17 | RXS17-DIFF1 | PAIR | 6 | 5.5 | 5 | 10 | 5 | 50 | 6 | 20 | 12 | 12 | 12 | 12 | 7.5 | 85 Ohms | TOP=L2:L3=L2/L4:L6=L5/L7:BOTTOM=L7 |
| PCIE_RX_N17 | RXS17-DIFF1 | PAIR | 7 | 5.5 | 5 | 10 | 5 | 50 | 6 | 20 | 12 | 12 | 12 | 12 | 7.5 | 85 Ohms | TOP=L2:L3=L2/L4:L6=L5/L7:BOTTOM=L7 |
| PCIE_RX_N17 | RXS17-DIFF1 | PAIR | 8 | 5.38 | 5 | 10 | 5 | 50 | 6 | 33 | 12 | 12 | 12 | 12 | 6.62 | 85 Ohms | TOP=L2:L3=L2/L4:L6=L5/L7:BOTTOM=L7 |
| PCIE_RX_P17 | RXS17-DIFF1 | PAIR | 1 | 5.38 | 5 | 10 | 5 | 50 | 6 | 33 | 12 | 12 | 12 | 12 | 6.62 | 85 Ohms | TOP=L2:L3=L2/L4:L6=L5/L7:BOTTOM=L7 |
| PCIE_RX_P17 | RXS17-DIFF1 | PAIR | 2 | 5.5 | 5 | 10 | 5 | 50 | 6 | 20 | 12 | 12 | 12 | 12 | 7.5 | 85 Ohms | TOP=L2:L3=L2/L4:L6=L5/L7:BOTTOM=L7 |
| PCIE_RX_P17 | RXS17-DIFF1 | PAIR | 3 | 5.5 | 5 | 10 | 5 | 50 | 6 | 20 | 12 | 12 | 12 | 12 | 7.5 | 85 Ohms | TOP=L2:L3=L2/L4:L6=L5/L7:BOTTOM=L7 |
| PCIE_RX_P17 | RXS17-DIFF1 | PAIR | 4 | 5.5 | 5 | 10 | 5 | 50 | 6 | 20 | 12 | 12 | 12 | 12 | 7.5 | 85 Ohms | TOP=L2:L3=L2/L4:L6=L5/L7:BOTTOM=L7 |
| PCIE_RX_P17 | RXS17-DIFF1 | PAIR | 5 | 5.5 | 5 | 10 | 5 | 50 | 6 | 20 | 12 | 12 | 12 | 12 | 7.5 | 85 Ohms | TOP=L2:L3=L2/L4:L6=L5/L7:BOTTOM=L7 |
| PCIE_RX_P17 | RXS17-DIFF1 | PAIR | 6 | 5.5 | 5 | 10 | 5 | 50 | 6 | 20 | 12 | 12 | 12 | 12 | 7.5 | 85 Ohms | TOP=L2:L3=L2/L4:L6=L5/L7:BOTTOM=L7 |
| PCIE_RX_P17 | RXS17-DIFF1 | PAIR | 7 | 5.5 | 5 | 10 | 5 | 50 | 6 | 20 | 12 | 12 | 12 | 12 | 7.5 | 85 Ohms | TOP=L2:L3=L2/L4:L6=L5/L7:BOTTOM=L7 |
| PCIE_RX_P17 | RXS17-DIFF1 | PAIR | 8 | 5.38 | 5 | 10 | 5 | 50 | 6 | 33 | 12 | 12 | 12 | 12 | 6.62 | 85 Ohms | TOP=L2:L3=L2/L4:L6=L5/L7:BOTTOM=L7 |
| PCIE_RX_N18 | RXS18-DIFF1 | PAIR | 1 | 5.38 | 5 | 10 | 5 | 50 | 6 | 33 | 12 | 12 | 12 | 12 | 6.62 | 85 Ohms | TOP=L2:L3=L2/L4:L6=L5/L7:BOTTOM=L7 |
| PCIE_RX_N18 | RXS18-DIFF1 | PAIR | 2 | 5.5 | 5 | 10 | 5 | 50 | 6 | 20 | 12 | 12 | 12 | 12 | 7.5 | 85 Ohms | TOP=L2:L3=L2/L4:L6=L5/L7:BOTTOM=L7 |
| PCIE_RX_N18 | RXS18-DIFF1 | PAIR | 3 | 5.5 | 5 | 10 | 5 | 50 | 6 | 20 | 12 | 12 | 12 | 12 | 7.5 | 85 Ohms | TOP=L2:L3=L2/L4:L6=L5/L7:BOTTOM=L7 |
| PCIE_RX_N18 | RXS18-DIFF1 | PAIR | 4 | 5.5 | 5 | 10 | 5 | 50 | 6 | 20 | 12 | 12 | 12 | 12 | 7.5 | 85 Ohms | TOP=L2:L3=L2/L4:L6=L5/L7:BOTTOM=L7 |
| PCIE_RX_N18 | RXS18-DIFF1 | PAIR | 5 | 5.5 | 5 | 10 | 5 | 50 | 6 | 20 | 12 | 12 | 12 | 12 | 7.5 | 85 Ohms | TOP=L2:L3=L2/L4:L6=L5/L7:BOTTOM=L7 |
| PCIE_RX_N18 | RXS18-DIFF1 | PAIR | 6 | 5.5 | 5 | 10 | 5 | 50 | 6 | 20 | 12 | 12 | 12 | 12 | 7.5 | 85 Ohms | TOP=L2:L3=L2/L4:L6=L5/L7:BOTTOM=L7 |
| PCIE_RX_N18 | RXS18-DIFF1 | PAIR | 7 | 5.5 | 5 | 10 | 5 | 50 | 6 | 20 | 12 | 12 | 12 | 12 | 7.5 | 85 Ohms | TOP=L2:L3=L2/L4:L6=L5/L7:BOTTOM=L7 |
| PCIE_RX_N18 | RXS18-DIFF1 | PAIR | 8 | 5.38 | 5 | 10 | 5 | 50 | 6 | 33 | 12 | 12 | 12 | 12 | 6.62 | 85 Ohms | TOP=L2:L3=L2/L4:L6=L5/L7:BOTTOM=L7 |
| PCIE_RX_P18 | RXS18-DIFF1 | PAIR | 1 | 5.38 | 5 | 10 | 5 | 50 | 6 | 33 | 12 | 12 | 12 | 12 | 6.62 | 85 Ohms | TOP=L2:L3=L2/L4:L6=L5/L7:BOTTOM=L7 |
| PCIE_RX_P18 | RXS18-DIFF1 | PAIR | 2 | 5.5 | 5 | 10 | 5 | 50 | 6 | 20 | 12 | 12 | 12 | 12 | 7.5 | 85 Ohms | TOP=L2:L3=L2/L4:L6=L5/L7:BOTTOM=L7 |
| PCIE_RX_P18 | RXS18-DIFF1 | PAIR | 3 | 5.5 | 5 | 10 | 5 | 50 | 6 | 20 | 12 | 12 | 12 | 12 | 7.5 | 85 Ohms | TOP=L2:L3=L2/L4:L6=L5/L7:BOTTOM=L7 |
| PCIE_RX_P18 | RXS18-DIFF1 | PAIR | 4 | 5.5 | 5 | 10 | 5 | 50 | 6 | 20 | 12 | 12 | 12 | 12 | 7.5 | 85 Ohms | TOP=L2:L3=L2/L4:L6=L5/L7:BOTTOM=L7 |
| PCIE_RX_P18 | RXS18-DIFF1 | PAIR | 5 | 5.5 | 5 | 10 | 5 | 50 | 6 | 20 | 12 | 12 | 12 | 12 | 7.5 | 85 Ohms | TOP=L2:L3=L2/L4:L6=L5/L7:BOTTOM=L7 |
| PCIE_RX_P18 | RXS18-DIFF1 | PAIR | 6 | 5.5 | 5 | 10 | 5 | 50 | 6 | 20 | 12 | 12 | 12 | 12 | 7.5 | 85 Ohms | TOP=L2:L3=L2/L4:L6=L5/L7:BOTTOM=L7 |
| PCIE_RX_P18 | RXS18-DIFF1 | PAIR | 7 | 5.5 | 5 | 10 | 5 | 50 | 6 | 20 | 12 | 12 | 12 | 12 | 7.5 | 85 Ohms | TOP=L2:L3=L2/L4:L6=L5/L7:BOTTOM=L7 |
| PCIE_RX_P18 | RXS18-DIFF1 | PAIR | 8 | 5.38 | 5 | 10 | 5 | 50 | 6 | 33 | 12 | 12 | 12 | 12 | 6.62 | 85 Ohms | TOP=L2:L3=L2/L4:L6=L5/L7:BOTTOM=L7 |
| PCIE_RX_N19 | RXS19-DIFF1 | PAIR | 1 | 5.38 | 5 | 10 | 5 | 50 | 6 | 33 | 12 | 12 | 12 | 12 | 6.62 | 85 Ohms | TOP=L2:L3=L2/L4:L6=L5/L7:BOTTOM=L7 |
| PCIE_RX_N19 | RXS19-DIFF1 | PAIR | 2 | 5.5 | 5 | 10 | 5 | 50 | 6 | 20 | 12 | 12 | 12 | 12 | 7.5 | 85 Ohms | TOP=L2:L3=L2/L4:L6=L5/L7:BOTTOM=L7 |
| PCIE_RX_N19 | RXS19-DIFF1 | PAIR | 3 | 5.5 | 5 | 10 | 5 | 50 | 6 | 20 | 12 | 12 | 12 | 12 | 7.5 | 85 Ohms | TOP=L2:L3=L2/L4:L6=L5/L7:BOTTOM=L7 |
| PCIE_RX_N19 | RXS19-DIFF1 | PAIR | 4 | 5.5 | 5 | 10 | 5 | 50 | 6 | 20 | 12 | 12 | 12 | 12 | 7.5 | 85 Ohms | TOP=L2:L3=L2/L4:L6=L5/L7:BOTTOM=L7 |
| PCIE_RX_N19 | RXS19-DIFF1 | PAIR | 5 | 5.5 | 5 | 10 | 5 | 50 | 6 | 20 | 12 | 12 | 12 | 12 | 7.5 | 85 Ohms | TOP=L2:L3=L2/L4:L6=L5/L7:BOTTOM=L7 |
| PCIE_RX_N19 | RXS19-DIFF1 | PAIR | 6 | 5.5 | 5 | 10 | 5 | 50 | 6 | 20 | 12 | 12 | 12 | 12 | 7.5 | 85 Ohms | TOP=L2:L3=L2/L4:L6=L5/L7:BOTTOM=L7 |
| PCIE_RX_N19 | RXS19-DIFF1 | PAIR | 7 | 5.5 | 5 | 10 | 5 | 50 | 6 | 20 | 12 | 12 | 12 | 12 | 7.5 | 85 Ohms | TOP=L2:L3=L2/L4:L6=L5/L7:BOTTOM=L7 |
| PCIE_RX_N19 | RXS19-DIFF1 | PAIR | 8 | 5.38 | 5 | 10 | 5 | 50 | 6 | 33 | 12 | 12 | 12 | 12 | 6.62 | 85 Ohms | TOP=L2:L3=L2/L4:L6=L5/L7:BOTTOM=L7 |
| PCIE_RX_P19 | RXS19-DIFF1 | PAIR | 1 | 5.38 | 5 | 10 | 5 | 50 | 6 | 33 | 12 | 12 | 12 | 12 | 6.62 | 85 Ohms | TOP=L2:L3=L2/L4:L6=L5/L7:BOTTOM=L7 |
| PCIE_RX_P19 | RXS19-DIFF1 | PAIR | 2 | 5.5 | 5 | 10 | 5 | 50 | 6 | 20 | 12 | 12 | 12 | 12 | 7.5 | 85 Ohms | TOP=L2:L3=L2/L4:L6=L5/L7:BOTTOM=L7 |
| PCIE_RX_P19 | RXS19-DIFF1 | PAIR | 3 | 5.5 | 5 | 10 | 5 | 50 | 6 | 20 | 12 | 12 | 12 | 12 | 7.5 | 85 Ohms | TOP=L2:L3=L2/L4:L6=L5/L7:BOTTOM=L7 |
| PCIE_RX_P19 | RXS19-DIFF1 | PAIR | 4 | 5.5 | 5 | 10 | 5 | 50 | 6 | 20 | 12 | 12 | 12 | 12 | 7.5 | 85 Ohms | TOP=L2:L3=L2/L4:L6=L5/L7:BOTTOM=L7 |
| PCIE_RX_P19 | RXS19-DIFF1 | PAIR | 5 | 5.5 | 5 | 10 | 5 | 50 | 6 | 20 | 12 | 12 | 12 | 12 | 7.5 | 85 Ohms | TOP=L2:L3=L2/L4:L6=L5/L7:BOTTOM=L7 |
| PCIE_RX_P19 | RXS19-DIFF1 | PAIR | 6 | 5.5 | 5 | 10 | 5 | 50 | 6 | 20 | 12 | 12 | 12 | 12 | 7.5 | 85 Ohms | TOP=L2:L3=L2/L4:L6=L5/L7:BOTTOM=L7 |
| PCIE_RX_P19 | RXS19-DIFF1 | PAIR | 7 | 5.5 | 5 | 10 | 5 | 50 | 6 | 20 | 12 | 12 | 12 | 12 | 7.5 | 85 Ohms | TOP=L2:L3=L2/L4:L6=L5/L7:BOTTOM=L7 |
| PCIE_RX_P19 | RXS19-DIFF1 | PAIR | 8 | 5.38 | 5 | 10 | 5 | 50 | 6 | 33 | 12 | 12 | 12 | 12 | 6.62 | 85 Ohms | TOP=L2:L3=L2/L4:L6=L5/L7:BOTTOM=L7 |
| PCIE_RX_N1 | RXS1-DIFF1 | PAIR | 1 | 5.38 | 5 | 10 | 5 | 50 | 6 | 33 | 12 | 12 | 12 | 12 | 6.62 | 85 Ohms | TOP=L2:L3=L2/L4:L6=L5/L7:BOTTOM=L7 |
| PCIE_RX_N1 | RXS1-DIFF1 | PAIR | 2 | 5.5 | 5 | 10 | 5 | 50 | 6 | 20 | 12 | 12 | 12 | 12 | 7.5 | 85 Ohms | TOP=L2:L3=L2/L4:L6=L5/L7:BOTTOM=L7 |
| PCIE_RX_N1 | RXS1-DIFF1 | PAIR | 3 | 5.5 | 5 | 10 | 5 | 50 | 6 | 20 | 12 | 12 | 12 | 12 | 7.5 | 85 Ohms | TOP=L2:L3=L2/L4:L6=L5/L7:BOTTOM=L7 |
| PCIE_RX_N1 | RXS1-DIFF1 | PAIR | 4 | 5.5 | 5 | 10 | 5 | 50 | 6 | 20 | 12 | 12 | 12 | 12 | 7.5 | 85 Ohms | TOP=L2:L3=L2/L4:L6=L5/L7:BOTTOM=L7 |
| PCIE_RX_N1 | RXS1-DIFF1 | PAIR | 5 | 5.5 | 5 | 10 | 5 | 50 | 6 | 20 | 12 | 12 | 12 | 12 | 7.5 | 85 Ohms | TOP=L2:L3=L2/L4:L6=L5/L7:BOTTOM=L7 |
| PCIE_RX_N1 | RXS1-DIFF1 | PAIR | 6 | 5.5 | 5 | 10 | 5 | 50 | 6 | 20 | 12 | 12 | 12 | 12 | 7.5 | 85 Ohms | TOP=L2:L3=L2/L4:L6=L5/L7:BOTTOM=L7 |
| PCIE_RX_N1 | RXS1-DIFF1 | PAIR | 7 | 5.5 | 5 | 10 | 5 | 50 | 6 | 20 | 12 | 12 | 12 | 12 | 7.5 | 85 Ohms | TOP=L2:L3=L2/L4:L6=L5/L7:BOTTOM=L7 |
| PCIE_RX_N1 | RXS1-DIFF1 | PAIR | 8 | 5.38 | 5 | 10 | 5 | 50 | 6 | 33 | 12 | 12 | 12 | 12 | 6.62 | 85 Ohms | TOP=L2:L3=L2/L4:L6=L5/L7:BOTTOM=L7 |
| PCIE_RX_P1 | RXS1-DIFF1 | PAIR | 1 | 5.38 | 5 | 10 | 5 | 50 | 6 | 33 | 12 | 12 | 12 | 12 | 6.62 | 85 Ohms | TOP=L2:L3=L2/L4:L6=L5/L7:BOTTOM=L7 |
| PCIE_RX_P1 | RXS1-DIFF1 | PAIR | 2 | 5.5 | 5 | 10 | 5 | 50 | 6 | 20 | 12 | 12 | 12 | 12 | 7.5 | 85 Ohms | TOP=L2:L3=L2/L4:L6=L5/L7:BOTTOM=L7 |
| PCIE_RX_P1 | RXS1-DIFF1 | PAIR | 3 | 5.5 | 5 | 10 | 5 | 50 | 6 | 20 | 12 | 12 | 12 | 12 | 7.5 | 85 Ohms | TOP=L2:L3=L2/L4:L6=L5/L7:BOTTOM=L7 |
| PCIE_RX_P1 | RXS1-DIFF1 | PAIR | 4 | 5.5 | 5 | 10 | 5 | 50 | 6 | 20 | 12 | 12 | 12 | 12 | 7.5 | 85 Ohms | TOP=L2:L3=L2/L4:L6=L5/L7:BOTTOM=L7 |
| PCIE_RX_P1 | RXS1-DIFF1 | PAIR | 5 | 5.5 | 5 | 10 | 5 | 50 | 6 | 20 | 12 | 12 | 12 | 12 | 7.5 | 85 Ohms | TOP=L2:L3=L2/L4:L6=L5/L7:BOTTOM=L7 |
| PCIE_RX_P1 | RXS1-DIFF1 | PAIR | 6 | 5.5 | 5 | 10 | 5 | 50 | 6 | 20 | 12 | 12 | 12 | 12 | 7.5 | 85 Ohms | TOP=L2:L3=L2/L4:L6=L5/L7:BOTTOM=L7 |
| PCIE_RX_P1 | RXS1-DIFF1 | PAIR | 7 | 5.5 | 5 | 10 | 5 | 50 | 6 | 20 | 12 | 12 | 12 | 12 | 7.5 | 85 Ohms | TOP=L2:L3=L2/L4:L6=L5/L7:BOTTOM=L7 |
| PCIE_RX_P1 | RXS1-DIFF1 | PAIR | 8 | 5.38 | 5 | 10 | 5 | 50 | 6 | 33 | 12 | 12 | 12 | 12 | 6.62 | 85 Ohms | TOP=L2:L3=L2/L4:L6=L5/L7:BOTTOM=L7 |
| PCIE_RX_N20 | RXS20-DIFF1 | PAIR | 1 | 5.38 | 5 | 10 | 5 | 50 | 6 | 33 | 12 | 12 | 12 | 12 | 6.62 | 85 Ohms | TOP=L2:L3=L2/L4:L6=L5/L7:BOTTOM=L7 |
| PCIE_RX_N20 | RXS20-DIFF1 | PAIR | 2 | 5.5 | 5 | 10 | 5 | 50 | 6 | 20 | 12 | 12 | 12 | 12 | 7.5 | 85 Ohms | TOP=L2:L3=L2/L4:L6=L5/L7:BOTTOM=L7 |
| PCIE_RX_N20 | RXS20-DIFF1 | PAIR | 3 | 5.5 | 5 | 10 | 5 | 50 | 6 | 20 | 12 | 12 | 12 | 12 | 7.5 | 85 Ohms | TOP=L2:L3=L2/L4:L6=L5/L7:BOTTOM=L7 |
| PCIE_RX_N20 | RXS20-DIFF1 | PAIR | 4 | 5.5 | 5 | 10 | 5 | 50 | 6 | 20 | 12 | 12 | 12 | 12 | 7.5 | 85 Ohms | TOP=L2:L3=L2/L4:L6=L5/L7:BOTTOM=L7 |
| PCIE_RX_N20 | RXS20-DIFF1 | PAIR | 5 | 5.5 | 5 | 10 | 5 | 50 | 6 | 20 | 12 | 12 | 12 | 12 | 7.5 | 85 Ohms | TOP=L2:L3=L2/L4:L6=L5/L7:BOTTOM=L7 |
| PCIE_RX_N20 | RXS20-DIFF1 | PAIR | 6 | 5.5 | 5 | 10 | 5 | 50 | 6 | 20 | 12 | 12 | 12 | 12 | 7.5 | 85 Ohms | TOP=L2:L3=L2/L4:L6=L5/L7:BOTTOM=L7 |
| PCIE_RX_N20 | RXS20-DIFF1 | PAIR | 7 | 5.5 | 5 | 10 | 5 | 50 | 6 | 20 | 12 | 12 | 12 | 12 | 7.5 | 85 Ohms | TOP=L2:L3=L2/L4:L6=L5/L7:BOTTOM=L7 |
| PCIE_RX_N20 | RXS20-DIFF1 | PAIR | 8 | 5.38 | 5 | 10 | 5 | 50 | 6 | 33 | 12 | 12 | 12 | 12 | 6.62 | 85 Ohms | TOP=L2:L3=L2/L4:L6=L5/L7:BOTTOM=L7 |
| PCIE_RX_P20 | RXS20-DIFF1 | PAIR | 1 | 5.38 | 5 | 10 | 5 | 50 | 6 | 33 | 12 | 12 | 12 | 12 | 6.62 | 85 Ohms | TOP=L2:L3=L2/L4:L6=L5/L7:BOTTOM=L7 |
| PCIE_RX_P20 | RXS20-DIFF1 | PAIR | 2 | 5.5 | 5 | 10 | 5 | 50 | 6 | 20 | 12 | 12 | 12 | 12 | 7.5 | 85 Ohms | TOP=L2:L3=L2/L4:L6=L5/L7:BOTTOM=L7 |
| PCIE_RX_P20 | RXS20-DIFF1 | PAIR | 3 | 5.5 | 5 | 10 | 5 | 50 | 6 | 20 | 12 | 12 | 12 | 12 | 7.5 | 85 Ohms | TOP=L2:L3=L2/L4:L6=L5/L7:BOTTOM=L7 |
| PCIE_RX_P20 | RXS20-DIFF1 | PAIR | 4 | 5.5 | 5 | 10 | 5 | 50 | 6 | 20 | 12 | 12 | 12 | 12 | 7.5 | 85 Ohms | TOP=L2:L3=L2/L4:L6=L5/L7:BOTTOM=L7 |
| PCIE_RX_P20 | RXS20-DIFF1 | PAIR | 5 | 5.5 | 5 | 10 | 5 | 50 | 6 | 20 | 12 | 12 | 12 | 12 | 7.5 | 85 Ohms | TOP=L2:L3=L2/L4:L6=L5/L7:BOTTOM=L7 |
| PCIE_RX_P20 | RXS20-DIFF1 | PAIR | 6 | 5.5 | 5 | 10 | 5 | 50 | 6 | 20 | 12 | 12 | 12 | 12 | 7.5 | 85 Ohms | TOP=L2:L3=L2/L4:L6=L5/L7:BOTTOM=L7 |
| PCIE_RX_P20 | RXS20-DIFF1 | PAIR | 7 | 5.5 | 5 | 10 | 5 | 50 | 6 | 20 | 12 | 12 | 12 | 12 | 7.5 | 85 Ohms | TOP=L2:L3=L2/L4:L6=L5/L7:BOTTOM=L7 |
| PCIE_RX_P20 | RXS20-DIFF1 | PAIR | 8 | 5.38 | 5 | 10 | 5 | 50 | 6 | 33 | 12 | 12 | 12 | 12 | 6.62 | 85 Ohms | TOP=L2:L3=L2/L4:L6=L5/L7:BOTTOM=L7 |
| PCIE_RX_N21 | RXS21-DIFF1 | PAIR | 1 | 5.38 | 5 | 10 | 5 | 50 | 6 | 33 | 12 | 12 | 12 | 12 | 6.62 | 85 Ohms | TOP=L2:L3=L2/L4:L6=L5/L7:BOTTOM=L7 |
| PCIE_RX_N21 | RXS21-DIFF1 | PAIR | 2 | 5.5 | 5 | 10 | 5 | 50 | 6 | 20 | 12 | 12 | 12 | 12 | 7.5 | 85 Ohms | TOP=L2:L3=L2/L4:L6=L5/L7:BOTTOM=L7 |
| PCIE_RX_N21 | RXS21-DIFF1 | PAIR | 3 | 5.5 | 5 | 10 | 5 | 50 | 6 | 20 | 12 | 12 | 12 | 12 | 7.5 | 85 Ohms | TOP=L2:L3=L2/L4:L6=L5/L7:BOTTOM=L7 |
| PCIE_RX_N21 | RXS21-DIFF1 | PAIR | 4 | 5.5 | 5 | 10 | 5 | 50 | 6 | 20 | 12 | 12 | 12 | 12 | 7.5 | 85 Ohms | TOP=L2:L3=L2/L4:L6=L5/L7:BOTTOM=L7 |
| PCIE_RX_N21 | RXS21-DIFF1 | PAIR | 5 | 5.5 | 5 | 10 | 5 | 50 | 6 | 20 | 12 | 12 | 12 | 12 | 7.5 | 85 Ohms | TOP=L2:L3=L2/L4:L6=L5/L7:BOTTOM=L7 |
| PCIE_RX_N21 | RXS21-DIFF1 | PAIR | 6 | 5.5 | 5 | 10 | 5 | 50 | 6 | 20 | 12 | 12 | 12 | 12 | 7.5 | 85 Ohms | TOP=L2:L3=L2/L4:L6=L5/L7:BOTTOM=L7 |
| PCIE_RX_N21 | RXS21-DIFF1 | PAIR | 7 | 5.5 | 5 | 10 | 5 | 50 | 6 | 20 | 12 | 12 | 12 | 12 | 7.5 | 85 Ohms | TOP=L2:L3=L2/L4:L6=L5/L7:BOTTOM=L7 |
| PCIE_RX_N21 | RXS21-DIFF1 | PAIR | 8 | 5.38 | 5 | 10 | 5 | 50 | 6 | 33 | 12 | 12 | 12 | 12 | 6.62 | 85 Ohms | TOP=L2:L3=L2/L4:L6=L5/L7:BOTTOM=L7 |
| PCIE_RX_P21 | RXS21-DIFF1 | PAIR | 1 | 5.38 | 5 | 10 | 5 | 50 | 6 | 33 | 12 | 12 | 12 | 12 | 6.62 | 85 Ohms | TOP=L2:L3=L2/L4:L6=L5/L7:BOTTOM=L7 |
| PCIE_RX_P21 | RXS21-DIFF1 | PAIR | 2 | 5.5 | 5 | 10 | 5 | 50 | 6 | 20 | 12 | 12 | 12 | 12 | 7.5 | 85 Ohms | TOP=L2:L3=L2/L4:L6=L5/L7:BOTTOM=L7 |
| PCIE_RX_P21 | RXS21-DIFF1 | PAIR | 3 | 5.5 | 5 | 10 | 5 | 50 | 6 | 20 | 12 | 12 | 12 | 12 | 7.5 | 85 Ohms | TOP=L2:L3=L2/L4:L6=L5/L7:BOTTOM=L7 |
| PCIE_RX_P21 | RXS21-DIFF1 | PAIR | 4 | 5.5 | 5 | 10 | 5 | 50 | 6 | 20 | 12 | 12 | 12 | 12 | 7.5 | 85 Ohms | TOP=L2:L3=L2/L4:L6=L5/L7:BOTTOM=L7 |
| PCIE_RX_P21 | RXS21-DIFF1 | PAIR | 5 | 5.5 | 5 | 10 | 5 | 50 | 6 | 20 | 12 | 12 | 12 | 12 | 7.5 | 85 Ohms | TOP=L2:L3=L2/L4:L6=L5/L7:BOTTOM=L7 |
| PCIE_RX_P21 | RXS21-DIFF1 | PAIR | 6 | 5.5 | 5 | 10 | 5 | 50 | 6 | 20 | 12 | 12 | 12 | 12 | 7.5 | 85 Ohms | TOP=L2:L3=L2/L4:L6=L5/L7:BOTTOM=L7 |
| PCIE_RX_P21 | RXS21-DIFF1 | PAIR | 7 | 5.5 | 5 | 10 | 5 | 50 | 6 | 20 | 12 | 12 | 12 | 12 | 7.5 | 85 Ohms | TOP=L2:L3=L2/L4:L6=L5/L7:BOTTOM=L7 |
| PCIE_RX_P21 | RXS21-DIFF1 | PAIR | 8 | 5.38 | 5 | 10 | 5 | 50 | 6 | 33 | 12 | 12 | 12 | 12 | 6.62 | 85 Ohms | TOP=L2:L3=L2/L4:L6=L5/L7:BOTTOM=L7 |
| PCIE_RX_N22 | RXS22-DIFF1 | PAIR | 1 | 5.38 | 5 | 10 | 5 | 50 | 6 | 33 | 12 | 12 | 12 | 12 | 6.62 | 85 Ohms | TOP=L2:L3=L2/L4:L6=L5/L7:BOTTOM=L7 |
| PCIE_RX_N22 | RXS22-DIFF1 | PAIR | 2 | 5.5 | 5 | 10 | 5 | 50 | 6 | 20 | 12 | 12 | 12 | 12 | 7.5 | 85 Ohms | TOP=L2:L3=L2/L4:L6=L5/L7:BOTTOM=L7 |
| PCIE_RX_N22 | RXS22-DIFF1 | PAIR | 3 | 5.5 | 5 | 10 | 5 | 50 | 6 | 20 | 12 | 12 | 12 | 12 | 7.5 | 85 Ohms | TOP=L2:L3=L2/L4:L6=L5/L7:BOTTOM=L7 |
| PCIE_RX_N22 | RXS22-DIFF1 | PAIR | 4 | 5.5 | 5 | 10 | 5 | 50 | 6 | 20 | 12 | 12 | 12 | 12 | 7.5 | 85 Ohms | TOP=L2:L3=L2/L4:L6=L5/L7:BOTTOM=L7 |
| PCIE_RX_N22 | RXS22-DIFF1 | PAIR | 5 | 5.5 | 5 | 10 | 5 | 50 | 6 | 20 | 12 | 12 | 12 | 12 | 7.5 | 85 Ohms | TOP=L2:L3=L2/L4:L6=L5/L7:BOTTOM=L7 |
| PCIE_RX_N22 | RXS22-DIFF1 | PAIR | 6 | 5.5 | 5 | 10 | 5 | 50 | 6 | 20 | 12 | 12 | 12 | 12 | 7.5 | 85 Ohms | TOP=L2:L3=L2/L4:L6=L5/L7:BOTTOM=L7 |
| PCIE_RX_N22 | RXS22-DIFF1 | PAIR | 7 | 5.5 | 5 | 10 | 5 | 50 | 6 | 20 | 12 | 12 | 12 | 12 | 7.5 | 85 Ohms | TOP=L2:L3=L2/L4:L6=L5/L7:BOTTOM=L7 |
| PCIE_RX_N22 | RXS22-DIFF1 | PAIR | 8 | 5.38 | 5 | 10 | 5 | 50 | 6 | 33 | 12 | 12 | 12 | 12 | 6.62 | 85 Ohms | TOP=L2:L3=L2/L4:L6=L5/L7:BOTTOM=L7 |
| PCIE_RX_P22 | RXS22-DIFF1 | PAIR | 1 | 5.38 | 5 | 10 | 5 | 50 | 6 | 33 | 12 | 12 | 12 | 12 | 6.62 | 85 Ohms | TOP=L2:L3=L2/L4:L6=L5/L7:BOTTOM=L7 |
| PCIE_RX_P22 | RXS22-DIFF1 | PAIR | 2 | 5.5 | 5 | 10 | 5 | 50 | 6 | 20 | 12 | 12 | 12 | 12 | 7.5 | 85 Ohms | TOP=L2:L3=L2/L4:L6=L5/L7:BOTTOM=L7 |
| PCIE_RX_P22 | RXS22-DIFF1 | PAIR | 3 | 5.5 | 5 | 10 | 5 | 50 | 6 | 20 | 12 | 12 | 12 | 12 | 7.5 | 85 Ohms | TOP=L2:L3=L2/L4:L6=L5/L7:BOTTOM=L7 |
| PCIE_RX_P22 | RXS22-DIFF1 | PAIR | 4 | 5.5 | 5 | 10 | 5 | 50 | 6 | 20 | 12 | 12 | 12 | 12 | 7.5 | 85 Ohms | TOP=L2:L3=L2/L4:L6=L5/L7:BOTTOM=L7 |
| PCIE_RX_P22 | RXS22-DIFF1 | PAIR | 5 | 5.5 | 5 | 10 | 5 | 50 | 6 | 20 | 12 | 12 | 12 | 12 | 7.5 | 85 Ohms | TOP=L2:L3=L2/L4:L6=L5/L7:BOTTOM=L7 |
| PCIE_RX_P22 | RXS22-DIFF1 | PAIR | 6 | 5.5 | 5 | 10 | 5 | 50 | 6 | 20 | 12 | 12 | 12 | 12 | 7.5 | 85 Ohms | TOP=L2:L3=L2/L4:L6=L5/L7:BOTTOM=L7 |
| PCIE_RX_P22 | RXS22-DIFF1 | PAIR | 7 | 5.5 | 5 | 10 | 5 | 50 | 6 | 20 | 12 | 12 | 12 | 12 | 7.5 | 85 Ohms | TOP=L2:L3=L2/L4:L6=L5/L7:BOTTOM=L7 |
| PCIE_RX_P22 | RXS22-DIFF1 | PAIR | 8 | 5.38 | 5 | 10 | 5 | 50 | 6 | 33 | 12 | 12 | 12 | 12 | 6.62 | 85 Ohms | TOP=L2:L3=L2/L4:L6=L5/L7:BOTTOM=L7 |
| PCIE_RX_N23 | RXS23-DIFF1 | PAIR | 1 | 5.38 | 5 | 10 | 5 | 50 | 6 | 33 | 12 | 12 | 12 | 12 | 6.62 | 85 Ohms | TOP=L2:L3=L2/L4:L6=L5/L7:BOTTOM=L7 |
| PCIE_RX_N23 | RXS23-DIFF1 | PAIR | 2 | 5.5 | 5 | 10 | 5 | 50 | 6 | 20 | 12 | 12 | 12 | 12 | 7.5 | 85 Ohms | TOP=L2:L3=L2/L4:L6=L5/L7:BOTTOM=L7 |
| PCIE_RX_N23 | RXS23-DIFF1 | PAIR | 3 | 5.5 | 5 | 10 | 5 | 50 | 6 | 20 | 12 | 12 | 12 | 12 | 7.5 | 85 Ohms | TOP=L2:L3=L2/L4:L6=L5/L7:BOTTOM=L7 |
| PCIE_RX_N23 | RXS23-DIFF1 | PAIR | 4 | 5.5 | 5 | 10 | 5 | 50 | 6 | 20 | 12 | 12 | 12 | 12 | 7.5 | 85 Ohms | TOP=L2:L3=L2/L4:L6=L5/L7:BOTTOM=L7 |
| PCIE_RX_N23 | RXS23-DIFF1 | PAIR | 5 | 5.5 | 5 | 10 | 5 | 50 | 6 | 20 | 12 | 12 | 12 | 12 | 7.5 | 85 Ohms | TOP=L2:L3=L2/L4:L6=L5/L7:BOTTOM=L7 |
| PCIE_RX_N23 | RXS23-DIFF1 | PAIR | 6 | 5.5 | 5 | 10 | 5 | 50 | 6 | 20 | 12 | 12 | 12 | 12 | 7.5 | 85 Ohms | TOP=L2:L3=L2/L4:L6=L5/L7:BOTTOM=L7 |
| PCIE_RX_N23 | RXS23-DIFF1 | PAIR | 7 | 5.5 | 5 | 10 | 5 | 50 | 6 | 20 | 12 | 12 | 12 | 12 | 7.5 | 85 Ohms | TOP=L2:L3=L2/L4:L6=L5/L7:BOTTOM=L7 |
| PCIE_RX_N23 | RXS23-DIFF1 | PAIR | 8 | 5.38 | 5 | 10 | 5 | 50 | 6 | 33 | 12 | 12 | 12 | 12 | 6.62 | 85 Ohms | TOP=L2:L3=L2/L4:L6=L5/L7:BOTTOM=L7 |
| PCIE_RX_P23 | RXS23-DIFF1 | PAIR | 1 | 5.38 | 5 | 10 | 5 | 50 | 6 | 33 | 12 | 12 | 12 | 12 | 6.62 | 85 Ohms | TOP=L2:L3=L2/L4:L6=L5/L7:BOTTOM=L7 |
| PCIE_RX_P23 | RXS23-DIFF1 | PAIR | 2 | 5.5 | 5 | 10 | 5 | 50 | 6 | 20 | 12 | 12 | 12 | 12 | 7.5 | 85 Ohms | TOP=L2:L3=L2/L4:L6=L5/L7:BOTTOM=L7 |
| PCIE_RX_P23 | RXS23-DIFF1 | PAIR | 3 | 5.5 | 5 | 10 | 5 | 50 | 6 | 20 | 12 | 12 | 12 | 12 | 7.5 | 85 Ohms | TOP=L2:L3=L2/L4:L6=L5/L7:BOTTOM=L7 |
| PCIE_RX_P23 | RXS23-DIFF1 | PAIR | 4 | 5.5 | 5 | 10 | 5 | 50 | 6 | 20 | 12 | 12 | 12 | 12 | 7.5 | 85 Ohms | TOP=L2:L3=L2/L4:L6=L5/L7:BOTTOM=L7 |
| PCIE_RX_P23 | RXS23-DIFF1 | PAIR | 5 | 5.5 | 5 | 10 | 5 | 50 | 6 | 20 | 12 | 12 | 12 | 12 | 7.5 | 85 Ohms | TOP=L2:L3=L2/L4:L6=L5/L7:BOTTOM=L7 |
| PCIE_RX_P23 | RXS23-DIFF1 | PAIR | 6 | 5.5 | 5 | 10 | 5 | 50 | 6 | 20 | 12 | 12 | 12 | 12 | 7.5 | 85 Ohms | TOP=L2:L3=L2/L4:L6=L5/L7:BOTTOM=L7 |
| PCIE_RX_P23 | RXS23-DIFF1 | PAIR | 7 | 5.5 | 5 | 10 | 5 | 50 | 6 | 20 | 12 | 12 | 12 | 12 | 7.5 | 85 Ohms | TOP=L2:L3=L2/L4:L6=L5/L7:BOTTOM=L7 |
| PCIE_RX_P23 | RXS23-DIFF1 | PAIR | 8 | 5.38 | 5 | 10 | 5 | 50 | 6 | 33 | 12 | 12 | 12 | 12 | 6.62 | 85 Ohms | TOP=L2:L3=L2/L4:L6=L5/L7:BOTTOM=L7 |
| PCIE_RX_N24 | RXS24-DIFF1 | PAIR | 1 | 5.38 | 5 | 10 | 5 | 50 | 6 | 33 | 12 | 12 | 12 | 12 | 6.62 | 85 Ohms | TOP=L2:L3=L2/L4:L6=L5/L7:BOTTOM=L7 |
| PCIE_RX_N24 | RXS24-DIFF1 | PAIR | 2 | 5.5 | 5 | 10 | 5 | 50 | 6 | 20 | 12 | 12 | 12 | 12 | 7.5 | 85 Ohms | TOP=L2:L3=L2/L4:L6=L5/L7:BOTTOM=L7 |
| PCIE_RX_N24 | RXS24-DIFF1 | PAIR | 3 | 5.5 | 5 | 10 | 5 | 50 | 6 | 20 | 12 | 12 | 12 | 12 | 7.5 | 85 Ohms | TOP=L2:L3=L2/L4:L6=L5/L7:BOTTOM=L7 |
| PCIE_RX_N24 | RXS24-DIFF1 | PAIR | 4 | 5.5 | 5 | 10 | 5 | 50 | 6 | 20 | 12 | 12 | 12 | 12 | 7.5 | 85 Ohms | TOP=L2:L3=L2/L4:L6=L5/L7:BOTTOM=L7 |
| PCIE_RX_N24 | RXS24-DIFF1 | PAIR | 5 | 5.5 | 5 | 10 | 5 | 50 | 6 | 20 | 12 | 12 | 12 | 12 | 7.5 | 85 Ohms | TOP=L2:L3=L2/L4:L6=L5/L7:BOTTOM=L7 |
| PCIE_RX_N24 | RXS24-DIFF1 | PAIR | 6 | 5.5 | 5 | 10 | 5 | 50 | 6 | 20 | 12 | 12 | 12 | 12 | 7.5 | 85 Ohms | TOP=L2:L3=L2/L4:L6=L5/L7:BOTTOM=L7 |
| PCIE_RX_N24 | RXS24-DIFF1 | PAIR | 7 | 5.5 | 5 | 10 | 5 | 50 | 6 | 20 | 12 | 12 | 12 | 12 | 7.5 | 85 Ohms | TOP=L2:L3=L2/L4:L6=L5/L7:BOTTOM=L7 |
| PCIE_RX_N24 | RXS24-DIFF1 | PAIR | 8 | 5.38 | 5 | 10 | 5 | 50 | 6 | 33 | 12 | 12 | 12 | 12 | 6.62 | 85 Ohms | TOP=L2:L3=L2/L4:L6=L5/L7:BOTTOM=L7 |
| PCIE_RX_P24 | RXS24-DIFF1 | PAIR | 1 | 5.38 | 5 | 10 | 5 | 50 | 6 | 33 | 12 | 12 | 12 | 12 | 6.62 | 85 Ohms | TOP=L2:L3=L2/L4:L6=L5/L7:BOTTOM=L7 |
| PCIE_RX_P24 | RXS24-DIFF1 | PAIR | 2 | 5.5 | 5 | 10 | 5 | 50 | 6 | 20 | 12 | 12 | 12 | 12 | 7.5 | 85 Ohms | TOP=L2:L3=L2/L4:L6=L5/L7:BOTTOM=L7 |
| PCIE_RX_P24 | RXS24-DIFF1 | PAIR | 3 | 5.5 | 5 | 10 | 5 | 50 | 6 | 20 | 12 | 12 | 12 | 12 | 7.5 | 85 Ohms | TOP=L2:L3=L2/L4:L6=L5/L7:BOTTOM=L7 |
| PCIE_RX_P24 | RXS24-DIFF1 | PAIR | 4 | 5.5 | 5 | 10 | 5 | 50 | 6 | 20 | 12 | 12 | 12 | 12 | 7.5 | 85 Ohms | TOP=L2:L3=L2/L4:L6=L5/L7:BOTTOM=L7 |
| PCIE_RX_P24 | RXS24-DIFF1 | PAIR | 5 | 5.5 | 5 | 10 | 5 | 50 | 6 | 20 | 12 | 12 | 12 | 12 | 7.5 | 85 Ohms | TOP=L2:L3=L2/L4:L6=L5/L7:BOTTOM=L7 |
| PCIE_RX_P24 | RXS24-DIFF1 | PAIR | 6 | 5.5 | 5 | 10 | 5 | 50 | 6 | 20 | 12 | 12 | 12 | 12 | 7.5 | 85 Ohms | TOP=L2:L3=L2/L4:L6=L5/L7:BOTTOM=L7 |
| PCIE_RX_P24 | RXS24-DIFF1 | PAIR | 7 | 5.5 | 5 | 10 | 5 | 50 | 6 | 20 | 12 | 12 | 12 | 12 | 7.5 | 85 Ohms | TOP=L2:L3=L2/L4:L6=L5/L7:BOTTOM=L7 |
| PCIE_RX_P24 | RXS24-DIFF1 | PAIR | 8 | 5.38 | 5 | 10 | 5 | 50 | 6 | 33 | 12 | 12 | 12 | 12 | 6.62 | 85 Ohms | TOP=L2:L3=L2/L4:L6=L5/L7:BOTTOM=L7 |
| PCIE_RX_N25 | RXS25-DIFF1 | PAIR | 1 | 5.38 | 5 | 10 | 5 | 50 | 6 | 33 | 12 | 12 | 12 | 12 | 6.62 | 85 Ohms | TOP=L2:L3=L2/L4:L6=L5/L7:BOTTOM=L7 |
| PCIE_RX_N25 | RXS25-DIFF1 | PAIR | 2 | 5.5 | 5 | 10 | 5 | 50 | 6 | 20 | 12 | 12 | 12 | 12 | 7.5 | 85 Ohms | TOP=L2:L3=L2/L4:L6=L5/L7:BOTTOM=L7 |
| PCIE_RX_N25 | RXS25-DIFF1 | PAIR | 3 | 5.5 | 5 | 10 | 5 | 50 | 6 | 20 | 12 | 12 | 12 | 12 | 7.5 | 85 Ohms | TOP=L2:L3=L2/L4:L6=L5/L7:BOTTOM=L7 |
| PCIE_RX_N25 | RXS25-DIFF1 | PAIR | 4 | 5.5 | 5 | 10 | 5 | 50 | 6 | 20 | 12 | 12 | 12 | 12 | 7.5 | 85 Ohms | TOP=L2:L3=L2/L4:L6=L5/L7:BOTTOM=L7 |
| PCIE_RX_N25 | RXS25-DIFF1 | PAIR | 5 | 5.5 | 5 | 10 | 5 | 50 | 6 | 20 | 12 | 12 | 12 | 12 | 7.5 | 85 Ohms | TOP=L2:L3=L2/L4:L6=L5/L7:BOTTOM=L7 |
| PCIE_RX_N25 | RXS25-DIFF1 | PAIR | 6 | 5.5 | 5 | 10 | 5 | 50 | 6 | 20 | 12 | 12 | 12 | 12 | 7.5 | 85 Ohms | TOP=L2:L3=L2/L4:L6=L5/L7:BOTTOM=L7 |
| PCIE_RX_N25 | RXS25-DIFF1 | PAIR | 7 | 5.5 | 5 | 10 | 5 | 50 | 6 | 20 | 12 | 12 | 12 | 12 | 7.5 | 85 Ohms | TOP=L2:L3=L2/L4:L6=L5/L7:BOTTOM=L7 |
| PCIE_RX_N25 | RXS25-DIFF1 | PAIR | 8 | 5.38 | 5 | 10 | 5 | 50 | 6 | 33 | 12 | 12 | 12 | 12 | 6.62 | 85 Ohms | TOP=L2:L3=L2/L4:L6=L5/L7:BOTTOM=L7 |
| PCIE_RX_P25 | RXS25-DIFF1 | PAIR | 1 | 5.38 | 5 | 10 | 5 | 50 | 6 | 33 | 12 | 12 | 12 | 12 | 6.62 | 85 Ohms | TOP=L2:L3=L2/L4:L6=L5/L7:BOTTOM=L7 |
| PCIE_RX_P25 | RXS25-DIFF1 | PAIR | 2 | 5.5 | 5 | 10 | 5 | 50 | 6 | 20 | 12 | 12 | 12 | 12 | 7.5 | 85 Ohms | TOP=L2:L3=L2/L4:L6=L5/L7:BOTTOM=L7 |
| PCIE_RX_P25 | RXS25-DIFF1 | PAIR | 3 | 5.5 | 5 | 10 | 5 | 50 | 6 | 20 | 12 | 12 | 12 | 12 | 7.5 | 85 Ohms | TOP=L2:L3=L2/L4:L6=L5/L7:BOTTOM=L7 |
| PCIE_RX_P25 | RXS25-DIFF1 | PAIR | 4 | 5.5 | 5 | 10 | 5 | 50 | 6 | 20 | 12 | 12 | 12 | 12 | 7.5 | 85 Ohms | TOP=L2:L3=L2/L4:L6=L5/L7:BOTTOM=L7 |
| PCIE_RX_P25 | RXS25-DIFF1 | PAIR | 5 | 5.5 | 5 | 10 | 5 | 50 | 6 | 20 | 12 | 12 | 12 | 12 | 7.5 | 85 Ohms | TOP=L2:L3=L2/L4:L6=L5/L7:BOTTOM=L7 |
| PCIE_RX_P25 | RXS25-DIFF1 | PAIR | 6 | 5.5 | 5 | 10 | 5 | 50 | 6 | 20 | 12 | 12 | 12 | 12 | 7.5 | 85 Ohms | TOP=L2:L3=L2/L4:L6=L5/L7:BOTTOM=L7 |
| PCIE_RX_P25 | RXS25-DIFF1 | PAIR | 7 | 5.5 | 5 | 10 | 5 | 50 | 6 | 20 | 12 | 12 | 12 | 12 | 7.5 | 85 Ohms | TOP=L2:L3=L2/L4:L6=L5/L7:BOTTOM=L7 |
| PCIE_RX_P25 | RXS25-DIFF1 | PAIR | 8 | 5.38 | 5 | 10 | 5 | 50 | 6 | 33 | 12 | 12 | 12 | 12 | 6.62 | 85 Ohms | TOP=L2:L3=L2/L4:L6=L5/L7:BOTTOM=L7 |
| PCIE_RX_N26 | RXS26-DIFF1 | PAIR | 1 | 5.38 | 5 | 10 | 5 | 50 | 6 | 33 | 12 | 12 | 12 | 12 | 6.62 | 85 Ohms | TOP=L2:L3=L2/L4:L6=L5/L7:BOTTOM=L7 |
| PCIE_RX_N26 | RXS26-DIFF1 | PAIR | 2 | 5.5 | 5 | 10 | 5 | 50 | 6 | 20 | 12 | 12 | 12 | 12 | 7.5 | 85 Ohms | TOP=L2:L3=L2/L4:L6=L5/L7:BOTTOM=L7 |
| PCIE_RX_N26 | RXS26-DIFF1 | PAIR | 3 | 5.5 | 5 | 10 | 5 | 50 | 6 | 20 | 12 | 12 | 12 | 12 | 7.5 | 85 Ohms | TOP=L2:L3=L2/L4:L6=L5/L7:BOTTOM=L7 |
| PCIE_RX_N26 | RXS26-DIFF1 | PAIR | 4 | 5.5 | 5 | 10 | 5 | 50 | 6 | 20 | 12 | 12 | 12 | 12 | 7.5 | 85 Ohms | TOP=L2:L3=L2/L4:L6=L5/L7:BOTTOM=L7 |
| PCIE_RX_N26 | RXS26-DIFF1 | PAIR | 5 | 5.5 | 5 | 10 | 5 | 50 | 6 | 20 | 12 | 12 | 12 | 12 | 7.5 | 85 Ohms | TOP=L2:L3=L2/L4:L6=L5/L7:BOTTOM=L7 |
| PCIE_RX_N26 | RXS26-DIFF1 | PAIR | 6 | 5.5 | 5 | 10 | 5 | 50 | 6 | 20 | 12 | 12 | 12 | 12 | 7.5 | 85 Ohms | TOP=L2:L3=L2/L4:L6=L5/L7:BOTTOM=L7 |
| PCIE_RX_N26 | RXS26-DIFF1 | PAIR | 7 | 5.5 | 5 | 10 | 5 | 50 | 6 | 20 | 12 | 12 | 12 | 12 | 7.5 | 85 Ohms | TOP=L2:L3=L2/L4:L6=L5/L7:BOTTOM=L7 |
| PCIE_RX_N26 | RXS26-DIFF1 | PAIR | 8 | 5.38 | 5 | 10 | 5 | 50 | 6 | 33 | 12 | 12 | 12 | 12 | 6.62 | 85 Ohms | TOP=L2:L3=L2/L4:L6=L5/L7:BOTTOM=L7 |
| PCIE_RX_P26 | RXS26-DIFF1 | PAIR | 1 | 5.38 | 5 | 10 | 5 | 50 | 6 | 33 | 12 | 12 | 12 | 12 | 6.62 | 85 Ohms | TOP=L2:L3=L2/L4:L6=L5/L7:BOTTOM=L7 |
| PCIE_RX_P26 | RXS26-DIFF1 | PAIR | 2 | 5.5 | 5 | 10 | 5 | 50 | 6 | 20 | 12 | 12 | 12 | 12 | 7.5 | 85 Ohms | TOP=L2:L3=L2/L4:L6=L5/L7:BOTTOM=L7 |
| PCIE_RX_P26 | RXS26-DIFF1 | PAIR | 3 | 5.5 | 5 | 10 | 5 | 50 | 6 | 20 | 12 | 12 | 12 | 12 | 7.5 | 85 Ohms | TOP=L2:L3=L2/L4:L6=L5/L7:BOTTOM=L7 |
| PCIE_RX_P26 | RXS26-DIFF1 | PAIR | 4 | 5.5 | 5 | 10 | 5 | 50 | 6 | 20 | 12 | 12 | 12 | 12 | 7.5 | 85 Ohms | TOP=L2:L3=L2/L4:L6=L5/L7:BOTTOM=L7 |
| PCIE_RX_P26 | RXS26-DIFF1 | PAIR | 5 | 5.5 | 5 | 10 | 5 | 50 | 6 | 20 | 12 | 12 | 12 | 12 | 7.5 | 85 Ohms | TOP=L2:L3=L2/L4:L6=L5/L7:BOTTOM=L7 |
| PCIE_RX_P26 | RXS26-DIFF1 | PAIR | 6 | 5.5 | 5 | 10 | 5 | 50 | 6 | 20 | 12 | 12 | 12 | 12 | 7.5 | 85 Ohms | TOP=L2:L3=L2/L4:L6=L5/L7:BOTTOM=L7 |
| PCIE_RX_P26 | RXS26-DIFF1 | PAIR | 7 | 5.5 | 5 | 10 | 5 | 50 | 6 | 20 | 12 | 12 | 12 | 12 | 7.5 | 85 Ohms | TOP=L2:L3=L2/L4:L6=L5/L7:BOTTOM=L7 |
| PCIE_RX_P26 | RXS26-DIFF1 | PAIR | 8 | 5.38 | 5 | 10 | 5 | 50 | 6 | 33 | 12 | 12 | 12 | 12 | 6.62 | 85 Ohms | TOP=L2:L3=L2/L4:L6=L5/L7:BOTTOM=L7 |
| PCIE_RX_N27 | RXS27-DIFF1 | PAIR | 1 | 5.38 | 5 | 10 | 5 | 50 | 6 | 33 | 12 | 12 | 12 | 12 | 6.62 | 85 Ohms | TOP=L2:L3=L2/L4:L6=L5/L7:BOTTOM=L7 |
| PCIE_RX_N27 | RXS27-DIFF1 | PAIR | 2 | 5.5 | 5 | 10 | 5 | 50 | 6 | 20 | 12 | 12 | 12 | 12 | 7.5 | 85 Ohms | TOP=L2:L3=L2/L4:L6=L5/L7:BOTTOM=L7 |
| PCIE_RX_N27 | RXS27-DIFF1 | PAIR | 3 | 5.5 | 5 | 10 | 5 | 50 | 6 | 20 | 12 | 12 | 12 | 12 | 7.5 | 85 Ohms | TOP=L2:L3=L2/L4:L6=L5/L7:BOTTOM=L7 |
| PCIE_RX_N27 | RXS27-DIFF1 | PAIR | 4 | 5.5 | 5 | 10 | 5 | 50 | 6 | 20 | 12 | 12 | 12 | 12 | 7.5 | 85 Ohms | TOP=L2:L3=L2/L4:L6=L5/L7:BOTTOM=L7 |
| PCIE_RX_N27 | RXS27-DIFF1 | PAIR | 5 | 5.5 | 5 | 10 | 5 | 50 | 6 | 20 | 12 | 12 | 12 | 12 | 7.5 | 85 Ohms | TOP=L2:L3=L2/L4:L6=L5/L7:BOTTOM=L7 |
| PCIE_RX_N27 | RXS27-DIFF1 | PAIR | 6 | 5.5 | 5 | 10 | 5 | 50 | 6 | 20 | 12 | 12 | 12 | 12 | 7.5 | 85 Ohms | TOP=L2:L3=L2/L4:L6=L5/L7:BOTTOM=L7 |
| PCIE_RX_N27 | RXS27-DIFF1 | PAIR | 7 | 5.5 | 5 | 10 | 5 | 50 | 6 | 20 | 12 | 12 | 12 | 12 | 7.5 | 85 Ohms | TOP=L2:L3=L2/L4:L6=L5/L7:BOTTOM=L7 |
| PCIE_RX_N27 | RXS27-DIFF1 | PAIR | 8 | 5.38 | 5 | 10 | 5 | 50 | 6 | 33 | 12 | 12 | 12 | 12 | 6.62 | 85 Ohms | TOP=L2:L3=L2/L4:L6=L5/L7:BOTTOM=L7 |
| PCIE_RX_P27 | RXS27-DIFF1 | PAIR | 1 | 5.38 | 5 | 10 | 5 | 50 | 6 | 33 | 12 | 12 | 12 | 12 | 6.62 | 85 Ohms | TOP=L2:L3=L2/L4:L6=L5/L7:BOTTOM=L7 |
| PCIE_RX_P27 | RXS27-DIFF1 | PAIR | 2 | 5.5 | 5 | 10 | 5 | 50 | 6 | 20 | 12 | 12 | 12 | 12 | 7.5 | 85 Ohms | TOP=L2:L3=L2/L4:L6=L5/L7:BOTTOM=L7 |
| PCIE_RX_P27 | RXS27-DIFF1 | PAIR | 3 | 5.5 | 5 | 10 | 5 | 50 | 6 | 20 | 12 | 12 | 12 | 12 | 7.5 | 85 Ohms | TOP=L2:L3=L2/L4:L6=L5/L7:BOTTOM=L7 |
| PCIE_RX_P27 | RXS27-DIFF1 | PAIR | 4 | 5.5 | 5 | 10 | 5 | 50 | 6 | 20 | 12 | 12 | 12 | 12 | 7.5 | 85 Ohms | TOP=L2:L3=L2/L4:L6=L5/L7:BOTTOM=L7 |
| PCIE_RX_P27 | RXS27-DIFF1 | PAIR | 5 | 5.5 | 5 | 10 | 5 | 50 | 6 | 20 | 12 | 12 | 12 | 12 | 7.5 | 85 Ohms | TOP=L2:L3=L2/L4:L6=L5/L7:BOTTOM=L7 |
| PCIE_RX_P27 | RXS27-DIFF1 | PAIR | 6 | 5.5 | 5 | 10 | 5 | 50 | 6 | 20 | 12 | 12 | 12 | 12 | 7.5 | 85 Ohms | TOP=L2:L3=L2/L4:L6=L5/L7:BOTTOM=L7 |
| PCIE_RX_P27 | RXS27-DIFF1 | PAIR | 7 | 5.5 | 5 | 10 | 5 | 50 | 6 | 20 | 12 | 12 | 12 | 12 | 7.5 | 85 Ohms | TOP=L2:L3=L2/L4:L6=L5/L7:BOTTOM=L7 |
| PCIE_RX_P27 | RXS27-DIFF1 | PAIR | 8 | 5.38 | 5 | 10 | 5 | 50 | 6 | 33 | 12 | 12 | 12 | 12 | 6.62 | 85 Ohms | TOP=L2:L3=L2/L4:L6=L5/L7:BOTTOM=L7 |
| PCIE_RX_N28 | RXS28-DIFF1 | PAIR | 1 | 5.38 | 5 | 10 | 5 | 50 | 6 | 33 | 12 | 12 | 12 | 12 | 6.62 | 85 Ohms | TOP=L2:L3=L2/L4:L6=L5/L7:BOTTOM=L7 |
| PCIE_RX_N28 | RXS28-DIFF1 | PAIR | 2 | 5.5 | 5 | 10 | 5 | 50 | 6 | 20 | 12 | 12 | 12 | 12 | 7.5 | 85 Ohms | TOP=L2:L3=L2/L4:L6=L5/L7:BOTTOM=L7 |
| PCIE_RX_N28 | RXS28-DIFF1 | PAIR | 3 | 5.5 | 5 | 10 | 5 | 50 | 6 | 20 | 12 | 12 | 12 | 12 | 7.5 | 85 Ohms | TOP=L2:L3=L2/L4:L6=L5/L7:BOTTOM=L7 |
| PCIE_RX_N28 | RXS28-DIFF1 | PAIR | 4 | 5.5 | 5 | 10 | 5 | 50 | 6 | 20 | 12 | 12 | 12 | 12 | 7.5 | 85 Ohms | TOP=L2:L3=L2/L4:L6=L5/L7:BOTTOM=L7 |
| PCIE_RX_N28 | RXS28-DIFF1 | PAIR | 5 | 5.5 | 5 | 10 | 5 | 50 | 6 | 20 | 12 | 12 | 12 | 12 | 7.5 | 85 Ohms | TOP=L2:L3=L2/L4:L6=L5/L7:BOTTOM=L7 |
| PCIE_RX_N28 | RXS28-DIFF1 | PAIR | 6 | 5.5 | 5 | 10 | 5 | 50 | 6 | 20 | 12 | 12 | 12 | 12 | 7.5 | 85 Ohms | TOP=L2:L3=L2/L4:L6=L5/L7:BOTTOM=L7 |
| PCIE_RX_N28 | RXS28-DIFF1 | PAIR | 7 | 5.5 | 5 | 10 | 5 | 50 | 6 | 20 | 12 | 12 | 12 | 12 | 7.5 | 85 Ohms | TOP=L2:L3=L2/L4:L6=L5/L7:BOTTOM=L7 |
| PCIE_RX_N28 | RXS28-DIFF1 | PAIR | 8 | 5.38 | 5 | 10 | 5 | 50 | 6 | 33 | 12 | 12 | 12 | 12 | 6.62 | 85 Ohms | TOP=L2:L3=L2/L4:L6=L5/L7:BOTTOM=L7 |
| PCIE_RX_P28 | RXS28-DIFF1 | PAIR | 1 | 5.38 | 5 | 10 | 5 | 50 | 6 | 33 | 12 | 12 | 12 | 12 | 6.62 | 85 Ohms | TOP=L2:L3=L2/L4:L6=L5/L7:BOTTOM=L7 |
| PCIE_RX_P28 | RXS28-DIFF1 | PAIR | 2 | 5.5 | 5 | 10 | 5 | 50 | 6 | 20 | 12 | 12 | 12 | 12 | 7.5 | 85 Ohms | TOP=L2:L3=L2/L4:L6=L5/L7:BOTTOM=L7 |
| PCIE_RX_P28 | RXS28-DIFF1 | PAIR | 3 | 5.5 | 5 | 10 | 5 | 50 | 6 | 20 | 12 | 12 | 12 | 12 | 7.5 | 85 Ohms | TOP=L2:L3=L2/L4:L6=L5/L7:BOTTOM=L7 |
| PCIE_RX_P28 | RXS28-DIFF1 | PAIR | 4 | 5.5 | 5 | 10 | 5 | 50 | 6 | 20 | 12 | 12 | 12 | 12 | 7.5 | 85 Ohms | TOP=L2:L3=L2/L4:L6=L5/L7:BOTTOM=L7 |
| PCIE_RX_P28 | RXS28-DIFF1 | PAIR | 5 | 5.5 | 5 | 10 | 5 | 50 | 6 | 20 | 12 | 12 | 12 | 12 | 7.5 | 85 Ohms | TOP=L2:L3=L2/L4:L6=L5/L7:BOTTOM=L7 |
| PCIE_RX_P28 | RXS28-DIFF1 | PAIR | 6 | 5.5 | 5 | 10 | 5 | 50 | 6 | 20 | 12 | 12 | 12 | 12 | 7.5 | 85 Ohms | TOP=L2:L3=L2/L4:L6=L5/L7:BOTTOM=L7 |
| PCIE_RX_P28 | RXS28-DIFF1 | PAIR | 7 | 5.5 | 5 | 10 | 5 | 50 | 6 | 20 | 12 | 12 | 12 | 12 | 7.5 | 85 Ohms | TOP=L2:L3=L2/L4:L6=L5/L7:BOTTOM=L7 |
| PCIE_RX_P28 | RXS28-DIFF1 | PAIR | 8 | 5.38 | 5 | 10 | 5 | 50 | 6 | 33 | 12 | 12 | 12 | 12 | 6.62 | 85 Ohms | TOP=L2:L3=L2/L4:L6=L5/L7:BOTTOM=L7 |
| PCIE_RX_N29 | RXS29-DIFF1 | PAIR | 1 | 5.38 | 5 | 10 | 5 | 50 | 6 | 33 | 12 | 12 | 12 | 12 | 6.62 | 85 Ohms | TOP=L2:L3=L2/L4:L6=L5/L7:BOTTOM=L7 |
| PCIE_RX_N29 | RXS29-DIFF1 | PAIR | 2 | 5.5 | 5 | 10 | 5 | 50 | 6 | 20 | 12 | 12 | 12 | 12 | 7.5 | 85 Ohms | TOP=L2:L3=L2/L4:L6=L5/L7:BOTTOM=L7 |
| PCIE_RX_N29 | RXS29-DIFF1 | PAIR | 3 | 5.5 | 5 | 10 | 5 | 50 | 6 | 20 | 12 | 12 | 12 | 12 | 7.5 | 85 Ohms | TOP=L2:L3=L2/L4:L6=L5/L7:BOTTOM=L7 |
| PCIE_RX_N29 | RXS29-DIFF1 | PAIR | 4 | 5.5 | 5 | 10 | 5 | 50 | 6 | 20 | 12 | 12 | 12 | 12 | 7.5 | 85 Ohms | TOP=L2:L3=L2/L4:L6=L5/L7:BOTTOM=L7 |
| PCIE_RX_N29 | RXS29-DIFF1 | PAIR | 5 | 5.5 | 5 | 10 | 5 | 50 | 6 | 20 | 12 | 12 | 12 | 12 | 7.5 | 85 Ohms | TOP=L2:L3=L2/L4:L6=L5/L7:BOTTOM=L7 |
| PCIE_RX_N29 | RXS29-DIFF1 | PAIR | 6 | 5.5 | 5 | 10 | 5 | 50 | 6 | 20 | 12 | 12 | 12 | 12 | 7.5 | 85 Ohms | TOP=L2:L3=L2/L4:L6=L5/L7:BOTTOM=L7 |
| PCIE_RX_N29 | RXS29-DIFF1 | PAIR | 7 | 5.5 | 5 | 10 | 5 | 50 | 6 | 20 | 12 | 12 | 12 | 12 | 7.5 | 85 Ohms | TOP=L2:L3=L2/L4:L6=L5/L7:BOTTOM=L7 |
| PCIE_RX_N29 | RXS29-DIFF1 | PAIR | 8 | 5.38 | 5 | 10 | 5 | 50 | 6 | 33 | 12 | 12 | 12 | 12 | 6.62 | 85 Ohms | TOP=L2:L3=L2/L4:L6=L5/L7:BOTTOM=L7 |
| PCIE_RX_P29 | RXS29-DIFF1 | PAIR | 1 | 5.38 | 5 | 10 | 5 | 50 | 6 | 33 | 12 | 12 | 12 | 12 | 6.62 | 85 Ohms | TOP=L2:L3=L2/L4:L6=L5/L7:BOTTOM=L7 |
| PCIE_RX_P29 | RXS29-DIFF1 | PAIR | 2 | 5.5 | 5 | 10 | 5 | 50 | 6 | 20 | 12 | 12 | 12 | 12 | 7.5 | 85 Ohms | TOP=L2:L3=L2/L4:L6=L5/L7:BOTTOM=L7 |
| PCIE_RX_P29 | RXS29-DIFF1 | PAIR | 3 | 5.5 | 5 | 10 | 5 | 50 | 6 | 20 | 12 | 12 | 12 | 12 | 7.5 | 85 Ohms | TOP=L2:L3=L2/L4:L6=L5/L7:BOTTOM=L7 |
| PCIE_RX_P29 | RXS29-DIFF1 | PAIR | 4 | 5.5 | 5 | 10 | 5 | 50 | 6 | 20 | 12 | 12 | 12 | 12 | 7.5 | 85 Ohms | TOP=L2:L3=L2/L4:L6=L5/L7:BOTTOM=L7 |
| PCIE_RX_P29 | RXS29-DIFF1 | PAIR | 5 | 5.5 | 5 | 10 | 5 | 50 | 6 | 20 | 12 | 12 | 12 | 12 | 7.5 | 85 Ohms | TOP=L2:L3=L2/L4:L6=L5/L7:BOTTOM=L7 |
| PCIE_RX_P29 | RXS29-DIFF1 | PAIR | 6 | 5.5 | 5 | 10 | 5 | 50 | 6 | 20 | 12 | 12 | 12 | 12 | 7.5 | 85 Ohms | TOP=L2:L3=L2/L4:L6=L5/L7:BOTTOM=L7 |
| PCIE_RX_P29 | RXS29-DIFF1 | PAIR | 7 | 5.5 | 5 | 10 | 5 | 50 | 6 | 20 | 12 | 12 | 12 | 12 | 7.5 | 85 Ohms | TOP=L2:L3=L2/L4:L6=L5/L7:BOTTOM=L7 |
| PCIE_RX_P29 | RXS29-DIFF1 | PAIR | 8 | 5.38 | 5 | 10 | 5 | 50 | 6 | 33 | 12 | 12 | 12 | 12 | 6.62 | 85 Ohms | TOP=L2:L3=L2/L4:L6=L5/L7:BOTTOM=L7 |
| PCIE_RX_N2 | RXS2-DIFF1 | PAIR | 1 | 5.38 | 5 | 10 | 5 | 50 | 6 | 33 | 12 | 12 | 12 | 12 | 6.62 | 85 Ohms | TOP=L2:L3=L2/L4:L6=L5/L7:BOTTOM=L7 |
| PCIE_RX_N2 | RXS2-DIFF1 | PAIR | 2 | 5.5 | 5 | 10 | 5 | 50 | 6 | 20 | 12 | 12 | 12 | 12 | 7.5 | 85 Ohms | TOP=L2:L3=L2/L4:L6=L5/L7:BOTTOM=L7 |
| PCIE_RX_N2 | RXS2-DIFF1 | PAIR | 3 | 5.5 | 5 | 10 | 5 | 50 | 6 | 20 | 12 | 12 | 12 | 12 | 7.5 | 85 Ohms | TOP=L2:L3=L2/L4:L6=L5/L7:BOTTOM=L7 |
| PCIE_RX_N2 | RXS2-DIFF1 | PAIR | 4 | 5.5 | 5 | 10 | 5 | 50 | 6 | 20 | 12 | 12 | 12 | 12 | 7.5 | 85 Ohms | TOP=L2:L3=L2/L4:L6=L5/L7:BOTTOM=L7 |
| PCIE_RX_N2 | RXS2-DIFF1 | PAIR | 5 | 5.5 | 5 | 10 | 5 | 50 | 6 | 20 | 12 | 12 | 12 | 12 | 7.5 | 85 Ohms | TOP=L2:L3=L2/L4:L6=L5/L7:BOTTOM=L7 |
| PCIE_RX_N2 | RXS2-DIFF1 | PAIR | 6 | 5.5 | 5 | 10 | 5 | 50 | 6 | 20 | 12 | 12 | 12 | 12 | 7.5 | 85 Ohms | TOP=L2:L3=L2/L4:L6=L5/L7:BOTTOM=L7 |
| PCIE_RX_N2 | RXS2-DIFF1 | PAIR | 7 | 5.5 | 5 | 10 | 5 | 50 | 6 | 20 | 12 | 12 | 12 | 12 | 7.5 | 85 Ohms | TOP=L2:L3=L2/L4:L6=L5/L7:BOTTOM=L7 |
| PCIE_RX_N2 | RXS2-DIFF1 | PAIR | 8 | 5.38 | 5 | 10 | 5 | 50 | 6 | 33 | 12 | 12 | 12 | 12 | 6.62 | 85 Ohms | TOP=L2:L3=L2/L4:L6=L5/L7:BOTTOM=L7 |
| PCIE_RX_P2 | RXS2-DIFF1 | PAIR | 1 | 5.38 | 5 | 10 | 5 | 50 | 6 | 33 | 12 | 12 | 12 | 12 | 6.62 | 85 Ohms | TOP=L2:L3=L2/L4:L6=L5/L7:BOTTOM=L7 |
| PCIE_RX_P2 | RXS2-DIFF1 | PAIR | 2 | 5.5 | 5 | 10 | 5 | 50 | 6 | 20 | 12 | 12 | 12 | 12 | 7.5 | 85 Ohms | TOP=L2:L3=L2/L4:L6=L5/L7:BOTTOM=L7 |
| PCIE_RX_P2 | RXS2-DIFF1 | PAIR | 3 | 5.5 | 5 | 10 | 5 | 50 | 6 | 20 | 12 | 12 | 12 | 12 | 7.5 | 85 Ohms | TOP=L2:L3=L2/L4:L6=L5/L7:BOTTOM=L7 |
| PCIE_RX_P2 | RXS2-DIFF1 | PAIR | 4 | 5.5 | 5 | 10 | 5 | 50 | 6 | 20 | 12 | 12 | 12 | 12 | 7.5 | 85 Ohms | TOP=L2:L3=L2/L4:L6=L5/L7:BOTTOM=L7 |
| PCIE_RX_P2 | RXS2-DIFF1 | PAIR | 5 | 5.5 | 5 | 10 | 5 | 50 | 6 | 20 | 12 | 12 | 12 | 12 | 7.5 | 85 Ohms | TOP=L2:L3=L2/L4:L6=L5/L7:BOTTOM=L7 |
| PCIE_RX_P2 | RXS2-DIFF1 | PAIR | 6 | 5.5 | 5 | 10 | 5 | 50 | 6 | 20 | 12 | 12 | 12 | 12 | 7.5 | 85 Ohms | TOP=L2:L3=L2/L4:L6=L5/L7:BOTTOM=L7 |
| PCIE_RX_P2 | RXS2-DIFF1 | PAIR | 7 | 5.5 | 5 | 10 | 5 | 50 | 6 | 20 | 12 | 12 | 12 | 12 | 7.5 | 85 Ohms | TOP=L2:L3=L2/L4:L6=L5/L7:BOTTOM=L7 |
| PCIE_RX_P2 | RXS2-DIFF1 | PAIR | 8 | 5.38 | 5 | 10 | 5 | 50 | 6 | 33 | 12 | 12 | 12 | 12 | 6.62 | 85 Ohms | TOP=L2:L3=L2/L4:L6=L5/L7:BOTTOM=L7 |
| PCIE_RX_N30 | RXS30-DIFF1 | PAIR | 1 | 5.38 | 5 | 10 | 5 | 50 | 6 | 33 | 12 | 12 | 12 | 12 | 6.62 | 85 Ohms | TOP=L2:L3=L2/L4:L6=L5/L7:BOTTOM=L7 |
| PCIE_RX_N30 | RXS30-DIFF1 | PAIR | 2 | 5.5 | 5 | 10 | 5 | 50 | 6 | 20 | 12 | 12 | 12 | 12 | 7.5 | 85 Ohms | TOP=L2:L3=L2/L4:L6=L5/L7:BOTTOM=L7 |
| PCIE_RX_N30 | RXS30-DIFF1 | PAIR | 3 | 5.5 | 5 | 10 | 5 | 50 | 6 | 20 | 12 | 12 | 12 | 12 | 7.5 | 85 Ohms | TOP=L2:L3=L2/L4:L6=L5/L7:BOTTOM=L7 |
| PCIE_RX_N30 | RXS30-DIFF1 | PAIR | 4 | 5.5 | 5 | 10 | 5 | 50 | 6 | 20 | 12 | 12 | 12 | 12 | 7.5 | 85 Ohms | TOP=L2:L3=L2/L4:L6=L5/L7:BOTTOM=L7 |
| PCIE_RX_N30 | RXS30-DIFF1 | PAIR | 5 | 5.5 | 5 | 10 | 5 | 50 | 6 | 20 | 12 | 12 | 12 | 12 | 7.5 | 85 Ohms | TOP=L2:L3=L2/L4:L6=L5/L7:BOTTOM=L7 |
| PCIE_RX_N30 | RXS30-DIFF1 | PAIR | 6 | 5.5 | 5 | 10 | 5 | 50 | 6 | 20 | 12 | 12 | 12 | 12 | 7.5 | 85 Ohms | TOP=L2:L3=L2/L4:L6=L5/L7:BOTTOM=L7 |
| PCIE_RX_N30 | RXS30-DIFF1 | PAIR | 7 | 5.5 | 5 | 10 | 5 | 50 | 6 | 20 | 12 | 12 | 12 | 12 | 7.5 | 85 Ohms | TOP=L2:L3=L2/L4:L6=L5/L7:BOTTOM=L7 |
| PCIE_RX_N30 | RXS30-DIFF1 | PAIR | 8 | 5.38 | 5 | 10 | 5 | 50 | 6 | 33 | 12 | 12 | 12 | 12 | 6.62 | 85 Ohms | TOP=L2:L3=L2/L4:L6=L5/L7:BOTTOM=L7 |
| PCIE_RX_P30 | RXS30-DIFF1 | PAIR | 1 | 5.38 | 5 | 10 | 5 | 50 | 6 | 33 | 12 | 12 | 12 | 12 | 6.62 | 85 Ohms | TOP=L2:L3=L2/L4:L6=L5/L7:BOTTOM=L7 |
| PCIE_RX_P30 | RXS30-DIFF1 | PAIR | 2 | 5.5 | 5 | 10 | 5 | 50 | 6 | 20 | 12 | 12 | 12 | 12 | 7.5 | 85 Ohms | TOP=L2:L3=L2/L4:L6=L5/L7:BOTTOM=L7 |
| PCIE_RX_P30 | RXS30-DIFF1 | PAIR | 3 | 5.5 | 5 | 10 | 5 | 50 | 6 | 20 | 12 | 12 | 12 | 12 | 7.5 | 85 Ohms | TOP=L2:L3=L2/L4:L6=L5/L7:BOTTOM=L7 |
| PCIE_RX_P30 | RXS30-DIFF1 | PAIR | 4 | 5.5 | 5 | 10 | 5 | 50 | 6 | 20 | 12 | 12 | 12 | 12 | 7.5 | 85 Ohms | TOP=L2:L3=L2/L4:L6=L5/L7:BOTTOM=L7 |
| PCIE_RX_P30 | RXS30-DIFF1 | PAIR | 5 | 5.5 | 5 | 10 | 5 | 50 | 6 | 20 | 12 | 12 | 12 | 12 | 7.5 | 85 Ohms | TOP=L2:L3=L2/L4:L6=L5/L7:BOTTOM=L7 |
| PCIE_RX_P30 | RXS30-DIFF1 | PAIR | 6 | 5.5 | 5 | 10 | 5 | 50 | 6 | 20 | 12 | 12 | 12 | 12 | 7.5 | 85 Ohms | TOP=L2:L3=L2/L4:L6=L5/L7:BOTTOM=L7 |
| PCIE_RX_P30 | RXS30-DIFF1 | PAIR | 7 | 5.5 | 5 | 10 | 5 | 50 | 6 | 20 | 12 | 12 | 12 | 12 | 7.5 | 85 Ohms | TOP=L2:L3=L2/L4:L6=L5/L7:BOTTOM=L7 |
| PCIE_RX_P30 | RXS30-DIFF1 | PAIR | 8 | 5.38 | 5 | 10 | 5 | 50 | 6 | 33 | 12 | 12 | 12 | 12 | 6.62 | 85 Ohms | TOP=L2:L3=L2/L4:L6=L5/L7:BOTTOM=L7 |
| PCIE_RX_N31 | RXS31-DIFF1 | PAIR | 1 | 5.38 | 5 | 10 | 5 | 50 | 6 | 33 | 12 | 12 | 12 | 12 | 6.62 | 85 Ohms | TOP=L2:L3=L2/L4:L6=L5/L7:BOTTOM=L7 |
| PCIE_RX_N31 | RXS31-DIFF1 | PAIR | 2 | 5.5 | 5 | 10 | 5 | 50 | 6 | 20 | 12 | 12 | 12 | 12 | 7.5 | 85 Ohms | TOP=L2:L3=L2/L4:L6=L5/L7:BOTTOM=L7 |
| PCIE_RX_N31 | RXS31-DIFF1 | PAIR | 3 | 5.5 | 5 | 10 | 5 | 50 | 6 | 20 | 12 | 12 | 12 | 12 | 7.5 | 85 Ohms | TOP=L2:L3=L2/L4:L6=L5/L7:BOTTOM=L7 |
| PCIE_RX_N31 | RXS31-DIFF1 | PAIR | 4 | 5.5 | 5 | 10 | 5 | 50 | 6 | 20 | 12 | 12 | 12 | 12 | 7.5 | 85 Ohms | TOP=L2:L3=L2/L4:L6=L5/L7:BOTTOM=L7 |
| PCIE_RX_N31 | RXS31-DIFF1 | PAIR | 5 | 5.5 | 5 | 10 | 5 | 50 | 6 | 20 | 12 | 12 | 12 | 12 | 7.5 | 85 Ohms | TOP=L2:L3=L2/L4:L6=L5/L7:BOTTOM=L7 |
| PCIE_RX_N31 | RXS31-DIFF1 | PAIR | 6 | 5.5 | 5 | 10 | 5 | 50 | 6 | 20 | 12 | 12 | 12 | 12 | 7.5 | 85 Ohms | TOP=L2:L3=L2/L4:L6=L5/L7:BOTTOM=L7 |
| PCIE_RX_N31 | RXS31-DIFF1 | PAIR | 7 | 5.5 | 5 | 10 | 5 | 50 | 6 | 20 | 12 | 12 | 12 | 12 | 7.5 | 85 Ohms | TOP=L2:L3=L2/L4:L6=L5/L7:BOTTOM=L7 |
| PCIE_RX_N31 | RXS31-DIFF1 | PAIR | 8 | 5.38 | 5 | 10 | 5 | 50 | 6 | 33 | 12 | 12 | 12 | 12 | 6.62 | 85 Ohms | TOP=L2:L3=L2/L4:L6=L5/L7:BOTTOM=L7 |
| PCIE_RX_P31 | RXS31-DIFF1 | PAIR | 1 | 5.38 | 5 | 10 | 5 | 50 | 6 | 33 | 12 | 12 | 12 | 12 | 6.62 | 85 Ohms | TOP=L2:L3=L2/L4:L6=L5/L7:BOTTOM=L7 |
| PCIE_RX_P31 | RXS31-DIFF1 | PAIR | 2 | 5.5 | 5 | 10 | 5 | 50 | 6 | 20 | 12 | 12 | 12 | 12 | 7.5 | 85 Ohms | TOP=L2:L3=L2/L4:L6=L5/L7:BOTTOM=L7 |
| PCIE_RX_P31 | RXS31-DIFF1 | PAIR | 3 | 5.5 | 5 | 10 | 5 | 50 | 6 | 20 | 12 | 12 | 12 | 12 | 7.5 | 85 Ohms | TOP=L2:L3=L2/L4:L6=L5/L7:BOTTOM=L7 |
| PCIE_RX_P31 | RXS31-DIFF1 | PAIR | 4 | 5.5 | 5 | 10 | 5 | 50 | 6 | 20 | 12 | 12 | 12 | 12 | 7.5 | 85 Ohms | TOP=L2:L3=L2/L4:L6=L5/L7:BOTTOM=L7 |
| PCIE_RX_P31 | RXS31-DIFF1 | PAIR | 5 | 5.5 | 5 | 10 | 5 | 50 | 6 | 20 | 12 | 12 | 12 | 12 | 7.5 | 85 Ohms | TOP=L2:L3=L2/L4:L6=L5/L7:BOTTOM=L7 |
| PCIE_RX_P31 | RXS31-DIFF1 | PAIR | 6 | 5.5 | 5 | 10 | 5 | 50 | 6 | 20 | 12 | 12 | 12 | 12 | 7.5 | 85 Ohms | TOP=L2:L3=L2/L4:L6=L5/L7:BOTTOM=L7 |
| PCIE_RX_P31 | RXS31-DIFF1 | PAIR | 7 | 5.5 | 5 | 10 | 5 | 50 | 6 | 20 | 12 | 12 | 12 | 12 | 7.5 | 85 Ohms | TOP=L2:L3=L2/L4:L6=L5/L7:BOTTOM=L7 |
| PCIE_RX_P31 | RXS31-DIFF1 | PAIR | 8 | 5.38 | 5 | 10 | 5 | 50 | 6 | 33 | 12 | 12 | 12 | 12 | 6.62 | 85 Ohms | TOP=L2:L3=L2/L4:L6=L5/L7:BOTTOM=L7 |
| PCIE_RX_N32 | RXS32-DIFF1 | PAIR | 1 | 5.38 | 5 | 10 | 5 | 50 | 6 | 33 | 12 | 12 | 12 | 12 | 6.62 | 85 Ohms | TOP=L2:L3=L2/L4:L6=L5/L7:BOTTOM=L7 |
| PCIE_RX_N32 | RXS32-DIFF1 | PAIR | 2 | 5.5 | 5 | 10 | 5 | 50 | 6 | 20 | 12 | 12 | 12 | 12 | 7.5 | 85 Ohms | TOP=L2:L3=L2/L4:L6=L5/L7:BOTTOM=L7 |
| PCIE_RX_N32 | RXS32-DIFF1 | PAIR | 3 | 5.5 | 5 | 10 | 5 | 50 | 6 | 20 | 12 | 12 | 12 | 12 | 7.5 | 85 Ohms | TOP=L2:L3=L2/L4:L6=L5/L7:BOTTOM=L7 |
| PCIE_RX_N32 | RXS32-DIFF1 | PAIR | 4 | 5.5 | 5 | 10 | 5 | 50 | 6 | 20 | 12 | 12 | 12 | 12 | 7.5 | 85 Ohms | TOP=L2:L3=L2/L4:L6=L5/L7:BOTTOM=L7 |
| PCIE_RX_N32 | RXS32-DIFF1 | PAIR | 5 | 5.5 | 5 | 10 | 5 | 50 | 6 | 20 | 12 | 12 | 12 | 12 | 7.5 | 85 Ohms | TOP=L2:L3=L2/L4:L6=L5/L7:BOTTOM=L7 |
| PCIE_RX_N32 | RXS32-DIFF1 | PAIR | 6 | 5.5 | 5 | 10 | 5 | 50 | 6 | 20 | 12 | 12 | 12 | 12 | 7.5 | 85 Ohms | TOP=L2:L3=L2/L4:L6=L5/L7:BOTTOM=L7 |
| PCIE_RX_N32 | RXS32-DIFF1 | PAIR | 7 | 5.5 | 5 | 10 | 5 | 50 | 6 | 20 | 12 | 12 | 12 | 12 | 7.5 | 85 Ohms | TOP=L2:L3=L2/L4:L6=L5/L7:BOTTOM=L7 |
| PCIE_RX_N32 | RXS32-DIFF1 | PAIR | 8 | 5.38 | 5 | 10 | 5 | 50 | 6 | 33 | 12 | 12 | 12 | 12 | 6.62 | 85 Ohms | TOP=L2:L3=L2/L4:L6=L5/L7:BOTTOM=L7 |
| PCIE_RX_P32 | RXS32-DIFF1 | PAIR | 1 | 5.38 | 5 | 10 | 5 | 50 | 6 | 33 | 12 | 12 | 12 | 12 | 6.62 | 85 Ohms | TOP=L2:L3=L2/L4:L6=L5/L7:BOTTOM=L7 |
| PCIE_RX_P32 | RXS32-DIFF1 | PAIR | 2 | 5.5 | 5 | 10 | 5 | 50 | 6 | 20 | 12 | 12 | 12 | 12 | 7.5 | 85 Ohms | TOP=L2:L3=L2/L4:L6=L5/L7:BOTTOM=L7 |
| PCIE_RX_P32 | RXS32-DIFF1 | PAIR | 3 | 5.5 | 5 | 10 | 5 | 50 | 6 | 20 | 12 | 12 | 12 | 12 | 7.5 | 85 Ohms | TOP=L2:L3=L2/L4:L6=L5/L7:BOTTOM=L7 |
| PCIE_RX_P32 | RXS32-DIFF1 | PAIR | 4 | 5.5 | 5 | 10 | 5 | 50 | 6 | 20 | 12 | 12 | 12 | 12 | 7.5 | 85 Ohms | TOP=L2:L3=L2/L4:L6=L5/L7:BOTTOM=L7 |
| PCIE_RX_P32 | RXS32-DIFF1 | PAIR | 5 | 5.5 | 5 | 10 | 5 | 50 | 6 | 20 | 12 | 12 | 12 | 12 | 7.5 | 85 Ohms | TOP=L2:L3=L2/L4:L6=L5/L7:BOTTOM=L7 |
| PCIE_RX_P32 | RXS32-DIFF1 | PAIR | 6 | 5.5 | 5 | 10 | 5 | 50 | 6 | 20 | 12 | 12 | 12 | 12 | 7.5 | 85 Ohms | TOP=L2:L3=L2/L4:L6=L5/L7:BOTTOM=L7 |
| PCIE_RX_P32 | RXS32-DIFF1 | PAIR | 7 | 5.5 | 5 | 10 | 5 | 50 | 6 | 20 | 12 | 12 | 12 | 12 | 7.5 | 85 Ohms | TOP=L2:L3=L2/L4:L6=L5/L7:BOTTOM=L7 |
| PCIE_RX_P32 | RXS32-DIFF1 | PAIR | 8 | 5.38 | 5 | 10 | 5 | 50 | 6 | 33 | 12 | 12 | 12 | 12 | 6.62 | 85 Ohms | TOP=L2:L3=L2/L4:L6=L5/L7:BOTTOM=L7 |
| PCIE_RX_N33 | RXS33-DIFF1 | PAIR | 1 | 5.38 | 5 | 10 | 5 | 50 | 6 | 33 | 12 | 12 | 12 | 12 | 6.62 | 85 Ohms | TOP=L2:L3=L2/L4:L6=L5/L7:BOTTOM=L7 |
| PCIE_RX_N33 | RXS33-DIFF1 | PAIR | 2 | 5.5 | 5 | 10 | 5 | 50 | 6 | 20 | 12 | 12 | 12 | 12 | 7.5 | 85 Ohms | TOP=L2:L3=L2/L4:L6=L5/L7:BOTTOM=L7 |
| PCIE_RX_N33 | RXS33-DIFF1 | PAIR | 3 | 5.5 | 5 | 10 | 5 | 50 | 6 | 20 | 12 | 12 | 12 | 12 | 7.5 | 85 Ohms | TOP=L2:L3=L2/L4:L6=L5/L7:BOTTOM=L7 |
| PCIE_RX_N33 | RXS33-DIFF1 | PAIR | 4 | 5.5 | 5 | 10 | 5 | 50 | 6 | 20 | 12 | 12 | 12 | 12 | 7.5 | 85 Ohms | TOP=L2:L3=L2/L4:L6=L5/L7:BOTTOM=L7 |
| PCIE_RX_N33 | RXS33-DIFF1 | PAIR | 5 | 5.5 | 5 | 10 | 5 | 50 | 6 | 20 | 12 | 12 | 12 | 12 | 7.5 | 85 Ohms | TOP=L2:L3=L2/L4:L6=L5/L7:BOTTOM=L7 |
| PCIE_RX_N33 | RXS33-DIFF1 | PAIR | 6 | 5.5 | 5 | 10 | 5 | 50 | 6 | 20 | 12 | 12 | 12 | 12 | 7.5 | 85 Ohms | TOP=L2:L3=L2/L4:L6=L5/L7:BOTTOM=L7 |
| PCIE_RX_N33 | RXS33-DIFF1 | PAIR | 7 | 5.5 | 5 | 10 | 5 | 50 | 6 | 20 | 12 | 12 | 12 | 12 | 7.5 | 85 Ohms | TOP=L2:L3=L2/L4:L6=L5/L7:BOTTOM=L7 |
| PCIE_RX_N33 | RXS33-DIFF1 | PAIR | 8 | 5.38 | 5 | 10 | 5 | 50 | 6 | 33 | 12 | 12 | 12 | 12 | 6.62 | 85 Ohms | TOP=L2:L3=L2/L4:L6=L5/L7:BOTTOM=L7 |
| PCIE_RX_P33 | RXS33-DIFF1 | PAIR | 1 | 5.38 | 5 | 10 | 5 | 50 | 6 | 33 | 12 | 12 | 12 | 12 | 6.62 | 85 Ohms | TOP=L2:L3=L2/L4:L6=L5/L7:BOTTOM=L7 |
| PCIE_RX_P33 | RXS33-DIFF1 | PAIR | 2 | 5.5 | 5 | 10 | 5 | 50 | 6 | 20 | 12 | 12 | 12 | 12 | 7.5 | 85 Ohms | TOP=L2:L3=L2/L4:L6=L5/L7:BOTTOM=L7 |
| PCIE_RX_P33 | RXS33-DIFF1 | PAIR | 3 | 5.5 | 5 | 10 | 5 | 50 | 6 | 20 | 12 | 12 | 12 | 12 | 7.5 | 85 Ohms | TOP=L2:L3=L2/L4:L6=L5/L7:BOTTOM=L7 |
| PCIE_RX_P33 | RXS33-DIFF1 | PAIR | 4 | 5.5 | 5 | 10 | 5 | 50 | 6 | 20 | 12 | 12 | 12 | 12 | 7.5 | 85 Ohms | TOP=L2:L3=L2/L4:L6=L5/L7:BOTTOM=L7 |
| PCIE_RX_P33 | RXS33-DIFF1 | PAIR | 5 | 5.5 | 5 | 10 | 5 | 50 | 6 | 20 | 12 | 12 | 12 | 12 | 7.5 | 85 Ohms | TOP=L2:L3=L2/L4:L6=L5/L7:BOTTOM=L7 |
| PCIE_RX_P33 | RXS33-DIFF1 | PAIR | 6 | 5.5 | 5 | 10 | 5 | 50 | 6 | 20 | 12 | 12 | 12 | 12 | 7.5 | 85 Ohms | TOP=L2:L3=L2/L4:L6=L5/L7:BOTTOM=L7 |
| PCIE_RX_P33 | RXS33-DIFF1 | PAIR | 7 | 5.5 | 5 | 10 | 5 | 50 | 6 | 20 | 12 | 12 | 12 | 12 | 7.5 | 85 Ohms | TOP=L2:L3=L2/L4:L6=L5/L7:BOTTOM=L7 |
| PCIE_RX_P33 | RXS33-DIFF1 | PAIR | 8 | 5.38 | 5 | 10 | 5 | 50 | 6 | 33 | 12 | 12 | 12 | 12 | 6.62 | 85 Ohms | TOP=L2:L3=L2/L4:L6=L5/L7:BOTTOM=L7 |
| PCIE_RX_N34 | RXS34-DIFF1 | PAIR | 1 | 5.38 | 5 | 10 | 5 | 50 | 6 | 33 | 12 | 12 | 12 | 12 | 6.62 | 85 Ohms | TOP=L2:L3=L2/L4:L6=L5/L7:BOTTOM=L7 |
| PCIE_RX_N34 | RXS34-DIFF1 | PAIR | 2 | 5.5 | 5 | 10 | 5 | 50 | 6 | 20 | 12 | 12 | 12 | 12 | 7.5 | 85 Ohms | TOP=L2:L3=L2/L4:L6=L5/L7:BOTTOM=L7 |
| PCIE_RX_N34 | RXS34-DIFF1 | PAIR | 3 | 5.5 | 5 | 10 | 5 | 50 | 6 | 20 | 12 | 12 | 12 | 12 | 7.5 | 85 Ohms | TOP=L2:L3=L2/L4:L6=L5/L7:BOTTOM=L7 |
| PCIE_RX_N34 | RXS34-DIFF1 | PAIR | 4 | 5.5 | 5 | 10 | 5 | 50 | 6 | 20 | 12 | 12 | 12 | 12 | 7.5 | 85 Ohms | TOP=L2:L3=L2/L4:L6=L5/L7:BOTTOM=L7 |
| PCIE_RX_N34 | RXS34-DIFF1 | PAIR | 5 | 5.5 | 5 | 10 | 5 | 50 | 6 | 20 | 12 | 12 | 12 | 12 | 7.5 | 85 Ohms | TOP=L2:L3=L2/L4:L6=L5/L7:BOTTOM=L7 |
| PCIE_RX_N34 | RXS34-DIFF1 | PAIR | 6 | 5.5 | 5 | 10 | 5 | 50 | 6 | 20 | 12 | 12 | 12 | 12 | 7.5 | 85 Ohms | TOP=L2:L3=L2/L4:L6=L5/L7:BOTTOM=L7 |
| PCIE_RX_N34 | RXS34-DIFF1 | PAIR | 7 | 5.5 | 5 | 10 | 5 | 50 | 6 | 20 | 12 | 12 | 12 | 12 | 7.5 | 85 Ohms | TOP=L2:L3=L2/L4:L6=L5/L7:BOTTOM=L7 |
| PCIE_RX_N34 | RXS34-DIFF1 | PAIR | 8 | 5.38 | 5 | 10 | 5 | 50 | 6 | 33 | 12 | 12 | 12 | 12 | 6.62 | 85 Ohms | TOP=L2:L3=L2/L4:L6=L5/L7:BOTTOM=L7 |
| PCIE_RX_P34 | RXS34-DIFF1 | PAIR | 1 | 5.38 | 5 | 10 | 5 | 50 | 6 | 33 | 12 | 12 | 12 | 12 | 6.62 | 85 Ohms | TOP=L2:L3=L2/L4:L6=L5/L7:BOTTOM=L7 |
| PCIE_RX_P34 | RXS34-DIFF1 | PAIR | 2 | 5.5 | 5 | 10 | 5 | 50 | 6 | 20 | 12 | 12 | 12 | 12 | 7.5 | 85 Ohms | TOP=L2:L3=L2/L4:L6=L5/L7:BOTTOM=L7 |
| PCIE_RX_P34 | RXS34-DIFF1 | PAIR | 3 | 5.5 | 5 | 10 | 5 | 50 | 6 | 20 | 12 | 12 | 12 | 12 | 7.5 | 85 Ohms | TOP=L2:L3=L2/L4:L6=L5/L7:BOTTOM=L7 |
| PCIE_RX_P34 | RXS34-DIFF1 | PAIR | 4 | 5.5 | 5 | 10 | 5 | 50 | 6 | 20 | 12 | 12 | 12 | 12 | 7.5 | 85 Ohms | TOP=L2:L3=L2/L4:L6=L5/L7:BOTTOM=L7 |
| PCIE_RX_P34 | RXS34-DIFF1 | PAIR | 5 | 5.5 | 5 | 10 | 5 | 50 | 6 | 20 | 12 | 12 | 12 | 12 | 7.5 | 85 Ohms | TOP=L2:L3=L2/L4:L6=L5/L7:BOTTOM=L7 |
| PCIE_RX_P34 | RXS34-DIFF1 | PAIR | 6 | 5.5 | 5 | 10 | 5 | 50 | 6 | 20 | 12 | 12 | 12 | 12 | 7.5 | 85 Ohms | TOP=L2:L3=L2/L4:L6=L5/L7:BOTTOM=L7 |
| PCIE_RX_P34 | RXS34-DIFF1 | PAIR | 7 | 5.5 | 5 | 10 | 5 | 50 | 6 | 20 | 12 | 12 | 12 | 12 | 7.5 | 85 Ohms | TOP=L2:L3=L2/L4:L6=L5/L7:BOTTOM=L7 |
| PCIE_RX_P34 | RXS34-DIFF1 | PAIR | 8 | 5.38 | 5 | 10 | 5 | 50 | 6 | 33 | 12 | 12 | 12 | 12 | 6.62 | 85 Ohms | TOP=L2:L3=L2/L4:L6=L5/L7:BOTTOM=L7 |
| PCIE_RX_N35 | RXS35-DIFF1 | PAIR | 1 | 5.38 | 5 | 10 | 5 | 50 | 6 | 33 | 12 | 12 | 12 | 12 | 6.62 | 85 Ohms | TOP=L2:L3=L2/L4:L6=L5/L7:BOTTOM=L7 |
| PCIE_RX_N35 | RXS35-DIFF1 | PAIR | 2 | 5.5 | 5 | 10 | 5 | 50 | 6 | 20 | 12 | 12 | 12 | 12 | 7.5 | 85 Ohms | TOP=L2:L3=L2/L4:L6=L5/L7:BOTTOM=L7 |
| PCIE_RX_N35 | RXS35-DIFF1 | PAIR | 3 | 5.5 | 5 | 10 | 5 | 50 | 6 | 20 | 12 | 12 | 12 | 12 | 7.5 | 85 Ohms | TOP=L2:L3=L2/L4:L6=L5/L7:BOTTOM=L7 |
| PCIE_RX_N35 | RXS35-DIFF1 | PAIR | 4 | 5.5 | 5 | 10 | 5 | 50 | 6 | 20 | 12 | 12 | 12 | 12 | 7.5 | 85 Ohms | TOP=L2:L3=L2/L4:L6=L5/L7:BOTTOM=L7 |
| PCIE_RX_N35 | RXS35-DIFF1 | PAIR | 5 | 5.5 | 5 | 10 | 5 | 50 | 6 | 20 | 12 | 12 | 12 | 12 | 7.5 | 85 Ohms | TOP=L2:L3=L2/L4:L6=L5/L7:BOTTOM=L7 |
| PCIE_RX_N35 | RXS35-DIFF1 | PAIR | 6 | 5.5 | 5 | 10 | 5 | 50 | 6 | 20 | 12 | 12 | 12 | 12 | 7.5 | 85 Ohms | TOP=L2:L3=L2/L4:L6=L5/L7:BOTTOM=L7 |
| PCIE_RX_N35 | RXS35-DIFF1 | PAIR | 7 | 5.5 | 5 | 10 | 5 | 50 | 6 | 20 | 12 | 12 | 12 | 12 | 7.5 | 85 Ohms | TOP=L2:L3=L2/L4:L6=L5/L7:BOTTOM=L7 |
| PCIE_RX_N35 | RXS35-DIFF1 | PAIR | 8 | 5.38 | 5 | 10 | 5 | 50 | 6 | 33 | 12 | 12 | 12 | 12 | 6.62 | 85 Ohms | TOP=L2:L3=L2/L4:L6=L5/L7:BOTTOM=L7 |
| PCIE_RX_P35 | RXS35-DIFF1 | PAIR | 1 | 5.38 | 5 | 10 | 5 | 50 | 6 | 33 | 12 | 12 | 12 | 12 | 6.62 | 85 Ohms | TOP=L2:L3=L2/L4:L6=L5/L7:BOTTOM=L7 |
| PCIE_RX_P35 | RXS35-DIFF1 | PAIR | 2 | 5.5 | 5 | 10 | 5 | 50 | 6 | 20 | 12 | 12 | 12 | 12 | 7.5 | 85 Ohms | TOP=L2:L3=L2/L4:L6=L5/L7:BOTTOM=L7 |
| PCIE_RX_P35 | RXS35-DIFF1 | PAIR | 3 | 5.5 | 5 | 10 | 5 | 50 | 6 | 20 | 12 | 12 | 12 | 12 | 7.5 | 85 Ohms | TOP=L2:L3=L2/L4:L6=L5/L7:BOTTOM=L7 |
| PCIE_RX_P35 | RXS35-DIFF1 | PAIR | 4 | 5.5 | 5 | 10 | 5 | 50 | 6 | 20 | 12 | 12 | 12 | 12 | 7.5 | 85 Ohms | TOP=L2:L3=L2/L4:L6=L5/L7:BOTTOM=L7 |
| PCIE_RX_P35 | RXS35-DIFF1 | PAIR | 5 | 5.5 | 5 | 10 | 5 | 50 | 6 | 20 | 12 | 12 | 12 | 12 | 7.5 | 85 Ohms | TOP=L2:L3=L2/L4:L6=L5/L7:BOTTOM=L7 |
| PCIE_RX_P35 | RXS35-DIFF1 | PAIR | 6 | 5.5 | 5 | 10 | 5 | 50 | 6 | 20 | 12 | 12 | 12 | 12 | 7.5 | 85 Ohms | TOP=L2:L3=L2/L4:L6=L5/L7:BOTTOM=L7 |
| PCIE_RX_P35 | RXS35-DIFF1 | PAIR | 7 | 5.5 | 5 | 10 | 5 | 50 | 6 | 20 | 12 | 12 | 12 | 12 | 7.5 | 85 Ohms | TOP=L2:L3=L2/L4:L6=L5/L7:BOTTOM=L7 |
| PCIE_RX_P35 | RXS35-DIFF1 | PAIR | 8 | 5.38 | 5 | 10 | 5 | 50 | 6 | 33 | 12 | 12 | 12 | 12 | 6.62 | 85 Ohms | TOP=L2:L3=L2/L4:L6=L5/L7:BOTTOM=L7 |
| PCIE_RX_N36 | RXS36-DIFF1 | PAIR | 1 | 5.38 | 5 | 10 | 5 | 50 | 6 | 33 | 12 | 12 | 12 | 12 | 6.62 | 85 Ohms | TOP=L2:L3=L2/L4:L6=L5/L7:BOTTOM=L7 |
| PCIE_RX_N36 | RXS36-DIFF1 | PAIR | 2 | 5.5 | 5 | 10 | 5 | 50 | 6 | 20 | 12 | 12 | 12 | 12 | 7.5 | 85 Ohms | TOP=L2:L3=L2/L4:L6=L5/L7:BOTTOM=L7 |
| PCIE_RX_N36 | RXS36-DIFF1 | PAIR | 3 | 5.5 | 5 | 10 | 5 | 50 | 6 | 20 | 12 | 12 | 12 | 12 | 7.5 | 85 Ohms | TOP=L2:L3=L2/L4:L6=L5/L7:BOTTOM=L7 |
| PCIE_RX_N36 | RXS36-DIFF1 | PAIR | 4 | 5.5 | 5 | 10 | 5 | 50 | 6 | 20 | 12 | 12 | 12 | 12 | 7.5 | 85 Ohms | TOP=L2:L3=L2/L4:L6=L5/L7:BOTTOM=L7 |
| PCIE_RX_N36 | RXS36-DIFF1 | PAIR | 5 | 5.5 | 5 | 10 | 5 | 50 | 6 | 20 | 12 | 12 | 12 | 12 | 7.5 | 85 Ohms | TOP=L2:L3=L2/L4:L6=L5/L7:BOTTOM=L7 |
| PCIE_RX_N36 | RXS36-DIFF1 | PAIR | 6 | 5.5 | 5 | 10 | 5 | 50 | 6 | 20 | 12 | 12 | 12 | 12 | 7.5 | 85 Ohms | TOP=L2:L3=L2/L4:L6=L5/L7:BOTTOM=L7 |
| PCIE_RX_N36 | RXS36-DIFF1 | PAIR | 7 | 5.5 | 5 | 10 | 5 | 50 | 6 | 20 | 12 | 12 | 12 | 12 | 7.5 | 85 Ohms | TOP=L2:L3=L2/L4:L6=L5/L7:BOTTOM=L7 |
| PCIE_RX_N36 | RXS36-DIFF1 | PAIR | 8 | 5.38 | 5 | 10 | 5 | 50 | 6 | 33 | 12 | 12 | 12 | 12 | 6.62 | 85 Ohms | TOP=L2:L3=L2/L4:L6=L5/L7:BOTTOM=L7 |
| PCIE_RX_P36 | RXS36-DIFF1 | PAIR | 1 | 5.38 | 5 | 10 | 5 | 50 | 6 | 33 | 12 | 12 | 12 | 12 | 6.62 | 85 Ohms | TOP=L2:L3=L2/L4:L6=L5/L7:BOTTOM=L7 |
| PCIE_RX_P36 | RXS36-DIFF1 | PAIR | 2 | 5.5 | 5 | 10 | 5 | 50 | 6 | 20 | 12 | 12 | 12 | 12 | 7.5 | 85 Ohms | TOP=L2:L3=L2/L4:L6=L5/L7:BOTTOM=L7 |
| PCIE_RX_P36 | RXS36-DIFF1 | PAIR | 3 | 5.5 | 5 | 10 | 5 | 50 | 6 | 20 | 12 | 12 | 12 | 12 | 7.5 | 85 Ohms | TOP=L2:L3=L2/L4:L6=L5/L7:BOTTOM=L7 |
| PCIE_RX_P36 | RXS36-DIFF1 | PAIR | 4 | 5.5 | 5 | 10 | 5 | 50 | 6 | 20 | 12 | 12 | 12 | 12 | 7.5 | 85 Ohms | TOP=L2:L3=L2/L4:L6=L5/L7:BOTTOM=L7 |
| PCIE_RX_P36 | RXS36-DIFF1 | PAIR | 5 | 5.5 | 5 | 10 | 5 | 50 | 6 | 20 | 12 | 12 | 12 | 12 | 7.5 | 85 Ohms | TOP=L2:L3=L2/L4:L6=L5/L7:BOTTOM=L7 |
| PCIE_RX_P36 | RXS36-DIFF1 | PAIR | 6 | 5.5 | 5 | 10 | 5 | 50 | 6 | 20 | 12 | 12 | 12 | 12 | 7.5 | 85 Ohms | TOP=L2:L3=L2/L4:L6=L5/L7:BOTTOM=L7 |
| PCIE_RX_P36 | RXS36-DIFF1 | PAIR | 7 | 5.5 | 5 | 10 | 5 | 50 | 6 | 20 | 12 | 12 | 12 | 12 | 7.5 | 85 Ohms | TOP=L2:L3=L2/L4:L6=L5/L7:BOTTOM=L7 |
| PCIE_RX_P36 | RXS36-DIFF1 | PAIR | 8 | 5.38 | 5 | 10 | 5 | 50 | 6 | 33 | 12 | 12 | 12 | 12 | 6.62 | 85 Ohms | TOP=L2:L3=L2/L4:L6=L5/L7:BOTTOM=L7 |
| PCIE_RX_N37 | RXS37-DIFF1 | PAIR | 1 | 5.38 | 5 | 10 | 5 | 50 | 6 | 33 | 12 | 12 | 12 | 12 | 6.62 | 85 Ohms | TOP=L2:L3=L2/L4:L6=L5/L7:BOTTOM=L7 |
| PCIE_RX_N37 | RXS37-DIFF1 | PAIR | 2 | 5.5 | 5 | 10 | 5 | 50 | 6 | 20 | 12 | 12 | 12 | 12 | 7.5 | 85 Ohms | TOP=L2:L3=L2/L4:L6=L5/L7:BOTTOM=L7 |
| PCIE_RX_N37 | RXS37-DIFF1 | PAIR | 3 | 5.5 | 5 | 10 | 5 | 50 | 6 | 20 | 12 | 12 | 12 | 12 | 7.5 | 85 Ohms | TOP=L2:L3=L2/L4:L6=L5/L7:BOTTOM=L7 |
| PCIE_RX_N37 | RXS37-DIFF1 | PAIR | 4 | 5.5 | 5 | 10 | 5 | 50 | 6 | 20 | 12 | 12 | 12 | 12 | 7.5 | 85 Ohms | TOP=L2:L3=L2/L4:L6=L5/L7:BOTTOM=L7 |
| PCIE_RX_N37 | RXS37-DIFF1 | PAIR | 5 | 5.5 | 5 | 10 | 5 | 50 | 6 | 20 | 12 | 12 | 12 | 12 | 7.5 | 85 Ohms | TOP=L2:L3=L2/L4:L6=L5/L7:BOTTOM=L7 |
| PCIE_RX_N37 | RXS37-DIFF1 | PAIR | 6 | 5.5 | 5 | 10 | 5 | 50 | 6 | 20 | 12 | 12 | 12 | 12 | 7.5 | 85 Ohms | TOP=L2:L3=L2/L4:L6=L5/L7:BOTTOM=L7 |
| PCIE_RX_N37 | RXS37-DIFF1 | PAIR | 7 | 5.5 | 5 | 10 | 5 | 50 | 6 | 20 | 12 | 12 | 12 | 12 | 7.5 | 85 Ohms | TOP=L2:L3=L2/L4:L6=L5/L7:BOTTOM=L7 |
| PCIE_RX_N37 | RXS37-DIFF1 | PAIR | 8 | 5.38 | 5 | 10 | 5 | 50 | 6 | 33 | 12 | 12 | 12 | 12 | 6.62 | 85 Ohms | TOP=L2:L3=L2/L4:L6=L5/L7:BOTTOM=L7 |
| PCIE_RX_P37 | RXS37-DIFF1 | PAIR | 1 | 5.38 | 5 | 10 | 5 | 50 | 6 | 33 | 12 | 12 | 12 | 12 | 6.62 | 85 Ohms | TOP=L2:L3=L2/L4:L6=L5/L7:BOTTOM=L7 |
| PCIE_RX_P37 | RXS37-DIFF1 | PAIR | 2 | 5.5 | 5 | 10 | 5 | 50 | 6 | 20 | 12 | 12 | 12 | 12 | 7.5 | 85 Ohms | TOP=L2:L3=L2/L4:L6=L5/L7:BOTTOM=L7 |
| PCIE_RX_P37 | RXS37-DIFF1 | PAIR | 3 | 5.5 | 5 | 10 | 5 | 50 | 6 | 20 | 12 | 12 | 12 | 12 | 7.5 | 85 Ohms | TOP=L2:L3=L2/L4:L6=L5/L7:BOTTOM=L7 |
| PCIE_RX_P37 | RXS37-DIFF1 | PAIR | 4 | 5.5 | 5 | 10 | 5 | 50 | 6 | 20 | 12 | 12 | 12 | 12 | 7.5 | 85 Ohms | TOP=L2:L3=L2/L4:L6=L5/L7:BOTTOM=L7 |
| PCIE_RX_P37 | RXS37-DIFF1 | PAIR | 5 | 5.5 | 5 | 10 | 5 | 50 | 6 | 20 | 12 | 12 | 12 | 12 | 7.5 | 85 Ohms | TOP=L2:L3=L2/L4:L6=L5/L7:BOTTOM=L7 |
| PCIE_RX_P37 | RXS37-DIFF1 | PAIR | 6 | 5.5 | 5 | 10 | 5 | 50 | 6 | 20 | 12 | 12 | 12 | 12 | 7.5 | 85 Ohms | TOP=L2:L3=L2/L4:L6=L5/L7:BOTTOM=L7 |
| PCIE_RX_P37 | RXS37-DIFF1 | PAIR | 7 | 5.5 | 5 | 10 | 5 | 50 | 6 | 20 | 12 | 12 | 12 | 12 | 7.5 | 85 Ohms | TOP=L2:L3=L2/L4:L6=L5/L7:BOTTOM=L7 |
| PCIE_RX_P37 | RXS37-DIFF1 | PAIR | 8 | 5.38 | 5 | 10 | 5 | 50 | 6 | 33 | 12 | 12 | 12 | 12 | 6.62 | 85 Ohms | TOP=L2:L3=L2/L4:L6=L5/L7:BOTTOM=L7 |
| PCIE_RX_N38 | RXS38-DIFF1 | PAIR | 1 | 5.38 | 5 | 10 | 5 | 50 | 6 | 33 | 12 | 12 | 12 | 12 | 6.62 | 85 Ohms | TOP=L2:L3=L2/L4:L6=L5/L7:BOTTOM=L7 |
| PCIE_RX_N38 | RXS38-DIFF1 | PAIR | 2 | 5.5 | 5 | 10 | 5 | 50 | 6 | 20 | 12 | 12 | 12 | 12 | 7.5 | 85 Ohms | TOP=L2:L3=L2/L4:L6=L5/L7:BOTTOM=L7 |
| PCIE_RX_N38 | RXS38-DIFF1 | PAIR | 3 | 5.5 | 5 | 10 | 5 | 50 | 6 | 20 | 12 | 12 | 12 | 12 | 7.5 | 85 Ohms | TOP=L2:L3=L2/L4:L6=L5/L7:BOTTOM=L7 |
| PCIE_RX_N38 | RXS38-DIFF1 | PAIR | 4 | 5.5 | 5 | 10 | 5 | 50 | 6 | 20 | 12 | 12 | 12 | 12 | 7.5 | 85 Ohms | TOP=L2:L3=L2/L4:L6=L5/L7:BOTTOM=L7 |
| PCIE_RX_N38 | RXS38-DIFF1 | PAIR | 5 | 5.5 | 5 | 10 | 5 | 50 | 6 | 20 | 12 | 12 | 12 | 12 | 7.5 | 85 Ohms | TOP=L2:L3=L2/L4:L6=L5/L7:BOTTOM=L7 |
| PCIE_RX_N38 | RXS38-DIFF1 | PAIR | 6 | 5.5 | 5 | 10 | 5 | 50 | 6 | 20 | 12 | 12 | 12 | 12 | 7.5 | 85 Ohms | TOP=L2:L3=L2/L4:L6=L5/L7:BOTTOM=L7 |
| PCIE_RX_N38 | RXS38-DIFF1 | PAIR | 7 | 5.5 | 5 | 10 | 5 | 50 | 6 | 20 | 12 | 12 | 12 | 12 | 7.5 | 85 Ohms | TOP=L2:L3=L2/L4:L6=L5/L7:BOTTOM=L7 |
| PCIE_RX_N38 | RXS38-DIFF1 | PAIR | 8 | 5.38 | 5 | 10 | 5 | 50 | 6 | 33 | 12 | 12 | 12 | 12 | 6.62 | 85 Ohms | TOP=L2:L3=L2/L4:L6=L5/L7:BOTTOM=L7 |
| PCIE_RX_P38 | RXS38-DIFF1 | PAIR | 1 | 5.38 | 5 | 10 | 5 | 50 | 6 | 33 | 12 | 12 | 12 | 12 | 6.62 | 85 Ohms | TOP=L2:L3=L2/L4:L6=L5/L7:BOTTOM=L7 |
| PCIE_RX_P38 | RXS38-DIFF1 | PAIR | 2 | 5.5 | 5 | 10 | 5 | 50 | 6 | 20 | 12 | 12 | 12 | 12 | 7.5 | 85 Ohms | TOP=L2:L3=L2/L4:L6=L5/L7:BOTTOM=L7 |
| PCIE_RX_P38 | RXS38-DIFF1 | PAIR | 3 | 5.5 | 5 | 10 | 5 | 50 | 6 | 20 | 12 | 12 | 12 | 12 | 7.5 | 85 Ohms | TOP=L2:L3=L2/L4:L6=L5/L7:BOTTOM=L7 |
| PCIE_RX_P38 | RXS38-DIFF1 | PAIR | 4 | 5.5 | 5 | 10 | 5 | 50 | 6 | 20 | 12 | 12 | 12 | 12 | 7.5 | 85 Ohms | TOP=L2:L3=L2/L4:L6=L5/L7:BOTTOM=L7 |
| PCIE_RX_P38 | RXS38-DIFF1 | PAIR | 5 | 5.5 | 5 | 10 | 5 | 50 | 6 | 20 | 12 | 12 | 12 | 12 | 7.5 | 85 Ohms | TOP=L2:L3=L2/L4:L6=L5/L7:BOTTOM=L7 |
| PCIE_RX_P38 | RXS38-DIFF1 | PAIR | 6 | 5.5 | 5 | 10 | 5 | 50 | 6 | 20 | 12 | 12 | 12 | 12 | 7.5 | 85 Ohms | TOP=L2:L3=L2/L4:L6=L5/L7:BOTTOM=L7 |
| PCIE_RX_P38 | RXS38-DIFF1 | PAIR | 7 | 5.5 | 5 | 10 | 5 | 50 | 6 | 20 | 12 | 12 | 12 | 12 | 7.5 | 85 Ohms | TOP=L2:L3=L2/L4:L6=L5/L7:BOTTOM=L7 |
| PCIE_RX_P38 | RXS38-DIFF1 | PAIR | 8 | 5.38 | 5 | 10 | 5 | 50 | 6 | 33 | 12 | 12 | 12 | 12 | 6.62 | 85 Ohms | TOP=L2:L3=L2/L4:L6=L5/L7:BOTTOM=L7 |
| PCIE_RX_N39 | RXS39-DIFF1 | PAIR | 1 | 5.38 | 5 | 10 | 5 | 50 | 6 | 33 | 12 | 12 | 12 | 12 | 6.62 | 85 Ohms | TOP=L2:L3=L2/L4:L6=L5/L7:BOTTOM=L7 |
| PCIE_RX_N39 | RXS39-DIFF1 | PAIR | 2 | 5.5 | 5 | 10 | 5 | 50 | 6 | 20 | 12 | 12 | 12 | 12 | 7.5 | 85 Ohms | TOP=L2:L3=L2/L4:L6=L5/L7:BOTTOM=L7 |
| PCIE_RX_N39 | RXS39-DIFF1 | PAIR | 3 | 5.5 | 5 | 10 | 5 | 50 | 6 | 20 | 12 | 12 | 12 | 12 | 7.5 | 85 Ohms | TOP=L2:L3=L2/L4:L6=L5/L7:BOTTOM=L7 |
| PCIE_RX_N39 | RXS39-DIFF1 | PAIR | 4 | 5.5 | 5 | 10 | 5 | 50 | 6 | 20 | 12 | 12 | 12 | 12 | 7.5 | 85 Ohms | TOP=L2:L3=L2/L4:L6=L5/L7:BOTTOM=L7 |
| PCIE_RX_N39 | RXS39-DIFF1 | PAIR | 5 | 5.5 | 5 | 10 | 5 | 50 | 6 | 20 | 12 | 12 | 12 | 12 | 7.5 | 85 Ohms | TOP=L2:L3=L2/L4:L6=L5/L7:BOTTOM=L7 |
| PCIE_RX_N39 | RXS39-DIFF1 | PAIR | 6 | 5.5 | 5 | 10 | 5 | 50 | 6 | 20 | 12 | 12 | 12 | 12 | 7.5 | 85 Ohms | TOP=L2:L3=L2/L4:L6=L5/L7:BOTTOM=L7 |
| PCIE_RX_N39 | RXS39-DIFF1 | PAIR | 7 | 5.5 | 5 | 10 | 5 | 50 | 6 | 20 | 12 | 12 | 12 | 12 | 7.5 | 85 Ohms | TOP=L2:L3=L2/L4:L6=L5/L7:BOTTOM=L7 |
| PCIE_RX_N39 | RXS39-DIFF1 | PAIR | 8 | 5.38 | 5 | 10 | 5 | 50 | 6 | 33 | 12 | 12 | 12 | 12 | 6.62 | 85 Ohms | TOP=L2:L3=L2/L4:L6=L5/L7:BOTTOM=L7 |
| PCIE_RX_P39 | RXS39-DIFF1 | PAIR | 1 | 5.38 | 5 | 10 | 5 | 50 | 6 | 33 | 12 | 12 | 12 | 12 | 6.62 | 85 Ohms | TOP=L2:L3=L2/L4:L6=L5/L7:BOTTOM=L7 |
| PCIE_RX_P39 | RXS39-DIFF1 | PAIR | 2 | 5.5 | 5 | 10 | 5 | 50 | 6 | 20 | 12 | 12 | 12 | 12 | 7.5 | 85 Ohms | TOP=L2:L3=L2/L4:L6=L5/L7:BOTTOM=L7 |
| PCIE_RX_P39 | RXS39-DIFF1 | PAIR | 3 | 5.5 | 5 | 10 | 5 | 50 | 6 | 20 | 12 | 12 | 12 | 12 | 7.5 | 85 Ohms | TOP=L2:L3=L2/L4:L6=L5/L7:BOTTOM=L7 |
| PCIE_RX_P39 | RXS39-DIFF1 | PAIR | 4 | 5.5 | 5 | 10 | 5 | 50 | 6 | 20 | 12 | 12 | 12 | 12 | 7.5 | 85 Ohms | TOP=L2:L3=L2/L4:L6=L5/L7:BOTTOM=L7 |
| PCIE_RX_P39 | RXS39-DIFF1 | PAIR | 5 | 5.5 | 5 | 10 | 5 | 50 | 6 | 20 | 12 | 12 | 12 | 12 | 7.5 | 85 Ohms | TOP=L2:L3=L2/L4:L6=L5/L7:BOTTOM=L7 |
| PCIE_RX_P39 | RXS39-DIFF1 | PAIR | 6 | 5.5 | 5 | 10 | 5 | 50 | 6 | 20 | 12 | 12 | 12 | 12 | 7.5 | 85 Ohms | TOP=L2:L3=L2/L4:L6=L5/L7:BOTTOM=L7 |
| PCIE_RX_P39 | RXS39-DIFF1 | PAIR | 7 | 5.5 | 5 | 10 | 5 | 50 | 6 | 20 | 12 | 12 | 12 | 12 | 7.5 | 85 Ohms | TOP=L2:L3=L2/L4:L6=L5/L7:BOTTOM=L7 |
| PCIE_RX_P39 | RXS39-DIFF1 | PAIR | 8 | 5.38 | 5 | 10 | 5 | 50 | 6 | 33 | 12 | 12 | 12 | 12 | 6.62 | 85 Ohms | TOP=L2:L3=L2/L4:L6=L5/L7:BOTTOM=L7 |
| PCIE_RX_N3 | RXS3-DIFF1 | PAIR | 1 | 5.38 | 5 | 10 | 5 | 50 | 6 | 33 | 12 | 12 | 12 | 12 | 6.62 | 85 Ohms | TOP=L2:L3=L2/L4:L6=L5/L7:BOTTOM=L7 |
| PCIE_RX_N3 | RXS3-DIFF1 | PAIR | 2 | 5.5 | 5 | 10 | 5 | 50 | 6 | 20 | 12 | 12 | 12 | 12 | 7.5 | 85 Ohms | TOP=L2:L3=L2/L4:L6=L5/L7:BOTTOM=L7 |
| PCIE_RX_N3 | RXS3-DIFF1 | PAIR | 3 | 5.5 | 5 | 10 | 5 | 50 | 6 | 20 | 12 | 12 | 12 | 12 | 7.5 | 85 Ohms | TOP=L2:L3=L2/L4:L6=L5/L7:BOTTOM=L7 |
| PCIE_RX_N3 | RXS3-DIFF1 | PAIR | 4 | 5.5 | 5 | 10 | 5 | 50 | 6 | 20 | 12 | 12 | 12 | 12 | 7.5 | 85 Ohms | TOP=L2:L3=L2/L4:L6=L5/L7:BOTTOM=L7 |
| PCIE_RX_N3 | RXS3-DIFF1 | PAIR | 5 | 5.5 | 5 | 10 | 5 | 50 | 6 | 20 | 12 | 12 | 12 | 12 | 7.5 | 85 Ohms | TOP=L2:L3=L2/L4:L6=L5/L7:BOTTOM=L7 |
| PCIE_RX_N3 | RXS3-DIFF1 | PAIR | 6 | 5.5 | 5 | 10 | 5 | 50 | 6 | 20 | 12 | 12 | 12 | 12 | 7.5 | 85 Ohms | TOP=L2:L3=L2/L4:L6=L5/L7:BOTTOM=L7 |
| PCIE_RX_N3 | RXS3-DIFF1 | PAIR | 7 | 5.5 | 5 | 10 | 5 | 50 | 6 | 20 | 12 | 12 | 12 | 12 | 7.5 | 85 Ohms | TOP=L2:L3=L2/L4:L6=L5/L7:BOTTOM=L7 |
| PCIE_RX_N3 | RXS3-DIFF1 | PAIR | 8 | 5.38 | 5 | 10 | 5 | 50 | 6 | 33 | 12 | 12 | 12 | 12 | 6.62 | 85 Ohms | TOP=L2:L3=L2/L4:L6=L5/L7:BOTTOM=L7 |
| PCIE_RX_P3 | RXS3-DIFF1 | PAIR | 1 | 5.38 | 5 | 10 | 5 | 50 | 6 | 33 | 12 | 12 | 12 | 12 | 6.62 | 85 Ohms | TOP=L2:L3=L2/L4:L6=L5/L7:BOTTOM=L7 |
| PCIE_RX_P3 | RXS3-DIFF1 | PAIR | 2 | 5.5 | 5 | 10 | 5 | 50 | 6 | 20 | 12 | 12 | 12 | 12 | 7.5 | 85 Ohms | TOP=L2:L3=L2/L4:L6=L5/L7:BOTTOM=L7 |
| PCIE_RX_P3 | RXS3-DIFF1 | PAIR | 3 | 5.5 | 5 | 10 | 5 | 50 | 6 | 20 | 12 | 12 | 12 | 12 | 7.5 | 85 Ohms | TOP=L2:L3=L2/L4:L6=L5/L7:BOTTOM=L7 |
| PCIE_RX_P3 | RXS3-DIFF1 | PAIR | 4 | 5.5 | 5 | 10 | 5 | 50 | 6 | 20 | 12 | 12 | 12 | 12 | 7.5 | 85 Ohms | TOP=L2:L3=L2/L4:L6=L5/L7:BOTTOM=L7 |
| PCIE_RX_P3 | RXS3-DIFF1 | PAIR | 5 | 5.5 | 5 | 10 | 5 | 50 | 6 | 20 | 12 | 12 | 12 | 12 | 7.5 | 85 Ohms | TOP=L2:L3=L2/L4:L6=L5/L7:BOTTOM=L7 |
| PCIE_RX_P3 | RXS3-DIFF1 | PAIR | 6 | 5.5 | 5 | 10 | 5 | 50 | 6 | 20 | 12 | 12 | 12 | 12 | 7.5 | 85 Ohms | TOP=L2:L3=L2/L4:L6=L5/L7:BOTTOM=L7 |
| PCIE_RX_P3 | RXS3-DIFF1 | PAIR | 7 | 5.5 | 5 | 10 | 5 | 50 | 6 | 20 | 12 | 12 | 12 | 12 | 7.5 | 85 Ohms | TOP=L2:L3=L2/L4:L6=L5/L7:BOTTOM=L7 |
| PCIE_RX_P3 | RXS3-DIFF1 | PAIR | 8 | 5.38 | 5 | 10 | 5 | 50 | 6 | 33 | 12 | 12 | 12 | 12 | 6.62 | 85 Ohms | TOP=L2:L3=L2/L4:L6=L5/L7:BOTTOM=L7 |
| PCIE_RX_N40 | RXS40-DIFF1 | PAIR | 1 | 5.38 | 5 | 10 | 5 | 50 | 6 | 33 | 12 | 12 | 12 | 12 | 6.62 | 85 Ohms | TOP=L2:L3=L2/L4:L6=L5/L7:BOTTOM=L7 |
| PCIE_RX_N40 | RXS40-DIFF1 | PAIR | 2 | 5.5 | 5 | 10 | 5 | 50 | 6 | 20 | 12 | 12 | 12 | 12 | 7.5 | 85 Ohms | TOP=L2:L3=L2/L4:L6=L5/L7:BOTTOM=L7 |
| PCIE_RX_N40 | RXS40-DIFF1 | PAIR | 3 | 5.5 | 5 | 10 | 5 | 50 | 6 | 20 | 12 | 12 | 12 | 12 | 7.5 | 85 Ohms | TOP=L2:L3=L2/L4:L6=L5/L7:BOTTOM=L7 |
| PCIE_RX_N40 | RXS40-DIFF1 | PAIR | 4 | 5.5 | 5 | 10 | 5 | 50 | 6 | 20 | 12 | 12 | 12 | 12 | 7.5 | 85 Ohms | TOP=L2:L3=L2/L4:L6=L5/L7:BOTTOM=L7 |
| PCIE_RX_N40 | RXS40-DIFF1 | PAIR | 5 | 5.5 | 5 | 10 | 5 | 50 | 6 | 20 | 12 | 12 | 12 | 12 | 7.5 | 85 Ohms | TOP=L2:L3=L2/L4:L6=L5/L7:BOTTOM=L7 |
| PCIE_RX_N40 | RXS40-DIFF1 | PAIR | 6 | 5.5 | 5 | 10 | 5 | 50 | 6 | 20 | 12 | 12 | 12 | 12 | 7.5 | 85 Ohms | TOP=L2:L3=L2/L4:L6=L5/L7:BOTTOM=L7 |
| PCIE_RX_N40 | RXS40-DIFF1 | PAIR | 7 | 5.5 | 5 | 10 | 5 | 50 | 6 | 20 | 12 | 12 | 12 | 12 | 7.5 | 85 Ohms | TOP=L2:L3=L2/L4:L6=L5/L7:BOTTOM=L7 |
| PCIE_RX_N40 | RXS40-DIFF1 | PAIR | 8 | 5.38 | 5 | 10 | 5 | 50 | 6 | 33 | 12 | 12 | 12 | 12 | 6.62 | 85 Ohms | TOP=L2:L3=L2/L4:L6=L5/L7:BOTTOM=L7 |
| PCIE_RX_P40 | RXS40-DIFF1 | PAIR | 1 | 5.38 | 5 | 10 | 5 | 50 | 6 | 33 | 12 | 12 | 12 | 12 | 6.62 | 85 Ohms | TOP=L2:L3=L2/L4:L6=L5/L7:BOTTOM=L7 |
| PCIE_RX_P40 | RXS40-DIFF1 | PAIR | 2 | 5.5 | 5 | 10 | 5 | 50 | 6 | 20 | 12 | 12 | 12 | 12 | 7.5 | 85 Ohms | TOP=L2:L3=L2/L4:L6=L5/L7:BOTTOM=L7 |
| PCIE_RX_P40 | RXS40-DIFF1 | PAIR | 3 | 5.5 | 5 | 10 | 5 | 50 | 6 | 20 | 12 | 12 | 12 | 12 | 7.5 | 85 Ohms | TOP=L2:L3=L2/L4:L6=L5/L7:BOTTOM=L7 |
| PCIE_RX_P40 | RXS40-DIFF1 | PAIR | 4 | 5.5 | 5 | 10 | 5 | 50 | 6 | 20 | 12 | 12 | 12 | 12 | 7.5 | 85 Ohms | TOP=L2:L3=L2/L4:L6=L5/L7:BOTTOM=L7 |
| PCIE_RX_P40 | RXS40-DIFF1 | PAIR | 5 | 5.5 | 5 | 10 | 5 | 50 | 6 | 20 | 12 | 12 | 12 | 12 | 7.5 | 85 Ohms | TOP=L2:L3=L2/L4:L6=L5/L7:BOTTOM=L7 |
| PCIE_RX_P40 | RXS40-DIFF1 | PAIR | 6 | 5.5 | 5 | 10 | 5 | 50 | 6 | 20 | 12 | 12 | 12 | 12 | 7.5 | 85 Ohms | TOP=L2:L3=L2/L4:L6=L5/L7:BOTTOM=L7 |
| PCIE_RX_P40 | RXS40-DIFF1 | PAIR | 7 | 5.5 | 5 | 10 | 5 | 50 | 6 | 20 | 12 | 12 | 12 | 12 | 7.5 | 85 Ohms | TOP=L2:L3=L2/L4:L6=L5/L7:BOTTOM=L7 |
| PCIE_RX_P40 | RXS40-DIFF1 | PAIR | 8 | 5.38 | 5 | 10 | 5 | 50 | 6 | 33 | 12 | 12 | 12 | 12 | 6.62 | 85 Ohms | TOP=L2:L3=L2/L4:L6=L5/L7:BOTTOM=L7 |
| PCIE_RX_N41 | RXS41-DIFF1 | PAIR | 1 | 5.38 | 5 | 10 | 5 | 50 | 6 | 33 | 12 | 12 | 12 | 12 | 6.62 | 85 Ohms | TOP=L2:L3=L2/L4:L6=L5/L7:BOTTOM=L7 |
| PCIE_RX_N41 | RXS41-DIFF1 | PAIR | 2 | 5.5 | 5 | 10 | 5 | 50 | 6 | 20 | 12 | 12 | 12 | 12 | 7.5 | 85 Ohms | TOP=L2:L3=L2/L4:L6=L5/L7:BOTTOM=L7 |
| PCIE_RX_N41 | RXS41-DIFF1 | PAIR | 3 | 5.5 | 5 | 10 | 5 | 50 | 6 | 20 | 12 | 12 | 12 | 12 | 7.5 | 85 Ohms | TOP=L2:L3=L2/L4:L6=L5/L7:BOTTOM=L7 |
| PCIE_RX_N41 | RXS41-DIFF1 | PAIR | 4 | 5.5 | 5 | 10 | 5 | 50 | 6 | 20 | 12 | 12 | 12 | 12 | 7.5 | 85 Ohms | TOP=L2:L3=L2/L4:L6=L5/L7:BOTTOM=L7 |
| PCIE_RX_N41 | RXS41-DIFF1 | PAIR | 5 | 5.5 | 5 | 10 | 5 | 50 | 6 | 20 | 12 | 12 | 12 | 12 | 7.5 | 85 Ohms | TOP=L2:L3=L2/L4:L6=L5/L7:BOTTOM=L7 |
| PCIE_RX_N41 | RXS41-DIFF1 | PAIR | 6 | 5.5 | 5 | 10 | 5 | 50 | 6 | 20 | 12 | 12 | 12 | 12 | 7.5 | 85 Ohms | TOP=L2:L3=L2/L4:L6=L5/L7:BOTTOM=L7 |
| PCIE_RX_N41 | RXS41-DIFF1 | PAIR | 7 | 5.5 | 5 | 10 | 5 | 50 | 6 | 20 | 12 | 12 | 12 | 12 | 7.5 | 85 Ohms | TOP=L2:L3=L2/L4:L6=L5/L7:BOTTOM=L7 |
| PCIE_RX_N41 | RXS41-DIFF1 | PAIR | 8 | 5.38 | 5 | 10 | 5 | 50 | 6 | 33 | 12 | 12 | 12 | 12 | 6.62 | 85 Ohms | TOP=L2:L3=L2/L4:L6=L5/L7:BOTTOM=L7 |
| PCIE_RX_P41 | RXS41-DIFF1 | PAIR | 1 | 5.38 | 5 | 10 | 5 | 50 | 6 | 33 | 12 | 12 | 12 | 12 | 6.62 | 85 Ohms | TOP=L2:L3=L2/L4:L6=L5/L7:BOTTOM=L7 |
| PCIE_RX_P41 | RXS41-DIFF1 | PAIR | 2 | 5.5 | 5 | 10 | 5 | 50 | 6 | 20 | 12 | 12 | 12 | 12 | 7.5 | 85 Ohms | TOP=L2:L3=L2/L4:L6=L5/L7:BOTTOM=L7 |
| PCIE_RX_P41 | RXS41-DIFF1 | PAIR | 3 | 5.5 | 5 | 10 | 5 | 50 | 6 | 20 | 12 | 12 | 12 | 12 | 7.5 | 85 Ohms | TOP=L2:L3=L2/L4:L6=L5/L7:BOTTOM=L7 |
| PCIE_RX_P41 | RXS41-DIFF1 | PAIR | 4 | 5.5 | 5 | 10 | 5 | 50 | 6 | 20 | 12 | 12 | 12 | 12 | 7.5 | 85 Ohms | TOP=L2:L3=L2/L4:L6=L5/L7:BOTTOM=L7 |
| PCIE_RX_P41 | RXS41-DIFF1 | PAIR | 5 | 5.5 | 5 | 10 | 5 | 50 | 6 | 20 | 12 | 12 | 12 | 12 | 7.5 | 85 Ohms | TOP=L2:L3=L2/L4:L6=L5/L7:BOTTOM=L7 |
| PCIE_RX_P41 | RXS41-DIFF1 | PAIR | 6 | 5.5 | 5 | 10 | 5 | 50 | 6 | 20 | 12 | 12 | 12 | 12 | 7.5 | 85 Ohms | TOP=L2:L3=L2/L4:L6=L5/L7:BOTTOM=L7 |
| PCIE_RX_P41 | RXS41-DIFF1 | PAIR | 7 | 5.5 | 5 | 10 | 5 | 50 | 6 | 20 | 12 | 12 | 12 | 12 | 7.5 | 85 Ohms | TOP=L2:L3=L2/L4:L6=L5/L7:BOTTOM=L7 |
| PCIE_RX_P41 | RXS41-DIFF1 | PAIR | 8 | 5.38 | 5 | 10 | 5 | 50 | 6 | 33 | 12 | 12 | 12 | 12 | 6.62 | 85 Ohms | TOP=L2:L3=L2/L4:L6=L5/L7:BOTTOM=L7 |
| PCIE_RX_N42 | RXS42-DIFF1 | PAIR | 1 | 5.38 | 5 | 10 | 5 | 50 | 6 | 33 | 12 | 12 | 12 | 12 | 6.62 | 85 Ohms | TOP=L2:L3=L2/L4:L6=L5/L7:BOTTOM=L7 |
| PCIE_RX_N42 | RXS42-DIFF1 | PAIR | 2 | 5.5 | 5 | 10 | 5 | 50 | 6 | 20 | 12 | 12 | 12 | 12 | 7.5 | 85 Ohms | TOP=L2:L3=L2/L4:L6=L5/L7:BOTTOM=L7 |
| PCIE_RX_N42 | RXS42-DIFF1 | PAIR | 3 | 5.5 | 5 | 10 | 5 | 50 | 6 | 20 | 12 | 12 | 12 | 12 | 7.5 | 85 Ohms | TOP=L2:L3=L2/L4:L6=L5/L7:BOTTOM=L7 |
| PCIE_RX_N42 | RXS42-DIFF1 | PAIR | 4 | 5.5 | 5 | 10 | 5 | 50 | 6 | 20 | 12 | 12 | 12 | 12 | 7.5 | 85 Ohms | TOP=L2:L3=L2/L4:L6=L5/L7:BOTTOM=L7 |
| PCIE_RX_N42 | RXS42-DIFF1 | PAIR | 5 | 5.5 | 5 | 10 | 5 | 50 | 6 | 20 | 12 | 12 | 12 | 12 | 7.5 | 85 Ohms | TOP=L2:L3=L2/L4:L6=L5/L7:BOTTOM=L7 |
| PCIE_RX_N42 | RXS42-DIFF1 | PAIR | 6 | 5.5 | 5 | 10 | 5 | 50 | 6 | 20 | 12 | 12 | 12 | 12 | 7.5 | 85 Ohms | TOP=L2:L3=L2/L4:L6=L5/L7:BOTTOM=L7 |
| PCIE_RX_N42 | RXS42-DIFF1 | PAIR | 7 | 5.5 | 5 | 10 | 5 | 50 | 6 | 20 | 12 | 12 | 12 | 12 | 7.5 | 85 Ohms | TOP=L2:L3=L2/L4:L6=L5/L7:BOTTOM=L7 |
| PCIE_RX_N42 | RXS42-DIFF1 | PAIR | 8 | 5.38 | 5 | 10 | 5 | 50 | 6 | 33 | 12 | 12 | 12 | 12 | 6.62 | 85 Ohms | TOP=L2:L3=L2/L4:L6=L5/L7:BOTTOM=L7 |
| PCIE_RX_P42 | RXS42-DIFF1 | PAIR | 1 | 5.38 | 5 | 10 | 5 | 50 | 6 | 33 | 12 | 12 | 12 | 12 | 6.62 | 85 Ohms | TOP=L2:L3=L2/L4:L6=L5/L7:BOTTOM=L7 |
| PCIE_RX_P42 | RXS42-DIFF1 | PAIR | 2 | 5.5 | 5 | 10 | 5 | 50 | 6 | 20 | 12 | 12 | 12 | 12 | 7.5 | 85 Ohms | TOP=L2:L3=L2/L4:L6=L5/L7:BOTTOM=L7 |
| PCIE_RX_P42 | RXS42-DIFF1 | PAIR | 3 | 5.5 | 5 | 10 | 5 | 50 | 6 | 20 | 12 | 12 | 12 | 12 | 7.5 | 85 Ohms | TOP=L2:L3=L2/L4:L6=L5/L7:BOTTOM=L7 |
| PCIE_RX_P42 | RXS42-DIFF1 | PAIR | 4 | 5.5 | 5 | 10 | 5 | 50 | 6 | 20 | 12 | 12 | 12 | 12 | 7.5 | 85 Ohms | TOP=L2:L3=L2/L4:L6=L5/L7:BOTTOM=L7 |
| PCIE_RX_P42 | RXS42-DIFF1 | PAIR | 5 | 5.5 | 5 | 10 | 5 | 50 | 6 | 20 | 12 | 12 | 12 | 12 | 7.5 | 85 Ohms | TOP=L2:L3=L2/L4:L6=L5/L7:BOTTOM=L7 |
| PCIE_RX_P42 | RXS42-DIFF1 | PAIR | 6 | 5.5 | 5 | 10 | 5 | 50 | 6 | 20 | 12 | 12 | 12 | 12 | 7.5 | 85 Ohms | TOP=L2:L3=L2/L4:L6=L5/L7:BOTTOM=L7 |
| PCIE_RX_P42 | RXS42-DIFF1 | PAIR | 7 | 5.5 | 5 | 10 | 5 | 50 | 6 | 20 | 12 | 12 | 12 | 12 | 7.5 | 85 Ohms | TOP=L2:L3=L2/L4:L6=L5/L7:BOTTOM=L7 |
| PCIE_RX_P42 | RXS42-DIFF1 | PAIR | 8 | 5.38 | 5 | 10 | 5 | 50 | 6 | 33 | 12 | 12 | 12 | 12 | 6.62 | 85 Ohms | TOP=L2:L3=L2/L4:L6=L5/L7:BOTTOM=L7 |
| PCIE_RX_N43 | RXS43-DIFF1 | PAIR | 1 | 5.38 | 5 | 10 | 5 | 50 | 6 | 33 | 12 | 12 | 12 | 12 | 6.62 | 85 Ohms | TOP=L2:L3=L2/L4:L6=L5/L7:BOTTOM=L7 |
| PCIE_RX_N43 | RXS43-DIFF1 | PAIR | 2 | 5.5 | 5 | 10 | 5 | 50 | 6 | 20 | 12 | 12 | 12 | 12 | 7.5 | 85 Ohms | TOP=L2:L3=L2/L4:L6=L5/L7:BOTTOM=L7 |
| PCIE_RX_N43 | RXS43-DIFF1 | PAIR | 3 | 5.5 | 5 | 10 | 5 | 50 | 6 | 20 | 12 | 12 | 12 | 12 | 7.5 | 85 Ohms | TOP=L2:L3=L2/L4:L6=L5/L7:BOTTOM=L7 |
| PCIE_RX_N43 | RXS43-DIFF1 | PAIR | 4 | 5.5 | 5 | 10 | 5 | 50 | 6 | 20 | 12 | 12 | 12 | 12 | 7.5 | 85 Ohms | TOP=L2:L3=L2/L4:L6=L5/L7:BOTTOM=L7 |
| PCIE_RX_N43 | RXS43-DIFF1 | PAIR | 5 | 5.5 | 5 | 10 | 5 | 50 | 6 | 20 | 12 | 12 | 12 | 12 | 7.5 | 85 Ohms | TOP=L2:L3=L2/L4:L6=L5/L7:BOTTOM=L7 |
| PCIE_RX_N43 | RXS43-DIFF1 | PAIR | 6 | 5.5 | 5 | 10 | 5 | 50 | 6 | 20 | 12 | 12 | 12 | 12 | 7.5 | 85 Ohms | TOP=L2:L3=L2/L4:L6=L5/L7:BOTTOM=L7 |
| PCIE_RX_N43 | RXS43-DIFF1 | PAIR | 7 | 5.5 | 5 | 10 | 5 | 50 | 6 | 20 | 12 | 12 | 12 | 12 | 7.5 | 85 Ohms | TOP=L2:L3=L2/L4:L6=L5/L7:BOTTOM=L7 |
| PCIE_RX_N43 | RXS43-DIFF1 | PAIR | 8 | 5.38 | 5 | 10 | 5 | 50 | 6 | 33 | 12 | 12 | 12 | 12 | 6.62 | 85 Ohms | TOP=L2:L3=L2/L4:L6=L5/L7:BOTTOM=L7 |
| PCIE_RX_P43 | RXS43-DIFF1 | PAIR | 1 | 5.38 | 5 | 10 | 5 | 50 | 6 | 33 | 12 | 12 | 12 | 12 | 6.62 | 85 Ohms | TOP=L2:L3=L2/L4:L6=L5/L7:BOTTOM=L7 |
| PCIE_RX_P43 | RXS43-DIFF1 | PAIR | 2 | 5.5 | 5 | 10 | 5 | 50 | 6 | 20 | 12 | 12 | 12 | 12 | 7.5 | 85 Ohms | TOP=L2:L3=L2/L4:L6=L5/L7:BOTTOM=L7 |
| PCIE_RX_P43 | RXS43-DIFF1 | PAIR | 3 | 5.5 | 5 | 10 | 5 | 50 | 6 | 20 | 12 | 12 | 12 | 12 | 7.5 | 85 Ohms | TOP=L2:L3=L2/L4:L6=L5/L7:BOTTOM=L7 |
| PCIE_RX_P43 | RXS43-DIFF1 | PAIR | 4 | 5.5 | 5 | 10 | 5 | 50 | 6 | 20 | 12 | 12 | 12 | 12 | 7.5 | 85 Ohms | TOP=L2:L3=L2/L4:L6=L5/L7:BOTTOM=L7 |
| PCIE_RX_P43 | RXS43-DIFF1 | PAIR | 5 | 5.5 | 5 | 10 | 5 | 50 | 6 | 20 | 12 | 12 | 12 | 12 | 7.5 | 85 Ohms | TOP=L2:L3=L2/L4:L6=L5/L7:BOTTOM=L7 |
| PCIE_RX_P43 | RXS43-DIFF1 | PAIR | 6 | 5.5 | 5 | 10 | 5 | 50 | 6 | 20 | 12 | 12 | 12 | 12 | 7.5 | 85 Ohms | TOP=L2:L3=L2/L4:L6=L5/L7:BOTTOM=L7 |
| PCIE_RX_P43 | RXS43-DIFF1 | PAIR | 7 | 5.5 | 5 | 10 | 5 | 50 | 6 | 20 | 12 | 12 | 12 | 12 | 7.5 | 85 Ohms | TOP=L2:L3=L2/L4:L6=L5/L7:BOTTOM=L7 |
| PCIE_RX_P43 | RXS43-DIFF1 | PAIR | 8 | 5.38 | 5 | 10 | 5 | 50 | 6 | 33 | 12 | 12 | 12 | 12 | 6.62 | 85 Ohms | TOP=L2:L3=L2/L4:L6=L5/L7:BOTTOM=L7 |
| PCIE_RX_N44 | RXS44-DIFF1 | PAIR | 1 | 5.38 | 5 | 10 | 5 | 50 | 6 | 33 | 12 | 12 | 12 | 12 | 6.62 | 85 Ohms | TOP=L2:L3=L2/L4:L6=L5/L7:BOTTOM=L7 |
| PCIE_RX_N44 | RXS44-DIFF1 | PAIR | 2 | 5.5 | 5 | 10 | 5 | 50 | 6 | 20 | 12 | 12 | 12 | 12 | 7.5 | 85 Ohms | TOP=L2:L3=L2/L4:L6=L5/L7:BOTTOM=L7 |
| PCIE_RX_N44 | RXS44-DIFF1 | PAIR | 3 | 5.5 | 5 | 10 | 5 | 50 | 6 | 20 | 12 | 12 | 12 | 12 | 7.5 | 85 Ohms | TOP=L2:L3=L2/L4:L6=L5/L7:BOTTOM=L7 |
| PCIE_RX_N44 | RXS44-DIFF1 | PAIR | 4 | 5.5 | 5 | 10 | 5 | 50 | 6 | 20 | 12 | 12 | 12 | 12 | 7.5 | 85 Ohms | TOP=L2:L3=L2/L4:L6=L5/L7:BOTTOM=L7 |
| PCIE_RX_N44 | RXS44-DIFF1 | PAIR | 5 | 5.5 | 5 | 10 | 5 | 50 | 6 | 20 | 12 | 12 | 12 | 12 | 7.5 | 85 Ohms | TOP=L2:L3=L2/L4:L6=L5/L7:BOTTOM=L7 |
| PCIE_RX_N44 | RXS44-DIFF1 | PAIR | 6 | 5.5 | 5 | 10 | 5 | 50 | 6 | 20 | 12 | 12 | 12 | 12 | 7.5 | 85 Ohms | TOP=L2:L3=L2/L4:L6=L5/L7:BOTTOM=L7 |
| PCIE_RX_N44 | RXS44-DIFF1 | PAIR | 7 | 5.5 | 5 | 10 | 5 | 50 | 6 | 20 | 12 | 12 | 12 | 12 | 7.5 | 85 Ohms | TOP=L2:L3=L2/L4:L6=L5/L7:BOTTOM=L7 |
| PCIE_RX_N44 | RXS44-DIFF1 | PAIR | 8 | 5.38 | 5 | 10 | 5 | 50 | 6 | 33 | 12 | 12 | 12 | 12 | 6.62 | 85 Ohms | TOP=L2:L3=L2/L4:L6=L5/L7:BOTTOM=L7 |
| PCIE_RX_P44 | RXS44-DIFF1 | PAIR | 1 | 5.38 | 5 | 10 | 5 | 50 | 6 | 33 | 12 | 12 | 12 | 12 | 6.62 | 85 Ohms | TOP=L2:L3=L2/L4:L6=L5/L7:BOTTOM=L7 |
| PCIE_RX_P44 | RXS44-DIFF1 | PAIR | 2 | 5.5 | 5 | 10 | 5 | 50 | 6 | 20 | 12 | 12 | 12 | 12 | 7.5 | 85 Ohms | TOP=L2:L3=L2/L4:L6=L5/L7:BOTTOM=L7 |
| PCIE_RX_P44 | RXS44-DIFF1 | PAIR | 3 | 5.5 | 5 | 10 | 5 | 50 | 6 | 20 | 12 | 12 | 12 | 12 | 7.5 | 85 Ohms | TOP=L2:L3=L2/L4:L6=L5/L7:BOTTOM=L7 |
| PCIE_RX_P44 | RXS44-DIFF1 | PAIR | 4 | 5.5 | 5 | 10 | 5 | 50 | 6 | 20 | 12 | 12 | 12 | 12 | 7.5 | 85 Ohms | TOP=L2:L3=L2/L4:L6=L5/L7:BOTTOM=L7 |
| PCIE_RX_P44 | RXS44-DIFF1 | PAIR | 5 | 5.5 | 5 | 10 | 5 | 50 | 6 | 20 | 12 | 12 | 12 | 12 | 7.5 | 85 Ohms | TOP=L2:L3=L2/L4:L6=L5/L7:BOTTOM=L7 |
| PCIE_RX_P44 | RXS44-DIFF1 | PAIR | 6 | 5.5 | 5 | 10 | 5 | 50 | 6 | 20 | 12 | 12 | 12 | 12 | 7.5 | 85 Ohms | TOP=L2:L3=L2/L4:L6=L5/L7:BOTTOM=L7 |
| PCIE_RX_P44 | RXS44-DIFF1 | PAIR | 7 | 5.5 | 5 | 10 | 5 | 50 | 6 | 20 | 12 | 12 | 12 | 12 | 7.5 | 85 Ohms | TOP=L2:L3=L2/L4:L6=L5/L7:BOTTOM=L7 |
| PCIE_RX_P44 | RXS44-DIFF1 | PAIR | 8 | 5.38 | 5 | 10 | 5 | 50 | 6 | 33 | 12 | 12 | 12 | 12 | 6.62 | 85 Ohms | TOP=L2:L3=L2/L4:L6=L5/L7:BOTTOM=L7 |
| PCIE_RX_N45 | RXS45-DIFF1 | PAIR | 1 | 5.38 | 5 | 10 | 5 | 50 | 6 | 33 | 12 | 12 | 12 | 12 | 6.62 | 85 Ohms | TOP=L2:L3=L2/L4:L6=L5/L7:BOTTOM=L7 |
| PCIE_RX_N45 | RXS45-DIFF1 | PAIR | 2 | 5.5 | 5 | 10 | 5 | 50 | 6 | 20 | 12 | 12 | 12 | 12 | 7.5 | 85 Ohms | TOP=L2:L3=L2/L4:L6=L5/L7:BOTTOM=L7 |
| PCIE_RX_N45 | RXS45-DIFF1 | PAIR | 3 | 5.5 | 5 | 10 | 5 | 50 | 6 | 20 | 12 | 12 | 12 | 12 | 7.5 | 85 Ohms | TOP=L2:L3=L2/L4:L6=L5/L7:BOTTOM=L7 |
| PCIE_RX_N45 | RXS45-DIFF1 | PAIR | 4 | 5.5 | 5 | 10 | 5 | 50 | 6 | 20 | 12 | 12 | 12 | 12 | 7.5 | 85 Ohms | TOP=L2:L3=L2/L4:L6=L5/L7:BOTTOM=L7 |
| PCIE_RX_N45 | RXS45-DIFF1 | PAIR | 5 | 5.5 | 5 | 10 | 5 | 50 | 6 | 20 | 12 | 12 | 12 | 12 | 7.5 | 85 Ohms | TOP=L2:L3=L2/L4:L6=L5/L7:BOTTOM=L7 |
| PCIE_RX_N45 | RXS45-DIFF1 | PAIR | 6 | 5.5 | 5 | 10 | 5 | 50 | 6 | 20 | 12 | 12 | 12 | 12 | 7.5 | 85 Ohms | TOP=L2:L3=L2/L4:L6=L5/L7:BOTTOM=L7 |
| PCIE_RX_N45 | RXS45-DIFF1 | PAIR | 7 | 5.5 | 5 | 10 | 5 | 50 | 6 | 20 | 12 | 12 | 12 | 12 | 7.5 | 85 Ohms | TOP=L2:L3=L2/L4:L6=L5/L7:BOTTOM=L7 |
| PCIE_RX_N45 | RXS45-DIFF1 | PAIR | 8 | 5.38 | 5 | 10 | 5 | 50 | 6 | 33 | 12 | 12 | 12 | 12 | 6.62 | 85 Ohms | TOP=L2:L3=L2/L4:L6=L5/L7:BOTTOM=L7 |
| PCIE_RX_P45 | RXS45-DIFF1 | PAIR | 1 | 5.38 | 5 | 10 | 5 | 50 | 6 | 33 | 12 | 12 | 12 | 12 | 6.62 | 85 Ohms | TOP=L2:L3=L2/L4:L6=L5/L7:BOTTOM=L7 |
| PCIE_RX_P45 | RXS45-DIFF1 | PAIR | 2 | 5.5 | 5 | 10 | 5 | 50 | 6 | 20 | 12 | 12 | 12 | 12 | 7.5 | 85 Ohms | TOP=L2:L3=L2/L4:L6=L5/L7:BOTTOM=L7 |
| PCIE_RX_P45 | RXS45-DIFF1 | PAIR | 3 | 5.5 | 5 | 10 | 5 | 50 | 6 | 20 | 12 | 12 | 12 | 12 | 7.5 | 85 Ohms | TOP=L2:L3=L2/L4:L6=L5/L7:BOTTOM=L7 |
| PCIE_RX_P45 | RXS45-DIFF1 | PAIR | 4 | 5.5 | 5 | 10 | 5 | 50 | 6 | 20 | 12 | 12 | 12 | 12 | 7.5 | 85 Ohms | TOP=L2:L3=L2/L4:L6=L5/L7:BOTTOM=L7 |
| PCIE_RX_P45 | RXS45-DIFF1 | PAIR | 5 | 5.5 | 5 | 10 | 5 | 50 | 6 | 20 | 12 | 12 | 12 | 12 | 7.5 | 85 Ohms | TOP=L2:L3=L2/L4:L6=L5/L7:BOTTOM=L7 |
| PCIE_RX_P45 | RXS45-DIFF1 | PAIR | 6 | 5.5 | 5 | 10 | 5 | 50 | 6 | 20 | 12 | 12 | 12 | 12 | 7.5 | 85 Ohms | TOP=L2:L3=L2/L4:L6=L5/L7:BOTTOM=L7 |
| PCIE_RX_P45 | RXS45-DIFF1 | PAIR | 7 | 5.5 | 5 | 10 | 5 | 50 | 6 | 20 | 12 | 12 | 12 | 12 | 7.5 | 85 Ohms | TOP=L2:L3=L2/L4:L6=L5/L7:BOTTOM=L7 |
| PCIE_RX_P45 | RXS45-DIFF1 | PAIR | 8 | 5.38 | 5 | 10 | 5 | 50 | 6 | 33 | 12 | 12 | 12 | 12 | 6.62 | 85 Ohms | TOP=L2:L3=L2/L4:L6=L5/L7:BOTTOM=L7 |
| PCIE_RX_N46 | RXS46-DIFF1 | PAIR | 1 | 5.38 | 5 | 10 | 5 | 50 | 6 | 33 | 12 | 12 | 12 | 12 | 6.62 | 85 Ohms | TOP=L2:L3=L2/L4:L6=L5/L7:BOTTOM=L7 |
| PCIE_RX_N46 | RXS46-DIFF1 | PAIR | 2 | 5.5 | 5 | 10 | 5 | 50 | 6 | 20 | 12 | 12 | 12 | 12 | 7.5 | 85 Ohms | TOP=L2:L3=L2/L4:L6=L5/L7:BOTTOM=L7 |
| PCIE_RX_N46 | RXS46-DIFF1 | PAIR | 3 | 5.5 | 5 | 10 | 5 | 50 | 6 | 20 | 12 | 12 | 12 | 12 | 7.5 | 85 Ohms | TOP=L2:L3=L2/L4:L6=L5/L7:BOTTOM=L7 |
| PCIE_RX_N46 | RXS46-DIFF1 | PAIR | 4 | 5.5 | 5 | 10 | 5 | 50 | 6 | 20 | 12 | 12 | 12 | 12 | 7.5 | 85 Ohms | TOP=L2:L3=L2/L4:L6=L5/L7:BOTTOM=L7 |
| PCIE_RX_N46 | RXS46-DIFF1 | PAIR | 5 | 5.5 | 5 | 10 | 5 | 50 | 6 | 20 | 12 | 12 | 12 | 12 | 7.5 | 85 Ohms | TOP=L2:L3=L2/L4:L6=L5/L7:BOTTOM=L7 |
| PCIE_RX_N46 | RXS46-DIFF1 | PAIR | 6 | 5.5 | 5 | 10 | 5 | 50 | 6 | 20 | 12 | 12 | 12 | 12 | 7.5 | 85 Ohms | TOP=L2:L3=L2/L4:L6=L5/L7:BOTTOM=L7 |
| PCIE_RX_N46 | RXS46-DIFF1 | PAIR | 7 | 5.5 | 5 | 10 | 5 | 50 | 6 | 20 | 12 | 12 | 12 | 12 | 7.5 | 85 Ohms | TOP=L2:L3=L2/L4:L6=L5/L7:BOTTOM=L7 |
| PCIE_RX_N46 | RXS46-DIFF1 | PAIR | 8 | 5.38 | 5 | 10 | 5 | 50 | 6 | 33 | 12 | 12 | 12 | 12 | 6.62 | 85 Ohms | TOP=L2:L3=L2/L4:L6=L5/L7:BOTTOM=L7 |
| PCIE_RX_P46 | RXS46-DIFF1 | PAIR | 1 | 5.38 | 5 | 10 | 5 | 50 | 6 | 33 | 12 | 12 | 12 | 12 | 6.62 | 85 Ohms | TOP=L2:L3=L2/L4:L6=L5/L7:BOTTOM=L7 |
| PCIE_RX_P46 | RXS46-DIFF1 | PAIR | 2 | 5.5 | 5 | 10 | 5 | 50 | 6 | 20 | 12 | 12 | 12 | 12 | 7.5 | 85 Ohms | TOP=L2:L3=L2/L4:L6=L5/L7:BOTTOM=L7 |
| PCIE_RX_P46 | RXS46-DIFF1 | PAIR | 3 | 5.5 | 5 | 10 | 5 | 50 | 6 | 20 | 12 | 12 | 12 | 12 | 7.5 | 85 Ohms | TOP=L2:L3=L2/L4:L6=L5/L7:BOTTOM=L7 |
| PCIE_RX_P46 | RXS46-DIFF1 | PAIR | 4 | 5.5 | 5 | 10 | 5 | 50 | 6 | 20 | 12 | 12 | 12 | 12 | 7.5 | 85 Ohms | TOP=L2:L3=L2/L4:L6=L5/L7:BOTTOM=L7 |
| PCIE_RX_P46 | RXS46-DIFF1 | PAIR | 5 | 5.5 | 5 | 10 | 5 | 50 | 6 | 20 | 12 | 12 | 12 | 12 | 7.5 | 85 Ohms | TOP=L2:L3=L2/L4:L6=L5/L7:BOTTOM=L7 |
| PCIE_RX_P46 | RXS46-DIFF1 | PAIR | 6 | 5.5 | 5 | 10 | 5 | 50 | 6 | 20 | 12 | 12 | 12 | 12 | 7.5 | 85 Ohms | TOP=L2:L3=L2/L4:L6=L5/L7:BOTTOM=L7 |
| PCIE_RX_P46 | RXS46-DIFF1 | PAIR | 7 | 5.5 | 5 | 10 | 5 | 50 | 6 | 20 | 12 | 12 | 12 | 12 | 7.5 | 85 Ohms | TOP=L2:L3=L2/L4:L6=L5/L7:BOTTOM=L7 |
| PCIE_RX_P46 | RXS46-DIFF1 | PAIR | 8 | 5.38 | 5 | 10 | 5 | 50 | 6 | 33 | 12 | 12 | 12 | 12 | 6.62 | 85 Ohms | TOP=L2:L3=L2/L4:L6=L5/L7:BOTTOM=L7 |
| PCIE_RX_N47 | RXS47-DIFF1 | PAIR | 1 | 5.38 | 5 | 10 | 5 | 50 | 6 | 33 | 12 | 12 | 12 | 12 | 6.62 | 85 Ohms | TOP=L2:L3=L2/L4:L6=L5/L7:BOTTOM=L7 |
| PCIE_RX_N47 | RXS47-DIFF1 | PAIR | 2 | 5.5 | 5 | 10 | 5 | 50 | 6 | 20 | 12 | 12 | 12 | 12 | 7.5 | 85 Ohms | TOP=L2:L3=L2/L4:L6=L5/L7:BOTTOM=L7 |
| PCIE_RX_N47 | RXS47-DIFF1 | PAIR | 3 | 5.5 | 5 | 10 | 5 | 50 | 6 | 20 | 12 | 12 | 12 | 12 | 7.5 | 85 Ohms | TOP=L2:L3=L2/L4:L6=L5/L7:BOTTOM=L7 |
| PCIE_RX_N47 | RXS47-DIFF1 | PAIR | 4 | 5.5 | 5 | 10 | 5 | 50 | 6 | 20 | 12 | 12 | 12 | 12 | 7.5 | 85 Ohms | TOP=L2:L3=L2/L4:L6=L5/L7:BOTTOM=L7 |
| PCIE_RX_N47 | RXS47-DIFF1 | PAIR | 5 | 5.5 | 5 | 10 | 5 | 50 | 6 | 20 | 12 | 12 | 12 | 12 | 7.5 | 85 Ohms | TOP=L2:L3=L2/L4:L6=L5/L7:BOTTOM=L7 |
| PCIE_RX_N47 | RXS47-DIFF1 | PAIR | 6 | 5.5 | 5 | 10 | 5 | 50 | 6 | 20 | 12 | 12 | 12 | 12 | 7.5 | 85 Ohms | TOP=L2:L3=L2/L4:L6=L5/L7:BOTTOM=L7 |
| PCIE_RX_N47 | RXS47-DIFF1 | PAIR | 7 | 5.5 | 5 | 10 | 5 | 50 | 6 | 20 | 12 | 12 | 12 | 12 | 7.5 | 85 Ohms | TOP=L2:L3=L2/L4:L6=L5/L7:BOTTOM=L7 |
| PCIE_RX_N47 | RXS47-DIFF1 | PAIR | 8 | 5.38 | 5 | 10 | 5 | 50 | 6 | 33 | 12 | 12 | 12 | 12 | 6.62 | 85 Ohms | TOP=L2:L3=L2/L4:L6=L5/L7:BOTTOM=L7 |
| PCIE_RX_P47 | RXS47-DIFF1 | PAIR | 1 | 5.38 | 5 | 10 | 5 | 50 | 6 | 33 | 12 | 12 | 12 | 12 | 6.62 | 85 Ohms | TOP=L2:L3=L2/L4:L6=L5/L7:BOTTOM=L7 |
| PCIE_RX_P47 | RXS47-DIFF1 | PAIR | 2 | 5.5 | 5 | 10 | 5 | 50 | 6 | 20 | 12 | 12 | 12 | 12 | 7.5 | 85 Ohms | TOP=L2:L3=L2/L4:L6=L5/L7:BOTTOM=L7 |
| PCIE_RX_P47 | RXS47-DIFF1 | PAIR | 3 | 5.5 | 5 | 10 | 5 | 50 | 6 | 20 | 12 | 12 | 12 | 12 | 7.5 | 85 Ohms | TOP=L2:L3=L2/L4:L6=L5/L7:BOTTOM=L7 |
| PCIE_RX_P47 | RXS47-DIFF1 | PAIR | 4 | 5.5 | 5 | 10 | 5 | 50 | 6 | 20 | 12 | 12 | 12 | 12 | 7.5 | 85 Ohms | TOP=L2:L3=L2/L4:L6=L5/L7:BOTTOM=L7 |
| PCIE_RX_P47 | RXS47-DIFF1 | PAIR | 5 | 5.5 | 5 | 10 | 5 | 50 | 6 | 20 | 12 | 12 | 12 | 12 | 7.5 | 85 Ohms | TOP=L2:L3=L2/L4:L6=L5/L7:BOTTOM=L7 |
| PCIE_RX_P47 | RXS47-DIFF1 | PAIR | 6 | 5.5 | 5 | 10 | 5 | 50 | 6 | 20 | 12 | 12 | 12 | 12 | 7.5 | 85 Ohms | TOP=L2:L3=L2/L4:L6=L5/L7:BOTTOM=L7 |
| PCIE_RX_P47 | RXS47-DIFF1 | PAIR | 7 | 5.5 | 5 | 10 | 5 | 50 | 6 | 20 | 12 | 12 | 12 | 12 | 7.5 | 85 Ohms | TOP=L2:L3=L2/L4:L6=L5/L7:BOTTOM=L7 |
| PCIE_RX_P47 | RXS47-DIFF1 | PAIR | 8 | 5.38 | 5 | 10 | 5 | 50 | 6 | 33 | 12 | 12 | 12 | 12 | 6.62 | 85 Ohms | TOP=L2:L3=L2/L4:L6=L5/L7:BOTTOM=L7 |
| PCIE_RX_N48 | RXS48-DIFF1 | PAIR | 1 | 5.38 | 5 | 10 | 5 | 50 | 6 | 33 | 12 | 12 | 12 | 12 | 6.62 | 85 Ohms | TOP=L2:L3=L2/L4:L6=L5/L7:BOTTOM=L7 |
| PCIE_RX_N48 | RXS48-DIFF1 | PAIR | 2 | 5.5 | 5 | 10 | 5 | 50 | 6 | 20 | 12 | 12 | 12 | 12 | 7.5 | 85 Ohms | TOP=L2:L3=L2/L4:L6=L5/L7:BOTTOM=L7 |
| PCIE_RX_N48 | RXS48-DIFF1 | PAIR | 3 | 5.5 | 5 | 10 | 5 | 50 | 6 | 20 | 12 | 12 | 12 | 12 | 7.5 | 85 Ohms | TOP=L2:L3=L2/L4:L6=L5/L7:BOTTOM=L7 |
| PCIE_RX_N48 | RXS48-DIFF1 | PAIR | 4 | 5.5 | 5 | 10 | 5 | 50 | 6 | 20 | 12 | 12 | 12 | 12 | 7.5 | 85 Ohms | TOP=L2:L3=L2/L4:L6=L5/L7:BOTTOM=L7 |
| PCIE_RX_N48 | RXS48-DIFF1 | PAIR | 5 | 5.5 | 5 | 10 | 5 | 50 | 6 | 20 | 12 | 12 | 12 | 12 | 7.5 | 85 Ohms | TOP=L2:L3=L2/L4:L6=L5/L7:BOTTOM=L7 |
| PCIE_RX_N48 | RXS48-DIFF1 | PAIR | 6 | 5.5 | 5 | 10 | 5 | 50 | 6 | 20 | 12 | 12 | 12 | 12 | 7.5 | 85 Ohms | TOP=L2:L3=L2/L4:L6=L5/L7:BOTTOM=L7 |
| PCIE_RX_N48 | RXS48-DIFF1 | PAIR | 7 | 5.5 | 5 | 10 | 5 | 50 | 6 | 20 | 12 | 12 | 12 | 12 | 7.5 | 85 Ohms | TOP=L2:L3=L2/L4:L6=L5/L7:BOTTOM=L7 |
| PCIE_RX_N48 | RXS48-DIFF1 | PAIR | 8 | 5.38 | 5 | 10 | 5 | 50 | 6 | 33 | 12 | 12 | 12 | 12 | 6.62 | 85 Ohms | TOP=L2:L3=L2/L4:L6=L5/L7:BOTTOM=L7 |
| PCIE_RX_P48 | RXS48-DIFF1 | PAIR | 1 | 5.38 | 5 | 10 | 5 | 50 | 6 | 33 | 12 | 12 | 12 | 12 | 6.62 | 85 Ohms | TOP=L2:L3=L2/L4:L6=L5/L7:BOTTOM=L7 |
| PCIE_RX_P48 | RXS48-DIFF1 | PAIR | 2 | 5.5 | 5 | 10 | 5 | 50 | 6 | 20 | 12 | 12 | 12 | 12 | 7.5 | 85 Ohms | TOP=L2:L3=L2/L4:L6=L5/L7:BOTTOM=L7 |
| PCIE_RX_P48 | RXS48-DIFF1 | PAIR | 3 | 5.5 | 5 | 10 | 5 | 50 | 6 | 20 | 12 | 12 | 12 | 12 | 7.5 | 85 Ohms | TOP=L2:L3=L2/L4:L6=L5/L7:BOTTOM=L7 |
| PCIE_RX_P48 | RXS48-DIFF1 | PAIR | 4 | 5.5 | 5 | 10 | 5 | 50 | 6 | 20 | 12 | 12 | 12 | 12 | 7.5 | 85 Ohms | TOP=L2:L3=L2/L4:L6=L5/L7:BOTTOM=L7 |
| PCIE_RX_P48 | RXS48-DIFF1 | PAIR | 5 | 5.5 | 5 | 10 | 5 | 50 | 6 | 20 | 12 | 12 | 12 | 12 | 7.5 | 85 Ohms | TOP=L2:L3=L2/L4:L6=L5/L7:BOTTOM=L7 |
| PCIE_RX_P48 | RXS48-DIFF1 | PAIR | 6 | 5.5 | 5 | 10 | 5 | 50 | 6 | 20 | 12 | 12 | 12 | 12 | 7.5 | 85 Ohms | TOP=L2:L3=L2/L4:L6=L5/L7:BOTTOM=L7 |
| PCIE_RX_P48 | RXS48-DIFF1 | PAIR | 7 | 5.5 | 5 | 10 | 5 | 50 | 6 | 20 | 12 | 12 | 12 | 12 | 7.5 | 85 Ohms | TOP=L2:L3=L2/L4:L6=L5/L7:BOTTOM=L7 |
| PCIE_RX_P48 | RXS48-DIFF1 | PAIR | 8 | 5.38 | 5 | 10 | 5 | 50 | 6 | 33 | 12 | 12 | 12 | 12 | 6.62 | 85 Ohms | TOP=L2:L3=L2/L4:L6=L5/L7:BOTTOM=L7 |
| PCIE_RX_N49 | RXS49-DIFF1 | PAIR | 1 | 5.38 | 5 | 10 | 5 | 50 | 6 | 33 | 12 | 12 | 12 | 12 | 6.62 | 85 Ohms | TOP=L2:L3=L2/L4:L6=L5/L7:BOTTOM=L7 |
| PCIE_RX_N49 | RXS49-DIFF1 | PAIR | 2 | 5.5 | 5 | 10 | 5 | 50 | 6 | 20 | 12 | 12 | 12 | 12 | 7.5 | 85 Ohms | TOP=L2:L3=L2/L4:L6=L5/L7:BOTTOM=L7 |
| PCIE_RX_N49 | RXS49-DIFF1 | PAIR | 3 | 5.5 | 5 | 10 | 5 | 50 | 6 | 20 | 12 | 12 | 12 | 12 | 7.5 | 85 Ohms | TOP=L2:L3=L2/L4:L6=L5/L7:BOTTOM=L7 |
| PCIE_RX_N49 | RXS49-DIFF1 | PAIR | 4 | 5.5 | 5 | 10 | 5 | 50 | 6 | 20 | 12 | 12 | 12 | 12 | 7.5 | 85 Ohms | TOP=L2:L3=L2/L4:L6=L5/L7:BOTTOM=L7 |
| PCIE_RX_N49 | RXS49-DIFF1 | PAIR | 5 | 5.5 | 5 | 10 | 5 | 50 | 6 | 20 | 12 | 12 | 12 | 12 | 7.5 | 85 Ohms | TOP=L2:L3=L2/L4:L6=L5/L7:BOTTOM=L7 |
| PCIE_RX_N49 | RXS49-DIFF1 | PAIR | 6 | 5.5 | 5 | 10 | 5 | 50 | 6 | 20 | 12 | 12 | 12 | 12 | 7.5 | 85 Ohms | TOP=L2:L3=L2/L4:L6=L5/L7:BOTTOM=L7 |
| PCIE_RX_N49 | RXS49-DIFF1 | PAIR | 7 | 5.5 | 5 | 10 | 5 | 50 | 6 | 20 | 12 | 12 | 12 | 12 | 7.5 | 85 Ohms | TOP=L2:L3=L2/L4:L6=L5/L7:BOTTOM=L7 |
| PCIE_RX_N49 | RXS49-DIFF1 | PAIR | 8 | 5.38 | 5 | 10 | 5 | 50 | 6 | 33 | 12 | 12 | 12 | 12 | 6.62 | 85 Ohms | TOP=L2:L3=L2/L4:L6=L5/L7:BOTTOM=L7 |
| PCIE_RX_P49 | RXS49-DIFF1 | PAIR | 1 | 5.38 | 5 | 10 | 5 | 50 | 6 | 33 | 12 | 12 | 12 | 12 | 6.62 | 85 Ohms | TOP=L2:L3=L2/L4:L6=L5/L7:BOTTOM=L7 |
| PCIE_RX_P49 | RXS49-DIFF1 | PAIR | 2 | 5.5 | 5 | 10 | 5 | 50 | 6 | 20 | 12 | 12 | 12 | 12 | 7.5 | 85 Ohms | TOP=L2:L3=L2/L4:L6=L5/L7:BOTTOM=L7 |
| PCIE_RX_P49 | RXS49-DIFF1 | PAIR | 3 | 5.5 | 5 | 10 | 5 | 50 | 6 | 20 | 12 | 12 | 12 | 12 | 7.5 | 85 Ohms | TOP=L2:L3=L2/L4:L6=L5/L7:BOTTOM=L7 |
| PCIE_RX_P49 | RXS49-DIFF1 | PAIR | 4 | 5.5 | 5 | 10 | 5 | 50 | 6 | 20 | 12 | 12 | 12 | 12 | 7.5 | 85 Ohms | TOP=L2:L3=L2/L4:L6=L5/L7:BOTTOM=L7 |
| PCIE_RX_P49 | RXS49-DIFF1 | PAIR | 5 | 5.5 | 5 | 10 | 5 | 50 | 6 | 20 | 12 | 12 | 12 | 12 | 7.5 | 85 Ohms | TOP=L2:L3=L2/L4:L6=L5/L7:BOTTOM=L7 |
| PCIE_RX_P49 | RXS49-DIFF1 | PAIR | 6 | 5.5 | 5 | 10 | 5 | 50 | 6 | 20 | 12 | 12 | 12 | 12 | 7.5 | 85 Ohms | TOP=L2:L3=L2/L4:L6=L5/L7:BOTTOM=L7 |
| PCIE_RX_P49 | RXS49-DIFF1 | PAIR | 7 | 5.5 | 5 | 10 | 5 | 50 | 6 | 20 | 12 | 12 | 12 | 12 | 7.5 | 85 Ohms | TOP=L2:L3=L2/L4:L6=L5/L7:BOTTOM=L7 |
| PCIE_RX_P49 | RXS49-DIFF1 | PAIR | 8 | 5.38 | 5 | 10 | 5 | 50 | 6 | 33 | 12 | 12 | 12 | 12 | 6.62 | 85 Ohms | TOP=L2:L3=L2/L4:L6=L5/L7:BOTTOM=L7 |
| PCIE_RX_N4 | RXS4-DIFF1 | PAIR | 1 | 5.38 | 5 | 10 | 5 | 50 | 6 | 33 | 12 | 12 | 12 | 12 | 6.62 | 85 Ohms | TOP=L2:L3=L2/L4:L6=L5/L7:BOTTOM=L7 |
| PCIE_RX_N4 | RXS4-DIFF1 | PAIR | 2 | 5.5 | 5 | 10 | 5 | 50 | 6 | 20 | 12 | 12 | 12 | 12 | 7.5 | 85 Ohms | TOP=L2:L3=L2/L4:L6=L5/L7:BOTTOM=L7 |
| PCIE_RX_N4 | RXS4-DIFF1 | PAIR | 3 | 5.5 | 5 | 10 | 5 | 50 | 6 | 20 | 12 | 12 | 12 | 12 | 7.5 | 85 Ohms | TOP=L2:L3=L2/L4:L6=L5/L7:BOTTOM=L7 |
| PCIE_RX_N4 | RXS4-DIFF1 | PAIR | 4 | 5.5 | 5 | 10 | 5 | 50 | 6 | 20 | 12 | 12 | 12 | 12 | 7.5 | 85 Ohms | TOP=L2:L3=L2/L4:L6=L5/L7:BOTTOM=L7 |
| PCIE_RX_N4 | RXS4-DIFF1 | PAIR | 5 | 5.5 | 5 | 10 | 5 | 50 | 6 | 20 | 12 | 12 | 12 | 12 | 7.5 | 85 Ohms | TOP=L2:L3=L2/L4:L6=L5/L7:BOTTOM=L7 |
| PCIE_RX_N4 | RXS4-DIFF1 | PAIR | 6 | 5.5 | 5 | 10 | 5 | 50 | 6 | 20 | 12 | 12 | 12 | 12 | 7.5 | 85 Ohms | TOP=L2:L3=L2/L4:L6=L5/L7:BOTTOM=L7 |
| PCIE_RX_N4 | RXS4-DIFF1 | PAIR | 7 | 5.5 | 5 | 10 | 5 | 50 | 6 | 20 | 12 | 12 | 12 | 12 | 7.5 | 85 Ohms | TOP=L2:L3=L2/L4:L6=L5/L7:BOTTOM=L7 |
| PCIE_RX_N4 | RXS4-DIFF1 | PAIR | 8 | 5.38 | 5 | 10 | 5 | 50 | 6 | 33 | 12 | 12 | 12 | 12 | 6.62 | 85 Ohms | TOP=L2:L3=L2/L4:L6=L5/L7:BOTTOM=L7 |
| PCIE_RX_P4 | RXS4-DIFF1 | PAIR | 1 | 5.38 | 5 | 10 | 5 | 50 | 6 | 33 | 12 | 12 | 12 | 12 | 6.62 | 85 Ohms | TOP=L2:L3=L2/L4:L6=L5/L7:BOTTOM=L7 |
| PCIE_RX_P4 | RXS4-DIFF1 | PAIR | 2 | 5.5 | 5 | 10 | 5 | 50 | 6 | 20 | 12 | 12 | 12 | 12 | 7.5 | 85 Ohms | TOP=L2:L3=L2/L4:L6=L5/L7:BOTTOM=L7 |
| PCIE_RX_P4 | RXS4-DIFF1 | PAIR | 3 | 5.5 | 5 | 10 | 5 | 50 | 6 | 20 | 12 | 12 | 12 | 12 | 7.5 | 85 Ohms | TOP=L2:L3=L2/L4:L6=L5/L7:BOTTOM=L7 |
| PCIE_RX_P4 | RXS4-DIFF1 | PAIR | 4 | 5.5 | 5 | 10 | 5 | 50 | 6 | 20 | 12 | 12 | 12 | 12 | 7.5 | 85 Ohms | TOP=L2:L3=L2/L4:L6=L5/L7:BOTTOM=L7 |
| PCIE_RX_P4 | RXS4-DIFF1 | PAIR | 5 | 5.5 | 5 | 10 | 5 | 50 | 6 | 20 | 12 | 12 | 12 | 12 | 7.5 | 85 Ohms | TOP=L2:L3=L2/L4:L6=L5/L7:BOTTOM=L7 |
| PCIE_RX_P4 | RXS4-DIFF1 | PAIR | 6 | 5.5 | 5 | 10 | 5 | 50 | 6 | 20 | 12 | 12 | 12 | 12 | 7.5 | 85 Ohms | TOP=L2:L3=L2/L4:L6=L5/L7:BOTTOM=L7 |
| PCIE_RX_P4 | RXS4-DIFF1 | PAIR | 7 | 5.5 | 5 | 10 | 5 | 50 | 6 | 20 | 12 | 12 | 12 | 12 | 7.5 | 85 Ohms | TOP=L2:L3=L2/L4:L6=L5/L7:BOTTOM=L7 |
| PCIE_RX_P4 | RXS4-DIFF1 | PAIR | 8 | 5.38 | 5 | 10 | 5 | 50 | 6 | 33 | 12 | 12 | 12 | 12 | 6.62 | 85 Ohms | TOP=L2:L3=L2/L4:L6=L5/L7:BOTTOM=L7 |
| PCIE_RX_N50 | RXS50-DIFF1 | PAIR | 1 | 5.38 | 5 | 10 | 5 | 50 | 6 | 33 | 12 | 12 | 12 | 12 | 6.62 | 85 Ohms | TOP=L2:L3=L2/L4:L6=L5/L7:BOTTOM=L7 |
| PCIE_RX_N50 | RXS50-DIFF1 | PAIR | 2 | 5.5 | 5 | 10 | 5 | 50 | 6 | 20 | 12 | 12 | 12 | 12 | 7.5 | 85 Ohms | TOP=L2:L3=L2/L4:L6=L5/L7:BOTTOM=L7 |
| PCIE_RX_N50 | RXS50-DIFF1 | PAIR | 3 | 5.5 | 5 | 10 | 5 | 50 | 6 | 20 | 12 | 12 | 12 | 12 | 7.5 | 85 Ohms | TOP=L2:L3=L2/L4:L6=L5/L7:BOTTOM=L7 |
| PCIE_RX_N50 | RXS50-DIFF1 | PAIR | 4 | 5.5 | 5 | 10 | 5 | 50 | 6 | 20 | 12 | 12 | 12 | 12 | 7.5 | 85 Ohms | TOP=L2:L3=L2/L4:L6=L5/L7:BOTTOM=L7 |
| PCIE_RX_N50 | RXS50-DIFF1 | PAIR | 5 | 5.5 | 5 | 10 | 5 | 50 | 6 | 20 | 12 | 12 | 12 | 12 | 7.5 | 85 Ohms | TOP=L2:L3=L2/L4:L6=L5/L7:BOTTOM=L7 |
| PCIE_RX_N50 | RXS50-DIFF1 | PAIR | 6 | 5.5 | 5 | 10 | 5 | 50 | 6 | 20 | 12 | 12 | 12 | 12 | 7.5 | 85 Ohms | TOP=L2:L3=L2/L4:L6=L5/L7:BOTTOM=L7 |
| PCIE_RX_N50 | RXS50-DIFF1 | PAIR | 7 | 5.5 | 5 | 10 | 5 | 50 | 6 | 20 | 12 | 12 | 12 | 12 | 7.5 | 85 Ohms | TOP=L2:L3=L2/L4:L6=L5/L7:BOTTOM=L7 |
| PCIE_RX_N50 | RXS50-DIFF1 | PAIR | 8 | 5.38 | 5 | 10 | 5 | 50 | 6 | 33 | 12 | 12 | 12 | 12 | 6.62 | 85 Ohms | TOP=L2:L3=L2/L4:L6=L5/L7:BOTTOM=L7 |
| PCIE_RX_P50 | RXS50-DIFF1 | PAIR | 1 | 5.38 | 5 | 10 | 5 | 50 | 6 | 33 | 12 | 12 | 12 | 12 | 6.62 | 85 Ohms | TOP=L2:L3=L2/L4:L6=L5/L7:BOTTOM=L7 |
| PCIE_RX_P50 | RXS50-DIFF1 | PAIR | 2 | 5.5 | 5 | 10 | 5 | 50 | 6 | 20 | 12 | 12 | 12 | 12 | 7.5 | 85 Ohms | TOP=L2:L3=L2/L4:L6=L5/L7:BOTTOM=L7 |
| PCIE_RX_P50 | RXS50-DIFF1 | PAIR | 3 | 5.5 | 5 | 10 | 5 | 50 | 6 | 20 | 12 | 12 | 12 | 12 | 7.5 | 85 Ohms | TOP=L2:L3=L2/L4:L6=L5/L7:BOTTOM=L7 |
| PCIE_RX_P50 | RXS50-DIFF1 | PAIR | 4 | 5.5 | 5 | 10 | 5 | 50 | 6 | 20 | 12 | 12 | 12 | 12 | 7.5 | 85 Ohms | TOP=L2:L3=L2/L4:L6=L5/L7:BOTTOM=L7 |
| PCIE_RX_P50 | RXS50-DIFF1 | PAIR | 5 | 5.5 | 5 | 10 | 5 | 50 | 6 | 20 | 12 | 12 | 12 | 12 | 7.5 | 85 Ohms | TOP=L2:L3=L2/L4:L6=L5/L7:BOTTOM=L7 |
| PCIE_RX_P50 | RXS50-DIFF1 | PAIR | 6 | 5.5 | 5 | 10 | 5 | 50 | 6 | 20 | 12 | 12 | 12 | 12 | 7.5 | 85 Ohms | TOP=L2:L3=L2/L4:L6=L5/L7:BOTTOM=L7 |
| PCIE_RX_P50 | RXS50-DIFF1 | PAIR | 7 | 5.5 | 5 | 10 | 5 | 50 | 6 | 20 | 12 | 12 | 12 | 12 | 7.5 | 85 Ohms | TOP=L2:L3=L2/L4:L6=L5/L7:BOTTOM=L7 |
| PCIE_RX_P50 | RXS50-DIFF1 | PAIR | 8 | 5.38 | 5 | 10 | 5 | 50 | 6 | 33 | 12 | 12 | 12 | 12 | 6.62 | 85 Ohms | TOP=L2:L3=L2/L4:L6=L5/L7:BOTTOM=L7 |
| PCIE_RX_N51 | RXS51-DIFF1 | PAIR | 1 | 5.38 | 5 | 10 | 5 | 50 | 6 | 33 | 12 | 12 | 12 | 12 | 6.62 | 85 Ohms | TOP=L2:L3=L2/L4:L6=L5/L7:BOTTOM=L7 |
| PCIE_RX_N51 | RXS51-DIFF1 | PAIR | 2 | 5.5 | 5 | 10 | 5 | 50 | 6 | 20 | 12 | 12 | 12 | 12 | 7.5 | 85 Ohms | TOP=L2:L3=L2/L4:L6=L5/L7:BOTTOM=L7 |
| PCIE_RX_N51 | RXS51-DIFF1 | PAIR | 3 | 5.5 | 5 | 10 | 5 | 50 | 6 | 20 | 12 | 12 | 12 | 12 | 7.5 | 85 Ohms | TOP=L2:L3=L2/L4:L6=L5/L7:BOTTOM=L7 |
| PCIE_RX_N51 | RXS51-DIFF1 | PAIR | 4 | 5.5 | 5 | 10 | 5 | 50 | 6 | 20 | 12 | 12 | 12 | 12 | 7.5 | 85 Ohms | TOP=L2:L3=L2/L4:L6=L5/L7:BOTTOM=L7 |
| PCIE_RX_N51 | RXS51-DIFF1 | PAIR | 5 | 5.5 | 5 | 10 | 5 | 50 | 6 | 20 | 12 | 12 | 12 | 12 | 7.5 | 85 Ohms | TOP=L2:L3=L2/L4:L6=L5/L7:BOTTOM=L7 |
| PCIE_RX_N51 | RXS51-DIFF1 | PAIR | 6 | 5.5 | 5 | 10 | 5 | 50 | 6 | 20 | 12 | 12 | 12 | 12 | 7.5 | 85 Ohms | TOP=L2:L3=L2/L4:L6=L5/L7:BOTTOM=L7 |
| PCIE_RX_N51 | RXS51-DIFF1 | PAIR | 7 | 5.5 | 5 | 10 | 5 | 50 | 6 | 20 | 12 | 12 | 12 | 12 | 7.5 | 85 Ohms | TOP=L2:L3=L2/L4:L6=L5/L7:BOTTOM=L7 |
| PCIE_RX_N51 | RXS51-DIFF1 | PAIR | 8 | 5.38 | 5 | 10 | 5 | 50 | 6 | 33 | 12 | 12 | 12 | 12 | 6.62 | 85 Ohms | TOP=L2:L3=L2/L4:L6=L5/L7:BOTTOM=L7 |
| PCIE_RX_P51 | RXS51-DIFF1 | PAIR | 1 | 5.38 | 5 | 10 | 5 | 50 | 6 | 33 | 12 | 12 | 12 | 12 | 6.62 | 85 Ohms | TOP=L2:L3=L2/L4:L6=L5/L7:BOTTOM=L7 |
| PCIE_RX_P51 | RXS51-DIFF1 | PAIR | 2 | 5.5 | 5 | 10 | 5 | 50 | 6 | 20 | 12 | 12 | 12 | 12 | 7.5 | 85 Ohms | TOP=L2:L3=L2/L4:L6=L5/L7:BOTTOM=L7 |
| PCIE_RX_P51 | RXS51-DIFF1 | PAIR | 3 | 5.5 | 5 | 10 | 5 | 50 | 6 | 20 | 12 | 12 | 12 | 12 | 7.5 | 85 Ohms | TOP=L2:L3=L2/L4:L6=L5/L7:BOTTOM=L7 |
| PCIE_RX_P51 | RXS51-DIFF1 | PAIR | 4 | 5.5 | 5 | 10 | 5 | 50 | 6 | 20 | 12 | 12 | 12 | 12 | 7.5 | 85 Ohms | TOP=L2:L3=L2/L4:L6=L5/L7:BOTTOM=L7 |
| PCIE_RX_P51 | RXS51-DIFF1 | PAIR | 5 | 5.5 | 5 | 10 | 5 | 50 | 6 | 20 | 12 | 12 | 12 | 12 | 7.5 | 85 Ohms | TOP=L2:L3=L2/L4:L6=L5/L7:BOTTOM=L7 |
| PCIE_RX_P51 | RXS51-DIFF1 | PAIR | 6 | 5.5 | 5 | 10 | 5 | 50 | 6 | 20 | 12 | 12 | 12 | 12 | 7.5 | 85 Ohms | TOP=L2:L3=L2/L4:L6=L5/L7:BOTTOM=L7 |
| PCIE_RX_P51 | RXS51-DIFF1 | PAIR | 7 | 5.5 | 5 | 10 | 5 | 50 | 6 | 20 | 12 | 12 | 12 | 12 | 7.5 | 85 Ohms | TOP=L2:L3=L2/L4:L6=L5/L7:BOTTOM=L7 |
| PCIE_RX_P51 | RXS51-DIFF1 | PAIR | 8 | 5.38 | 5 | 10 | 5 | 50 | 6 | 33 | 12 | 12 | 12 | 12 | 6.62 | 85 Ohms | TOP=L2:L3=L2/L4:L6=L5/L7:BOTTOM=L7 |
| PCIE_RX_N52 | RXS52-DIFF1 | PAIR | 1 | 5.38 | 5 | 10 | 5 | 50 | 6 | 33 | 12 | 12 | 12 | 12 | 6.62 | 85 Ohms | TOP=L2:L3=L2/L4:L6=L5/L7:BOTTOM=L7 |
| PCIE_RX_N52 | RXS52-DIFF1 | PAIR | 2 | 5.5 | 5 | 10 | 5 | 50 | 6 | 20 | 12 | 12 | 12 | 12 | 7.5 | 85 Ohms | TOP=L2:L3=L2/L4:L6=L5/L7:BOTTOM=L7 |
| PCIE_RX_N52 | RXS52-DIFF1 | PAIR | 3 | 5.5 | 5 | 10 | 5 | 50 | 6 | 20 | 12 | 12 | 12 | 12 | 7.5 | 85 Ohms | TOP=L2:L3=L2/L4:L6=L5/L7:BOTTOM=L7 |
| PCIE_RX_N52 | RXS52-DIFF1 | PAIR | 4 | 5.5 | 5 | 10 | 5 | 50 | 6 | 20 | 12 | 12 | 12 | 12 | 7.5 | 85 Ohms | TOP=L2:L3=L2/L4:L6=L5/L7:BOTTOM=L7 |
| PCIE_RX_N52 | RXS52-DIFF1 | PAIR | 5 | 5.5 | 5 | 10 | 5 | 50 | 6 | 20 | 12 | 12 | 12 | 12 | 7.5 | 85 Ohms | TOP=L2:L3=L2/L4:L6=L5/L7:BOTTOM=L7 |
| PCIE_RX_N52 | RXS52-DIFF1 | PAIR | 6 | 5.5 | 5 | 10 | 5 | 50 | 6 | 20 | 12 | 12 | 12 | 12 | 7.5 | 85 Ohms | TOP=L2:L3=L2/L4:L6=L5/L7:BOTTOM=L7 |
| PCIE_RX_N52 | RXS52-DIFF1 | PAIR | 7 | 5.5 | 5 | 10 | 5 | 50 | 6 | 20 | 12 | 12 | 12 | 12 | 7.5 | 85 Ohms | TOP=L2:L3=L2/L4:L6=L5/L7:BOTTOM=L7 |
| PCIE_RX_N52 | RXS52-DIFF1 | PAIR | 8 | 5.38 | 5 | 10 | 5 | 50 | 6 | 33 | 12 | 12 | 12 | 12 | 6.62 | 85 Ohms | TOP=L2:L3=L2/L4:L6=L5/L7:BOTTOM=L7 |
| PCIE_RX_P52 | RXS52-DIFF1 | PAIR | 1 | 5.38 | 5 | 10 | 5 | 50 | 6 | 33 | 12 | 12 | 12 | 12 | 6.62 | 85 Ohms | TOP=L2:L3=L2/L4:L6=L5/L7:BOTTOM=L7 |
| PCIE_RX_P52 | RXS52-DIFF1 | PAIR | 2 | 5.5 | 5 | 10 | 5 | 50 | 6 | 20 | 12 | 12 | 12 | 12 | 7.5 | 85 Ohms | TOP=L2:L3=L2/L4:L6=L5/L7:BOTTOM=L7 |
| PCIE_RX_P52 | RXS52-DIFF1 | PAIR | 3 | 5.5 | 5 | 10 | 5 | 50 | 6 | 20 | 12 | 12 | 12 | 12 | 7.5 | 85 Ohms | TOP=L2:L3=L2/L4:L6=L5/L7:BOTTOM=L7 |
| PCIE_RX_P52 | RXS52-DIFF1 | PAIR | 4 | 5.5 | 5 | 10 | 5 | 50 | 6 | 20 | 12 | 12 | 12 | 12 | 7.5 | 85 Ohms | TOP=L2:L3=L2/L4:L6=L5/L7:BOTTOM=L7 |
| PCIE_RX_P52 | RXS52-DIFF1 | PAIR | 5 | 5.5 | 5 | 10 | 5 | 50 | 6 | 20 | 12 | 12 | 12 | 12 | 7.5 | 85 Ohms | TOP=L2:L3=L2/L4:L6=L5/L7:BOTTOM=L7 |
| PCIE_RX_P52 | RXS52-DIFF1 | PAIR | 6 | 5.5 | 5 | 10 | 5 | 50 | 6 | 20 | 12 | 12 | 12 | 12 | 7.5 | 85 Ohms | TOP=L2:L3=L2/L4:L6=L5/L7:BOTTOM=L7 |
| PCIE_RX_P52 | RXS52-DIFF1 | PAIR | 7 | 5.5 | 5 | 10 | 5 | 50 | 6 | 20 | 12 | 12 | 12 | 12 | 7.5 | 85 Ohms | TOP=L2:L3=L2/L4:L6=L5/L7:BOTTOM=L7 |
| PCIE_RX_P52 | RXS52-DIFF1 | PAIR | 8 | 5.38 | 5 | 10 | 5 | 50 | 6 | 33 | 12 | 12 | 12 | 12 | 6.62 | 85 Ohms | TOP=L2:L3=L2/L4:L6=L5/L7:BOTTOM=L7 |
| PCIE_RX_N53 | RXS53-DIFF1 | PAIR | 1 | 5.38 | 5 | 10 | 5 | 50 | 6 | 33 | 12 | 12 | 12 | 12 | 6.62 | 85 Ohms | TOP=L2:L3=L2/L4:L6=L5/L7:BOTTOM=L7 |
| PCIE_RX_N53 | RXS53-DIFF1 | PAIR | 2 | 5.5 | 5 | 10 | 5 | 50 | 6 | 20 | 12 | 12 | 12 | 12 | 7.5 | 85 Ohms | TOP=L2:L3=L2/L4:L6=L5/L7:BOTTOM=L7 |
| PCIE_RX_N53 | RXS53-DIFF1 | PAIR | 3 | 5.5 | 5 | 10 | 5 | 50 | 6 | 20 | 12 | 12 | 12 | 12 | 7.5 | 85 Ohms | TOP=L2:L3=L2/L4:L6=L5/L7:BOTTOM=L7 |
| PCIE_RX_N53 | RXS53-DIFF1 | PAIR | 4 | 5.5 | 5 | 10 | 5 | 50 | 6 | 20 | 12 | 12 | 12 | 12 | 7.5 | 85 Ohms | TOP=L2:L3=L2/L4:L6=L5/L7:BOTTOM=L7 |
| PCIE_RX_N53 | RXS53-DIFF1 | PAIR | 5 | 5.5 | 5 | 10 | 5 | 50 | 6 | 20 | 12 | 12 | 12 | 12 | 7.5 | 85 Ohms | TOP=L2:L3=L2/L4:L6=L5/L7:BOTTOM=L7 |
| PCIE_RX_N53 | RXS53-DIFF1 | PAIR | 6 | 5.5 | 5 | 10 | 5 | 50 | 6 | 20 | 12 | 12 | 12 | 12 | 7.5 | 85 Ohms | TOP=L2:L3=L2/L4:L6=L5/L7:BOTTOM=L7 |
| PCIE_RX_N53 | RXS53-DIFF1 | PAIR | 7 | 5.5 | 5 | 10 | 5 | 50 | 6 | 20 | 12 | 12 | 12 | 12 | 7.5 | 85 Ohms | TOP=L2:L3=L2/L4:L6=L5/L7:BOTTOM=L7 |
| PCIE_RX_N53 | RXS53-DIFF1 | PAIR | 8 | 5.38 | 5 | 10 | 5 | 50 | 6 | 33 | 12 | 12 | 12 | 12 | 6.62 | 85 Ohms | TOP=L2:L3=L2/L4:L6=L5/L7:BOTTOM=L7 |
| PCIE_RX_P53 | RXS53-DIFF1 | PAIR | 1 | 5.38 | 5 | 10 | 5 | 50 | 6 | 33 | 12 | 12 | 12 | 12 | 6.62 | 85 Ohms | TOP=L2:L3=L2/L4:L6=L5/L7:BOTTOM=L7 |
| PCIE_RX_P53 | RXS53-DIFF1 | PAIR | 2 | 5.5 | 5 | 10 | 5 | 50 | 6 | 20 | 12 | 12 | 12 | 12 | 7.5 | 85 Ohms | TOP=L2:L3=L2/L4:L6=L5/L7:BOTTOM=L7 |
| PCIE_RX_P53 | RXS53-DIFF1 | PAIR | 3 | 5.5 | 5 | 10 | 5 | 50 | 6 | 20 | 12 | 12 | 12 | 12 | 7.5 | 85 Ohms | TOP=L2:L3=L2/L4:L6=L5/L7:BOTTOM=L7 |
| PCIE_RX_P53 | RXS53-DIFF1 | PAIR | 4 | 5.5 | 5 | 10 | 5 | 50 | 6 | 20 | 12 | 12 | 12 | 12 | 7.5 | 85 Ohms | TOP=L2:L3=L2/L4:L6=L5/L7:BOTTOM=L7 |
| PCIE_RX_P53 | RXS53-DIFF1 | PAIR | 5 | 5.5 | 5 | 10 | 5 | 50 | 6 | 20 | 12 | 12 | 12 | 12 | 7.5 | 85 Ohms | TOP=L2:L3=L2/L4:L6=L5/L7:BOTTOM=L7 |
| PCIE_RX_P53 | RXS53-DIFF1 | PAIR | 6 | 5.5 | 5 | 10 | 5 | 50 | 6 | 20 | 12 | 12 | 12 | 12 | 7.5 | 85 Ohms | TOP=L2:L3=L2/L4:L6=L5/L7:BOTTOM=L7 |
| PCIE_RX_P53 | RXS53-DIFF1 | PAIR | 7 | 5.5 | 5 | 10 | 5 | 50 | 6 | 20 | 12 | 12 | 12 | 12 | 7.5 | 85 Ohms | TOP=L2:L3=L2/L4:L6=L5/L7:BOTTOM=L7 |
| PCIE_RX_P53 | RXS53-DIFF1 | PAIR | 8 | 5.38 | 5 | 10 | 5 | 50 | 6 | 33 | 12 | 12 | 12 | 12 | 6.62 | 85 Ohms | TOP=L2:L3=L2/L4:L6=L5/L7:BOTTOM=L7 |
| PCIE_RX_N54 | RXS54-DIFF1 | PAIR | 1 | 5.38 | 5 | 10 | 5 | 50 | 6 | 33 | 12 | 12 | 12 | 12 | 6.62 | 85 Ohms | TOP=L2:L3=L2/L4:L6=L5/L7:BOTTOM=L7 |
| PCIE_RX_N54 | RXS54-DIFF1 | PAIR | 2 | 5.5 | 5 | 10 | 5 | 50 | 6 | 20 | 12 | 12 | 12 | 12 | 7.5 | 85 Ohms | TOP=L2:L3=L2/L4:L6=L5/L7:BOTTOM=L7 |
| PCIE_RX_N54 | RXS54-DIFF1 | PAIR | 3 | 5.5 | 5 | 10 | 5 | 50 | 6 | 20 | 12 | 12 | 12 | 12 | 7.5 | 85 Ohms | TOP=L2:L3=L2/L4:L6=L5/L7:BOTTOM=L7 |
| PCIE_RX_N54 | RXS54-DIFF1 | PAIR | 4 | 5.5 | 5 | 10 | 5 | 50 | 6 | 20 | 12 | 12 | 12 | 12 | 7.5 | 85 Ohms | TOP=L2:L3=L2/L4:L6=L5/L7:BOTTOM=L7 |
| PCIE_RX_N54 | RXS54-DIFF1 | PAIR | 5 | 5.5 | 5 | 10 | 5 | 50 | 6 | 20 | 12 | 12 | 12 | 12 | 7.5 | 85 Ohms | TOP=L2:L3=L2/L4:L6=L5/L7:BOTTOM=L7 |
| PCIE_RX_N54 | RXS54-DIFF1 | PAIR | 6 | 5.5 | 5 | 10 | 5 | 50 | 6 | 20 | 12 | 12 | 12 | 12 | 7.5 | 85 Ohms | TOP=L2:L3=L2/L4:L6=L5/L7:BOTTOM=L7 |
| PCIE_RX_N54 | RXS54-DIFF1 | PAIR | 7 | 5.5 | 5 | 10 | 5 | 50 | 6 | 20 | 12 | 12 | 12 | 12 | 7.5 | 85 Ohms | TOP=L2:L3=L2/L4:L6=L5/L7:BOTTOM=L7 |
| PCIE_RX_N54 | RXS54-DIFF1 | PAIR | 8 | 5.38 | 5 | 10 | 5 | 50 | 6 | 33 | 12 | 12 | 12 | 12 | 6.62 | 85 Ohms | TOP=L2:L3=L2/L4:L6=L5/L7:BOTTOM=L7 |
| PCIE_RX_P54 | RXS54-DIFF1 | PAIR | 1 | 5.38 | 5 | 10 | 5 | 50 | 6 | 33 | 12 | 12 | 12 | 12 | 6.62 | 85 Ohms | TOP=L2:L3=L2/L4:L6=L5/L7:BOTTOM=L7 |
| PCIE_RX_P54 | RXS54-DIFF1 | PAIR | 2 | 5.5 | 5 | 10 | 5 | 50 | 6 | 20 | 12 | 12 | 12 | 12 | 7.5 | 85 Ohms | TOP=L2:L3=L2/L4:L6=L5/L7:BOTTOM=L7 |
| PCIE_RX_P54 | RXS54-DIFF1 | PAIR | 3 | 5.5 | 5 | 10 | 5 | 50 | 6 | 20 | 12 | 12 | 12 | 12 | 7.5 | 85 Ohms | TOP=L2:L3=L2/L4:L6=L5/L7:BOTTOM=L7 |
| PCIE_RX_P54 | RXS54-DIFF1 | PAIR | 4 | 5.5 | 5 | 10 | 5 | 50 | 6 | 20 | 12 | 12 | 12 | 12 | 7.5 | 85 Ohms | TOP=L2:L3=L2/L4:L6=L5/L7:BOTTOM=L7 |
| PCIE_RX_P54 | RXS54-DIFF1 | PAIR | 5 | 5.5 | 5 | 10 | 5 | 50 | 6 | 20 | 12 | 12 | 12 | 12 | 7.5 | 85 Ohms | TOP=L2:L3=L2/L4:L6=L5/L7:BOTTOM=L7 |
| PCIE_RX_P54 | RXS54-DIFF1 | PAIR | 6 | 5.5 | 5 | 10 | 5 | 50 | 6 | 20 | 12 | 12 | 12 | 12 | 7.5 | 85 Ohms | TOP=L2:L3=L2/L4:L6=L5/L7:BOTTOM=L7 |
| PCIE_RX_P54 | RXS54-DIFF1 | PAIR | 7 | 5.5 | 5 | 10 | 5 | 50 | 6 | 20 | 12 | 12 | 12 | 12 | 7.5 | 85 Ohms | TOP=L2:L3=L2/L4:L6=L5/L7:BOTTOM=L7 |
| PCIE_RX_P54 | RXS54-DIFF1 | PAIR | 8 | 5.38 | 5 | 10 | 5 | 50 | 6 | 33 | 12 | 12 | 12 | 12 | 6.62 | 85 Ohms | TOP=L2:L3=L2/L4:L6=L5/L7:BOTTOM=L7 |
| PCIE_RX_N55 | RXS55-DIFF1 | PAIR | 1 | 5.38 | 5 | 10 | 5 | 50 | 6 | 33 | 12 | 12 | 12 | 12 | 6.62 | 85 Ohms | TOP=L2:L3=L2/L4:L6=L5/L7:BOTTOM=L7 |
| PCIE_RX_N55 | RXS55-DIFF1 | PAIR | 2 | 5.5 | 5 | 10 | 5 | 50 | 6 | 20 | 12 | 12 | 12 | 12 | 7.5 | 85 Ohms | TOP=L2:L3=L2/L4:L6=L5/L7:BOTTOM=L7 |
| PCIE_RX_N55 | RXS55-DIFF1 | PAIR | 3 | 5.5 | 5 | 10 | 5 | 50 | 6 | 20 | 12 | 12 | 12 | 12 | 7.5 | 85 Ohms | TOP=L2:L3=L2/L4:L6=L5/L7:BOTTOM=L7 |
| PCIE_RX_N55 | RXS55-DIFF1 | PAIR | 4 | 5.5 | 5 | 10 | 5 | 50 | 6 | 20 | 12 | 12 | 12 | 12 | 7.5 | 85 Ohms | TOP=L2:L3=L2/L4:L6=L5/L7:BOTTOM=L7 |
| PCIE_RX_N55 | RXS55-DIFF1 | PAIR | 5 | 5.5 | 5 | 10 | 5 | 50 | 6 | 20 | 12 | 12 | 12 | 12 | 7.5 | 85 Ohms | TOP=L2:L3=L2/L4:L6=L5/L7:BOTTOM=L7 |
| PCIE_RX_N55 | RXS55-DIFF1 | PAIR | 6 | 5.5 | 5 | 10 | 5 | 50 | 6 | 20 | 12 | 12 | 12 | 12 | 7.5 | 85 Ohms | TOP=L2:L3=L2/L4:L6=L5/L7:BOTTOM=L7 |
| PCIE_RX_N55 | RXS55-DIFF1 | PAIR | 7 | 5.5 | 5 | 10 | 5 | 50 | 6 | 20 | 12 | 12 | 12 | 12 | 7.5 | 85 Ohms | TOP=L2:L3=L2/L4:L6=L5/L7:BOTTOM=L7 |
| PCIE_RX_N55 | RXS55-DIFF1 | PAIR | 8 | 5.38 | 5 | 10 | 5 | 50 | 6 | 33 | 12 | 12 | 12 | 12 | 6.62 | 85 Ohms | TOP=L2:L3=L2/L4:L6=L5/L7:BOTTOM=L7 |
| PCIE_RX_P55 | RXS55-DIFF1 | PAIR | 1 | 5.38 | 5 | 10 | 5 | 50 | 6 | 33 | 12 | 12 | 12 | 12 | 6.62 | 85 Ohms | TOP=L2:L3=L2/L4:L6=L5/L7:BOTTOM=L7 |
| PCIE_RX_P55 | RXS55-DIFF1 | PAIR | 2 | 5.5 | 5 | 10 | 5 | 50 | 6 | 20 | 12 | 12 | 12 | 12 | 7.5 | 85 Ohms | TOP=L2:L3=L2/L4:L6=L5/L7:BOTTOM=L7 |
| PCIE_RX_P55 | RXS55-DIFF1 | PAIR | 3 | 5.5 | 5 | 10 | 5 | 50 | 6 | 20 | 12 | 12 | 12 | 12 | 7.5 | 85 Ohms | TOP=L2:L3=L2/L4:L6=L5/L7:BOTTOM=L7 |
| PCIE_RX_P55 | RXS55-DIFF1 | PAIR | 4 | 5.5 | 5 | 10 | 5 | 50 | 6 | 20 | 12 | 12 | 12 | 12 | 7.5 | 85 Ohms | TOP=L2:L3=L2/L4:L6=L5/L7:BOTTOM=L7 |
| PCIE_RX_P55 | RXS55-DIFF1 | PAIR | 5 | 5.5 | 5 | 10 | 5 | 50 | 6 | 20 | 12 | 12 | 12 | 12 | 7.5 | 85 Ohms | TOP=L2:L3=L2/L4:L6=L5/L7:BOTTOM=L7 |
| PCIE_RX_P55 | RXS55-DIFF1 | PAIR | 6 | 5.5 | 5 | 10 | 5 | 50 | 6 | 20 | 12 | 12 | 12 | 12 | 7.5 | 85 Ohms | TOP=L2:L3=L2/L4:L6=L5/L7:BOTTOM=L7 |
| PCIE_RX_P55 | RXS55-DIFF1 | PAIR | 7 | 5.5 | 5 | 10 | 5 | 50 | 6 | 20 | 12 | 12 | 12 | 12 | 7.5 | 85 Ohms | TOP=L2:L3=L2/L4:L6=L5/L7:BOTTOM=L7 |
| PCIE_RX_P55 | RXS55-DIFF1 | PAIR | 8 | 5.38 | 5 | 10 | 5 | 50 | 6 | 33 | 12 | 12 | 12 | 12 | 6.62 | 85 Ohms | TOP=L2:L3=L2/L4:L6=L5/L7:BOTTOM=L7 |
| PCIE_RX_N56 | RXS56-DIFF1 | PAIR | 1 | 5.38 | 5 | 10 | 5 | 50 | 6 | 33 | 12 | 12 | 12 | 12 | 6.62 | 85 Ohms | TOP=L2:L3=L2/L4:L6=L5/L7:BOTTOM=L7 |
| PCIE_RX_N56 | RXS56-DIFF1 | PAIR | 2 | 5.5 | 5 | 10 | 5 | 50 | 6 | 20 | 12 | 12 | 12 | 12 | 7.5 | 85 Ohms | TOP=L2:L3=L2/L4:L6=L5/L7:BOTTOM=L7 |
| PCIE_RX_N56 | RXS56-DIFF1 | PAIR | 3 | 5.5 | 5 | 10 | 5 | 50 | 6 | 20 | 12 | 12 | 12 | 12 | 7.5 | 85 Ohms | TOP=L2:L3=L2/L4:L6=L5/L7:BOTTOM=L7 |
| PCIE_RX_N56 | RXS56-DIFF1 | PAIR | 4 | 5.5 | 5 | 10 | 5 | 50 | 6 | 20 | 12 | 12 | 12 | 12 | 7.5 | 85 Ohms | TOP=L2:L3=L2/L4:L6=L5/L7:BOTTOM=L7 |
| PCIE_RX_N56 | RXS56-DIFF1 | PAIR | 5 | 5.5 | 5 | 10 | 5 | 50 | 6 | 20 | 12 | 12 | 12 | 12 | 7.5 | 85 Ohms | TOP=L2:L3=L2/L4:L6=L5/L7:BOTTOM=L7 |
| PCIE_RX_N56 | RXS56-DIFF1 | PAIR | 6 | 5.5 | 5 | 10 | 5 | 50 | 6 | 20 | 12 | 12 | 12 | 12 | 7.5 | 85 Ohms | TOP=L2:L3=L2/L4:L6=L5/L7:BOTTOM=L7 |
| PCIE_RX_N56 | RXS56-DIFF1 | PAIR | 7 | 5.5 | 5 | 10 | 5 | 50 | 6 | 20 | 12 | 12 | 12 | 12 | 7.5 | 85 Ohms | TOP=L2:L3=L2/L4:L6=L5/L7:BOTTOM=L7 |
| PCIE_RX_N56 | RXS56-DIFF1 | PAIR | 8 | 5.38 | 5 | 10 | 5 | 50 | 6 | 33 | 12 | 12 | 12 | 12 | 6.62 | 85 Ohms | TOP=L2:L3=L2/L4:L6=L5/L7:BOTTOM=L7 |
| PCIE_RX_P56 | RXS56-DIFF1 | PAIR | 1 | 5.38 | 5 | 10 | 5 | 50 | 6 | 33 | 12 | 12 | 12 | 12 | 6.62 | 85 Ohms | TOP=L2:L3=L2/L4:L6=L5/L7:BOTTOM=L7 |
| PCIE_RX_P56 | RXS56-DIFF1 | PAIR | 2 | 5.5 | 5 | 10 | 5 | 50 | 6 | 20 | 12 | 12 | 12 | 12 | 7.5 | 85 Ohms | TOP=L2:L3=L2/L4:L6=L5/L7:BOTTOM=L7 |
| PCIE_RX_P56 | RXS56-DIFF1 | PAIR | 3 | 5.5 | 5 | 10 | 5 | 50 | 6 | 20 | 12 | 12 | 12 | 12 | 7.5 | 85 Ohms | TOP=L2:L3=L2/L4:L6=L5/L7:BOTTOM=L7 |
| PCIE_RX_P56 | RXS56-DIFF1 | PAIR | 4 | 5.5 | 5 | 10 | 5 | 50 | 6 | 20 | 12 | 12 | 12 | 12 | 7.5 | 85 Ohms | TOP=L2:L3=L2/L4:L6=L5/L7:BOTTOM=L7 |
| PCIE_RX_P56 | RXS56-DIFF1 | PAIR | 5 | 5.5 | 5 | 10 | 5 | 50 | 6 | 20 | 12 | 12 | 12 | 12 | 7.5 | 85 Ohms | TOP=L2:L3=L2/L4:L6=L5/L7:BOTTOM=L7 |
| PCIE_RX_P56 | RXS56-DIFF1 | PAIR | 6 | 5.5 | 5 | 10 | 5 | 50 | 6 | 20 | 12 | 12 | 12 | 12 | 7.5 | 85 Ohms | TOP=L2:L3=L2/L4:L6=L5/L7:BOTTOM=L7 |
| PCIE_RX_P56 | RXS56-DIFF1 | PAIR | 7 | 5.5 | 5 | 10 | 5 | 50 | 6 | 20 | 12 | 12 | 12 | 12 | 7.5 | 85 Ohms | TOP=L2:L3=L2/L4:L6=L5/L7:BOTTOM=L7 |
| PCIE_RX_P56 | RXS56-DIFF1 | PAIR | 8 | 5.38 | 5 | 10 | 5 | 50 | 6 | 33 | 12 | 12 | 12 | 12 | 6.62 | 85 Ohms | TOP=L2:L3=L2/L4:L6=L5/L7:BOTTOM=L7 |
| PCIE_RX_N57 | RXS57-DIFF1 | PAIR | 1 | 5.38 | 5 | 10 | 5 | 50 | 6 | 33 | 12 | 12 | 12 | 12 | 6.62 | 85 Ohms | TOP=L2:L3=L2/L4:L6=L5/L7:BOTTOM=L7 |
| PCIE_RX_N57 | RXS57-DIFF1 | PAIR | 2 | 5.5 | 5 | 10 | 5 | 50 | 6 | 20 | 12 | 12 | 12 | 12 | 7.5 | 85 Ohms | TOP=L2:L3=L2/L4:L6=L5/L7:BOTTOM=L7 |
| PCIE_RX_N57 | RXS57-DIFF1 | PAIR | 3 | 5.5 | 5 | 10 | 5 | 50 | 6 | 20 | 12 | 12 | 12 | 12 | 7.5 | 85 Ohms | TOP=L2:L3=L2/L4:L6=L5/L7:BOTTOM=L7 |
| PCIE_RX_N57 | RXS57-DIFF1 | PAIR | 4 | 5.5 | 5 | 10 | 5 | 50 | 6 | 20 | 12 | 12 | 12 | 12 | 7.5 | 85 Ohms | TOP=L2:L3=L2/L4:L6=L5/L7:BOTTOM=L7 |
| PCIE_RX_N57 | RXS57-DIFF1 | PAIR | 5 | 5.5 | 5 | 10 | 5 | 50 | 6 | 20 | 12 | 12 | 12 | 12 | 7.5 | 85 Ohms | TOP=L2:L3=L2/L4:L6=L5/L7:BOTTOM=L7 |
| PCIE_RX_N57 | RXS57-DIFF1 | PAIR | 6 | 5.5 | 5 | 10 | 5 | 50 | 6 | 20 | 12 | 12 | 12 | 12 | 7.5 | 85 Ohms | TOP=L2:L3=L2/L4:L6=L5/L7:BOTTOM=L7 |
| PCIE_RX_N57 | RXS57-DIFF1 | PAIR | 7 | 5.5 | 5 | 10 | 5 | 50 | 6 | 20 | 12 | 12 | 12 | 12 | 7.5 | 85 Ohms | TOP=L2:L3=L2/L4:L6=L5/L7:BOTTOM=L7 |
| PCIE_RX_N57 | RXS57-DIFF1 | PAIR | 8 | 5.38 | 5 | 10 | 5 | 50 | 6 | 33 | 12 | 12 | 12 | 12 | 6.62 | 85 Ohms | TOP=L2:L3=L2/L4:L6=L5/L7:BOTTOM=L7 |
| PCIE_RX_P57 | RXS57-DIFF1 | PAIR | 1 | 5.38 | 5 | 10 | 5 | 50 | 6 | 33 | 12 | 12 | 12 | 12 | 6.62 | 85 Ohms | TOP=L2:L3=L2/L4:L6=L5/L7:BOTTOM=L7 |
| PCIE_RX_P57 | RXS57-DIFF1 | PAIR | 2 | 5.5 | 5 | 10 | 5 | 50 | 6 | 20 | 12 | 12 | 12 | 12 | 7.5 | 85 Ohms | TOP=L2:L3=L2/L4:L6=L5/L7:BOTTOM=L7 |
| PCIE_RX_P57 | RXS57-DIFF1 | PAIR | 3 | 5.5 | 5 | 10 | 5 | 50 | 6 | 20 | 12 | 12 | 12 | 12 | 7.5 | 85 Ohms | TOP=L2:L3=L2/L4:L6=L5/L7:BOTTOM=L7 |
| PCIE_RX_P57 | RXS57-DIFF1 | PAIR | 4 | 5.5 | 5 | 10 | 5 | 50 | 6 | 20 | 12 | 12 | 12 | 12 | 7.5 | 85 Ohms | TOP=L2:L3=L2/L4:L6=L5/L7:BOTTOM=L7 |
| PCIE_RX_P57 | RXS57-DIFF1 | PAIR | 5 | 5.5 | 5 | 10 | 5 | 50 | 6 | 20 | 12 | 12 | 12 | 12 | 7.5 | 85 Ohms | TOP=L2:L3=L2/L4:L6=L5/L7:BOTTOM=L7 |
| PCIE_RX_P57 | RXS57-DIFF1 | PAIR | 6 | 5.5 | 5 | 10 | 5 | 50 | 6 | 20 | 12 | 12 | 12 | 12 | 7.5 | 85 Ohms | TOP=L2:L3=L2/L4:L6=L5/L7:BOTTOM=L7 |
| PCIE_RX_P57 | RXS57-DIFF1 | PAIR | 7 | 5.5 | 5 | 10 | 5 | 50 | 6 | 20 | 12 | 12 | 12 | 12 | 7.5 | 85 Ohms | TOP=L2:L3=L2/L4:L6=L5/L7:BOTTOM=L7 |
| PCIE_RX_P57 | RXS57-DIFF1 | PAIR | 8 | 5.38 | 5 | 10 | 5 | 50 | 6 | 33 | 12 | 12 | 12 | 12 | 6.62 | 85 Ohms | TOP=L2:L3=L2/L4:L6=L5/L7:BOTTOM=L7 |
| PCIE_RX_N58 | RXS58-DIFF1 | PAIR | 1 | 5.38 | 5 | 10 | 5 | 50 | 6 | 33 | 12 | 12 | 12 | 12 | 6.62 | 85 Ohms | TOP=L2:L3=L2/L4:L6=L5/L7:BOTTOM=L7 |
| PCIE_RX_N58 | RXS58-DIFF1 | PAIR | 2 | 5.5 | 5 | 10 | 5 | 50 | 6 | 20 | 12 | 12 | 12 | 12 | 7.5 | 85 Ohms | TOP=L2:L3=L2/L4:L6=L5/L7:BOTTOM=L7 |
| PCIE_RX_N58 | RXS58-DIFF1 | PAIR | 3 | 5.5 | 5 | 10 | 5 | 50 | 6 | 20 | 12 | 12 | 12 | 12 | 7.5 | 85 Ohms | TOP=L2:L3=L2/L4:L6=L5/L7:BOTTOM=L7 |
| PCIE_RX_N58 | RXS58-DIFF1 | PAIR | 4 | 5.5 | 5 | 10 | 5 | 50 | 6 | 20 | 12 | 12 | 12 | 12 | 7.5 | 85 Ohms | TOP=L2:L3=L2/L4:L6=L5/L7:BOTTOM=L7 |
| PCIE_RX_N58 | RXS58-DIFF1 | PAIR | 5 | 5.5 | 5 | 10 | 5 | 50 | 6 | 20 | 12 | 12 | 12 | 12 | 7.5 | 85 Ohms | TOP=L2:L3=L2/L4:L6=L5/L7:BOTTOM=L7 |
| PCIE_RX_N58 | RXS58-DIFF1 | PAIR | 6 | 5.5 | 5 | 10 | 5 | 50 | 6 | 20 | 12 | 12 | 12 | 12 | 7.5 | 85 Ohms | TOP=L2:L3=L2/L4:L6=L5/L7:BOTTOM=L7 |
| PCIE_RX_N58 | RXS58-DIFF1 | PAIR | 7 | 5.5 | 5 | 10 | 5 | 50 | 6 | 20 | 12 | 12 | 12 | 12 | 7.5 | 85 Ohms | TOP=L2:L3=L2/L4:L6=L5/L7:BOTTOM=L7 |
| PCIE_RX_N58 | RXS58-DIFF1 | PAIR | 8 | 5.38 | 5 | 10 | 5 | 50 | 6 | 33 | 12 | 12 | 12 | 12 | 6.62 | 85 Ohms | TOP=L2:L3=L2/L4:L6=L5/L7:BOTTOM=L7 |
| PCIE_RX_P58 | RXS58-DIFF1 | PAIR | 1 | 5.38 | 5 | 10 | 5 | 50 | 6 | 33 | 12 | 12 | 12 | 12 | 6.62 | 85 Ohms | TOP=L2:L3=L2/L4:L6=L5/L7:BOTTOM=L7 |
| PCIE_RX_P58 | RXS58-DIFF1 | PAIR | 2 | 5.5 | 5 | 10 | 5 | 50 | 6 | 20 | 12 | 12 | 12 | 12 | 7.5 | 85 Ohms | TOP=L2:L3=L2/L4:L6=L5/L7:BOTTOM=L7 |
| PCIE_RX_P58 | RXS58-DIFF1 | PAIR | 3 | 5.5 | 5 | 10 | 5 | 50 | 6 | 20 | 12 | 12 | 12 | 12 | 7.5 | 85 Ohms | TOP=L2:L3=L2/L4:L6=L5/L7:BOTTOM=L7 |
| PCIE_RX_P58 | RXS58-DIFF1 | PAIR | 4 | 5.5 | 5 | 10 | 5 | 50 | 6 | 20 | 12 | 12 | 12 | 12 | 7.5 | 85 Ohms | TOP=L2:L3=L2/L4:L6=L5/L7:BOTTOM=L7 |
| PCIE_RX_P58 | RXS58-DIFF1 | PAIR | 5 | 5.5 | 5 | 10 | 5 | 50 | 6 | 20 | 12 | 12 | 12 | 12 | 7.5 | 85 Ohms | TOP=L2:L3=L2/L4:L6=L5/L7:BOTTOM=L7 |
| PCIE_RX_P58 | RXS58-DIFF1 | PAIR | 6 | 5.5 | 5 | 10 | 5 | 50 | 6 | 20 | 12 | 12 | 12 | 12 | 7.5 | 85 Ohms | TOP=L2:L3=L2/L4:L6=L5/L7:BOTTOM=L7 |
| PCIE_RX_P58 | RXS58-DIFF1 | PAIR | 7 | 5.5 | 5 | 10 | 5 | 50 | 6 | 20 | 12 | 12 | 12 | 12 | 7.5 | 85 Ohms | TOP=L2:L3=L2/L4:L6=L5/L7:BOTTOM=L7 |
| PCIE_RX_P58 | RXS58-DIFF1 | PAIR | 8 | 5.38 | 5 | 10 | 5 | 50 | 6 | 33 | 12 | 12 | 12 | 12 | 6.62 | 85 Ohms | TOP=L2:L3=L2/L4:L6=L5/L7:BOTTOM=L7 |
| PCIE_RX_N59 | RXS59-DIFF1 | PAIR | 1 | 5.38 | 5 | 10 | 5 | 50 | 6 | 33 | 12 | 12 | 12 | 12 | 6.62 | 85 Ohms | TOP=L2:L3=L2/L4:L6=L5/L7:BOTTOM=L7 |
| PCIE_RX_N59 | RXS59-DIFF1 | PAIR | 2 | 5.5 | 5 | 10 | 5 | 50 | 6 | 20 | 12 | 12 | 12 | 12 | 7.5 | 85 Ohms | TOP=L2:L3=L2/L4:L6=L5/L7:BOTTOM=L7 |
| PCIE_RX_N59 | RXS59-DIFF1 | PAIR | 3 | 5.5 | 5 | 10 | 5 | 50 | 6 | 20 | 12 | 12 | 12 | 12 | 7.5 | 85 Ohms | TOP=L2:L3=L2/L4:L6=L5/L7:BOTTOM=L7 |
| PCIE_RX_N59 | RXS59-DIFF1 | PAIR | 4 | 5.5 | 5 | 10 | 5 | 50 | 6 | 20 | 12 | 12 | 12 | 12 | 7.5 | 85 Ohms | TOP=L2:L3=L2/L4:L6=L5/L7:BOTTOM=L7 |
| PCIE_RX_N59 | RXS59-DIFF1 | PAIR | 5 | 5.5 | 5 | 10 | 5 | 50 | 6 | 20 | 12 | 12 | 12 | 12 | 7.5 | 85 Ohms | TOP=L2:L3=L2/L4:L6=L5/L7:BOTTOM=L7 |
| PCIE_RX_N59 | RXS59-DIFF1 | PAIR | 6 | 5.5 | 5 | 10 | 5 | 50 | 6 | 20 | 12 | 12 | 12 | 12 | 7.5 | 85 Ohms | TOP=L2:L3=L2/L4:L6=L5/L7:BOTTOM=L7 |
| PCIE_RX_N59 | RXS59-DIFF1 | PAIR | 7 | 5.5 | 5 | 10 | 5 | 50 | 6 | 20 | 12 | 12 | 12 | 12 | 7.5 | 85 Ohms | TOP=L2:L3=L2/L4:L6=L5/L7:BOTTOM=L7 |
| PCIE_RX_N59 | RXS59-DIFF1 | PAIR | 8 | 5.38 | 5 | 10 | 5 | 50 | 6 | 33 | 12 | 12 | 12 | 12 | 6.62 | 85 Ohms | TOP=L2:L3=L2/L4:L6=L5/L7:BOTTOM=L7 |
| PCIE_RX_P59 | RXS59-DIFF1 | PAIR | 1 | 5.38 | 5 | 10 | 5 | 50 | 6 | 33 | 12 | 12 | 12 | 12 | 6.62 | 85 Ohms | TOP=L2:L3=L2/L4:L6=L5/L7:BOTTOM=L7 |
| PCIE_RX_P59 | RXS59-DIFF1 | PAIR | 2 | 5.5 | 5 | 10 | 5 | 50 | 6 | 20 | 12 | 12 | 12 | 12 | 7.5 | 85 Ohms | TOP=L2:L3=L2/L4:L6=L5/L7:BOTTOM=L7 |
| PCIE_RX_P59 | RXS59-DIFF1 | PAIR | 3 | 5.5 | 5 | 10 | 5 | 50 | 6 | 20 | 12 | 12 | 12 | 12 | 7.5 | 85 Ohms | TOP=L2:L3=L2/L4:L6=L5/L7:BOTTOM=L7 |
| PCIE_RX_P59 | RXS59-DIFF1 | PAIR | 4 | 5.5 | 5 | 10 | 5 | 50 | 6 | 20 | 12 | 12 | 12 | 12 | 7.5 | 85 Ohms | TOP=L2:L3=L2/L4:L6=L5/L7:BOTTOM=L7 |
| PCIE_RX_P59 | RXS59-DIFF1 | PAIR | 5 | 5.5 | 5 | 10 | 5 | 50 | 6 | 20 | 12 | 12 | 12 | 12 | 7.5 | 85 Ohms | TOP=L2:L3=L2/L4:L6=L5/L7:BOTTOM=L7 |
| PCIE_RX_P59 | RXS59-DIFF1 | PAIR | 6 | 5.5 | 5 | 10 | 5 | 50 | 6 | 20 | 12 | 12 | 12 | 12 | 7.5 | 85 Ohms | TOP=L2:L3=L2/L4:L6=L5/L7:BOTTOM=L7 |
| PCIE_RX_P59 | RXS59-DIFF1 | PAIR | 7 | 5.5 | 5 | 10 | 5 | 50 | 6 | 20 | 12 | 12 | 12 | 12 | 7.5 | 85 Ohms | TOP=L2:L3=L2/L4:L6=L5/L7:BOTTOM=L7 |
| PCIE_RX_P59 | RXS59-DIFF1 | PAIR | 8 | 5.38 | 5 | 10 | 5 | 50 | 6 | 33 | 12 | 12 | 12 | 12 | 6.62 | 85 Ohms | TOP=L2:L3=L2/L4:L6=L5/L7:BOTTOM=L7 |
| PCIE_RX_N5 | RXS5-DIFF1 | PAIR | 1 | 5.38 | 5 | 10 | 5 | 50 | 6 | 33 | 12 | 12 | 12 | 12 | 6.62 | 85 Ohms | TOP=L2:L3=L2/L4:L6=L5/L7:BOTTOM=L7 |
| PCIE_RX_N5 | RXS5-DIFF1 | PAIR | 2 | 5.5 | 5 | 10 | 5 | 50 | 6 | 20 | 12 | 12 | 12 | 12 | 7.5 | 85 Ohms | TOP=L2:L3=L2/L4:L6=L5/L7:BOTTOM=L7 |
| PCIE_RX_N5 | RXS5-DIFF1 | PAIR | 3 | 5.5 | 5 | 10 | 5 | 50 | 6 | 20 | 12 | 12 | 12 | 12 | 7.5 | 85 Ohms | TOP=L2:L3=L2/L4:L6=L5/L7:BOTTOM=L7 |
| PCIE_RX_N5 | RXS5-DIFF1 | PAIR | 4 | 5.5 | 5 | 10 | 5 | 50 | 6 | 20 | 12 | 12 | 12 | 12 | 7.5 | 85 Ohms | TOP=L2:L3=L2/L4:L6=L5/L7:BOTTOM=L7 |
| PCIE_RX_N5 | RXS5-DIFF1 | PAIR | 5 | 5.5 | 5 | 10 | 5 | 50 | 6 | 20 | 12 | 12 | 12 | 12 | 7.5 | 85 Ohms | TOP=L2:L3=L2/L4:L6=L5/L7:BOTTOM=L7 |
| PCIE_RX_N5 | RXS5-DIFF1 | PAIR | 6 | 5.5 | 5 | 10 | 5 | 50 | 6 | 20 | 12 | 12 | 12 | 12 | 7.5 | 85 Ohms | TOP=L2:L3=L2/L4:L6=L5/L7:BOTTOM=L7 |
| PCIE_RX_N5 | RXS5-DIFF1 | PAIR | 7 | 5.5 | 5 | 10 | 5 | 50 | 6 | 20 | 12 | 12 | 12 | 12 | 7.5 | 85 Ohms | TOP=L2:L3=L2/L4:L6=L5/L7:BOTTOM=L7 |
| PCIE_RX_N5 | RXS5-DIFF1 | PAIR | 8 | 5.38 | 5 | 10 | 5 | 50 | 6 | 33 | 12 | 12 | 12 | 12 | 6.62 | 85 Ohms | TOP=L2:L3=L2/L4:L6=L5/L7:BOTTOM=L7 |
| PCIE_RX_P5 | RXS5-DIFF1 | PAIR | 1 | 5.38 | 5 | 10 | 5 | 50 | 6 | 33 | 12 | 12 | 12 | 12 | 6.62 | 85 Ohms | TOP=L2:L3=L2/L4:L6=L5/L7:BOTTOM=L7 |
| PCIE_RX_P5 | RXS5-DIFF1 | PAIR | 2 | 5.5 | 5 | 10 | 5 | 50 | 6 | 20 | 12 | 12 | 12 | 12 | 7.5 | 85 Ohms | TOP=L2:L3=L2/L4:L6=L5/L7:BOTTOM=L7 |
| PCIE_RX_P5 | RXS5-DIFF1 | PAIR | 3 | 5.5 | 5 | 10 | 5 | 50 | 6 | 20 | 12 | 12 | 12 | 12 | 7.5 | 85 Ohms | TOP=L2:L3=L2/L4:L6=L5/L7:BOTTOM=L7 |
| PCIE_RX_P5 | RXS5-DIFF1 | PAIR | 4 | 5.5 | 5 | 10 | 5 | 50 | 6 | 20 | 12 | 12 | 12 | 12 | 7.5 | 85 Ohms | TOP=L2:L3=L2/L4:L6=L5/L7:BOTTOM=L7 |
| PCIE_RX_P5 | RXS5-DIFF1 | PAIR | 5 | 5.5 | 5 | 10 | 5 | 50 | 6 | 20 | 12 | 12 | 12 | 12 | 7.5 | 85 Ohms | TOP=L2:L3=L2/L4:L6=L5/L7:BOTTOM=L7 |
| PCIE_RX_P5 | RXS5-DIFF1 | PAIR | 6 | 5.5 | 5 | 10 | 5 | 50 | 6 | 20 | 12 | 12 | 12 | 12 | 7.5 | 85 Ohms | TOP=L2:L3=L2/L4:L6=L5/L7:BOTTOM=L7 |
| PCIE_RX_P5 | RXS5-DIFF1 | PAIR | 7 | 5.5 | 5 | 10 | 5 | 50 | 6 | 20 | 12 | 12 | 12 | 12 | 7.5 | 85 Ohms | TOP=L2:L3=L2/L4:L6=L5/L7:BOTTOM=L7 |
| PCIE_RX_P5 | RXS5-DIFF1 | PAIR | 8 | 5.38 | 5 | 10 | 5 | 50 | 6 | 33 | 12 | 12 | 12 | 12 | 6.62 | 85 Ohms | TOP=L2:L3=L2/L4:L6=L5/L7:BOTTOM=L7 |
| PCIE_RX_N60 | RXS60-DIFF1 | PAIR | 1 | 5.38 | 5 | 10 | 5 | 50 | 6 | 33 | 12 | 12 | 12 | 12 | 6.62 | 85 Ohms | TOP=L2:L3=L2/L4:L6=L5/L7:BOTTOM=L7 |
| PCIE_RX_N60 | RXS60-DIFF1 | PAIR | 2 | 5.5 | 5 | 10 | 5 | 50 | 6 | 20 | 12 | 12 | 12 | 12 | 7.5 | 85 Ohms | TOP=L2:L3=L2/L4:L6=L5/L7:BOTTOM=L7 |
| PCIE_RX_N60 | RXS60-DIFF1 | PAIR | 3 | 5.5 | 5 | 10 | 5 | 50 | 6 | 20 | 12 | 12 | 12 | 12 | 7.5 | 85 Ohms | TOP=L2:L3=L2/L4:L6=L5/L7:BOTTOM=L7 |
| PCIE_RX_N60 | RXS60-DIFF1 | PAIR | 4 | 5.5 | 5 | 10 | 5 | 50 | 6 | 20 | 12 | 12 | 12 | 12 | 7.5 | 85 Ohms | TOP=L2:L3=L2/L4:L6=L5/L7:BOTTOM=L7 |
| PCIE_RX_N60 | RXS60-DIFF1 | PAIR | 5 | 5.5 | 5 | 10 | 5 | 50 | 6 | 20 | 12 | 12 | 12 | 12 | 7.5 | 85 Ohms | TOP=L2:L3=L2/L4:L6=L5/L7:BOTTOM=L7 |
| PCIE_RX_N60 | RXS60-DIFF1 | PAIR | 6 | 5.5 | 5 | 10 | 5 | 50 | 6 | 20 | 12 | 12 | 12 | 12 | 7.5 | 85 Ohms | TOP=L2:L3=L2/L4:L6=L5/L7:BOTTOM=L7 |
| PCIE_RX_N60 | RXS60-DIFF1 | PAIR | 7 | 5.5 | 5 | 10 | 5 | 50 | 6 | 20 | 12 | 12 | 12 | 12 | 7.5 | 85 Ohms | TOP=L2:L3=L2/L4:L6=L5/L7:BOTTOM=L7 |
| PCIE_RX_N60 | RXS60-DIFF1 | PAIR | 8 | 5.38 | 5 | 10 | 5 | 50 | 6 | 33 | 12 | 12 | 12 | 12 | 6.62 | 85 Ohms | TOP=L2:L3=L2/L4:L6=L5/L7:BOTTOM=L7 |
| PCIE_RX_P60 | RXS60-DIFF1 | PAIR | 1 | 5.38 | 5 | 10 | 5 | 50 | 6 | 33 | 12 | 12 | 12 | 12 | 6.62 | 85 Ohms | TOP=L2:L3=L2/L4:L6=L5/L7:BOTTOM=L7 |
| PCIE_RX_P60 | RXS60-DIFF1 | PAIR | 2 | 5.5 | 5 | 10 | 5 | 50 | 6 | 20 | 12 | 12 | 12 | 12 | 7.5 | 85 Ohms | TOP=L2:L3=L2/L4:L6=L5/L7:BOTTOM=L7 |
| PCIE_RX_P60 | RXS60-DIFF1 | PAIR | 3 | 5.5 | 5 | 10 | 5 | 50 | 6 | 20 | 12 | 12 | 12 | 12 | 7.5 | 85 Ohms | TOP=L2:L3=L2/L4:L6=L5/L7:BOTTOM=L7 |
| PCIE_RX_P60 | RXS60-DIFF1 | PAIR | 4 | 5.5 | 5 | 10 | 5 | 50 | 6 | 20 | 12 | 12 | 12 | 12 | 7.5 | 85 Ohms | TOP=L2:L3=L2/L4:L6=L5/L7:BOTTOM=L7 |
| PCIE_RX_P60 | RXS60-DIFF1 | PAIR | 5 | 5.5 | 5 | 10 | 5 | 50 | 6 | 20 | 12 | 12 | 12 | 12 | 7.5 | 85 Ohms | TOP=L2:L3=L2/L4:L6=L5/L7:BOTTOM=L7 |
| PCIE_RX_P60 | RXS60-DIFF1 | PAIR | 6 | 5.5 | 5 | 10 | 5 | 50 | 6 | 20 | 12 | 12 | 12 | 12 | 7.5 | 85 Ohms | TOP=L2:L3=L2/L4:L6=L5/L7:BOTTOM=L7 |
| PCIE_RX_P60 | RXS60-DIFF1 | PAIR | 7 | 5.5 | 5 | 10 | 5 | 50 | 6 | 20 | 12 | 12 | 12 | 12 | 7.5 | 85 Ohms | TOP=L2:L3=L2/L4:L6=L5/L7:BOTTOM=L7 |
| PCIE_RX_P60 | RXS60-DIFF1 | PAIR | 8 | 5.38 | 5 | 10 | 5 | 50 | 6 | 33 | 12 | 12 | 12 | 12 | 6.62 | 85 Ohms | TOP=L2:L3=L2/L4:L6=L5/L7:BOTTOM=L7 |
| PCIE_RX_N61 | RXS61-DIFF1 | PAIR | 1 | 5.38 | 5 | 10 | 5 | 50 | 6 | 33 | 12 | 12 | 12 | 12 | 6.62 | 85 Ohms | TOP=L2:L3=L2/L4:L6=L5/L7:BOTTOM=L7 |
| PCIE_RX_N61 | RXS61-DIFF1 | PAIR | 2 | 5.5 | 5 | 10 | 5 | 50 | 6 | 20 | 12 | 12 | 12 | 12 | 7.5 | 85 Ohms | TOP=L2:L3=L2/L4:L6=L5/L7:BOTTOM=L7 |
| PCIE_RX_N61 | RXS61-DIFF1 | PAIR | 3 | 5.5 | 5 | 10 | 5 | 50 | 6 | 20 | 12 | 12 | 12 | 12 | 7.5 | 85 Ohms | TOP=L2:L3=L2/L4:L6=L5/L7:BOTTOM=L7 |
| PCIE_RX_N61 | RXS61-DIFF1 | PAIR | 4 | 5.5 | 5 | 10 | 5 | 50 | 6 | 20 | 12 | 12 | 12 | 12 | 7.5 | 85 Ohms | TOP=L2:L3=L2/L4:L6=L5/L7:BOTTOM=L7 |
| PCIE_RX_N61 | RXS61-DIFF1 | PAIR | 5 | 5.5 | 5 | 10 | 5 | 50 | 6 | 20 | 12 | 12 | 12 | 12 | 7.5 | 85 Ohms | TOP=L2:L3=L2/L4:L6=L5/L7:BOTTOM=L7 |
| PCIE_RX_N61 | RXS61-DIFF1 | PAIR | 6 | 5.5 | 5 | 10 | 5 | 50 | 6 | 20 | 12 | 12 | 12 | 12 | 7.5 | 85 Ohms | TOP=L2:L3=L2/L4:L6=L5/L7:BOTTOM=L7 |
| PCIE_RX_N61 | RXS61-DIFF1 | PAIR | 7 | 5.5 | 5 | 10 | 5 | 50 | 6 | 20 | 12 | 12 | 12 | 12 | 7.5 | 85 Ohms | TOP=L2:L3=L2/L4:L6=L5/L7:BOTTOM=L7 |
| PCIE_RX_N61 | RXS61-DIFF1 | PAIR | 8 | 5.38 | 5 | 10 | 5 | 50 | 6 | 33 | 12 | 12 | 12 | 12 | 6.62 | 85 Ohms | TOP=L2:L3=L2/L4:L6=L5/L7:BOTTOM=L7 |
| PCIE_RX_P61 | RXS61-DIFF1 | PAIR | 1 | 5.38 | 5 | 10 | 5 | 50 | 6 | 33 | 12 | 12 | 12 | 12 | 6.62 | 85 Ohms | TOP=L2:L3=L2/L4:L6=L5/L7:BOTTOM=L7 |
| PCIE_RX_P61 | RXS61-DIFF1 | PAIR | 2 | 5.5 | 5 | 10 | 5 | 50 | 6 | 20 | 12 | 12 | 12 | 12 | 7.5 | 85 Ohms | TOP=L2:L3=L2/L4:L6=L5/L7:BOTTOM=L7 |
| PCIE_RX_P61 | RXS61-DIFF1 | PAIR | 3 | 5.5 | 5 | 10 | 5 | 50 | 6 | 20 | 12 | 12 | 12 | 12 | 7.5 | 85 Ohms | TOP=L2:L3=L2/L4:L6=L5/L7:BOTTOM=L7 |
| PCIE_RX_P61 | RXS61-DIFF1 | PAIR | 4 | 5.5 | 5 | 10 | 5 | 50 | 6 | 20 | 12 | 12 | 12 | 12 | 7.5 | 85 Ohms | TOP=L2:L3=L2/L4:L6=L5/L7:BOTTOM=L7 |
| PCIE_RX_P61 | RXS61-DIFF1 | PAIR | 5 | 5.5 | 5 | 10 | 5 | 50 | 6 | 20 | 12 | 12 | 12 | 12 | 7.5 | 85 Ohms | TOP=L2:L3=L2/L4:L6=L5/L7:BOTTOM=L7 |
| PCIE_RX_P61 | RXS61-DIFF1 | PAIR | 6 | 5.5 | 5 | 10 | 5 | 50 | 6 | 20 | 12 | 12 | 12 | 12 | 7.5 | 85 Ohms | TOP=L2:L3=L2/L4:L6=L5/L7:BOTTOM=L7 |
| PCIE_RX_P61 | RXS61-DIFF1 | PAIR | 7 | 5.5 | 5 | 10 | 5 | 50 | 6 | 20 | 12 | 12 | 12 | 12 | 7.5 | 85 Ohms | TOP=L2:L3=L2/L4:L6=L5/L7:BOTTOM=L7 |
| PCIE_RX_P61 | RXS61-DIFF1 | PAIR | 8 | 5.38 | 5 | 10 | 5 | 50 | 6 | 33 | 12 | 12 | 12 | 12 | 6.62 | 85 Ohms | TOP=L2:L3=L2/L4:L6=L5/L7:BOTTOM=L7 |
| PCIE_RX_N62 | RXS62-DIFF1 | PAIR | 1 | 5.38 | 5 | 10 | 5 | 50 | 6 | 33 | 12 | 12 | 12 | 12 | 6.62 | 85 Ohms | TOP=L2:L3=L2/L4:L6=L5/L7:BOTTOM=L7 |
| PCIE_RX_N62 | RXS62-DIFF1 | PAIR | 2 | 5.5 | 5 | 10 | 5 | 50 | 6 | 20 | 12 | 12 | 12 | 12 | 7.5 | 85 Ohms | TOP=L2:L3=L2/L4:L6=L5/L7:BOTTOM=L7 |
| PCIE_RX_N62 | RXS62-DIFF1 | PAIR | 3 | 5.5 | 5 | 10 | 5 | 50 | 6 | 20 | 12 | 12 | 12 | 12 | 7.5 | 85 Ohms | TOP=L2:L3=L2/L4:L6=L5/L7:BOTTOM=L7 |
| PCIE_RX_N62 | RXS62-DIFF1 | PAIR | 4 | 5.5 | 5 | 10 | 5 | 50 | 6 | 20 | 12 | 12 | 12 | 12 | 7.5 | 85 Ohms | TOP=L2:L3=L2/L4:L6=L5/L7:BOTTOM=L7 |
| PCIE_RX_N62 | RXS62-DIFF1 | PAIR | 5 | 5.5 | 5 | 10 | 5 | 50 | 6 | 20 | 12 | 12 | 12 | 12 | 7.5 | 85 Ohms | TOP=L2:L3=L2/L4:L6=L5/L7:BOTTOM=L7 |
| PCIE_RX_N62 | RXS62-DIFF1 | PAIR | 6 | 5.5 | 5 | 10 | 5 | 50 | 6 | 20 | 12 | 12 | 12 | 12 | 7.5 | 85 Ohms | TOP=L2:L3=L2/L4:L6=L5/L7:BOTTOM=L7 |
| PCIE_RX_N62 | RXS62-DIFF1 | PAIR | 7 | 5.5 | 5 | 10 | 5 | 50 | 6 | 20 | 12 | 12 | 12 | 12 | 7.5 | 85 Ohms | TOP=L2:L3=L2/L4:L6=L5/L7:BOTTOM=L7 |
| PCIE_RX_N62 | RXS62-DIFF1 | PAIR | 8 | 5.38 | 5 | 10 | 5 | 50 | 6 | 33 | 12 | 12 | 12 | 12 | 6.62 | 85 Ohms | TOP=L2:L3=L2/L4:L6=L5/L7:BOTTOM=L7 |
| PCIE_RX_P62 | RXS62-DIFF1 | PAIR | 1 | 5.38 | 5 | 10 | 5 | 50 | 6 | 33 | 12 | 12 | 12 | 12 | 6.62 | 85 Ohms | TOP=L2:L3=L2/L4:L6=L5/L7:BOTTOM=L7 |
| PCIE_RX_P62 | RXS62-DIFF1 | PAIR | 2 | 5.5 | 5 | 10 | 5 | 50 | 6 | 20 | 12 | 12 | 12 | 12 | 7.5 | 85 Ohms | TOP=L2:L3=L2/L4:L6=L5/L7:BOTTOM=L7 |
| PCIE_RX_P62 | RXS62-DIFF1 | PAIR | 3 | 5.5 | 5 | 10 | 5 | 50 | 6 | 20 | 12 | 12 | 12 | 12 | 7.5 | 85 Ohms | TOP=L2:L3=L2/L4:L6=L5/L7:BOTTOM=L7 |
| PCIE_RX_P62 | RXS62-DIFF1 | PAIR | 4 | 5.5 | 5 | 10 | 5 | 50 | 6 | 20 | 12 | 12 | 12 | 12 | 7.5 | 85 Ohms | TOP=L2:L3=L2/L4:L6=L5/L7:BOTTOM=L7 |
| PCIE_RX_P62 | RXS62-DIFF1 | PAIR | 5 | 5.5 | 5 | 10 | 5 | 50 | 6 | 20 | 12 | 12 | 12 | 12 | 7.5 | 85 Ohms | TOP=L2:L3=L2/L4:L6=L5/L7:BOTTOM=L7 |
| PCIE_RX_P62 | RXS62-DIFF1 | PAIR | 6 | 5.5 | 5 | 10 | 5 | 50 | 6 | 20 | 12 | 12 | 12 | 12 | 7.5 | 85 Ohms | TOP=L2:L3=L2/L4:L6=L5/L7:BOTTOM=L7 |
| PCIE_RX_P62 | RXS62-DIFF1 | PAIR | 7 | 5.5 | 5 | 10 | 5 | 50 | 6 | 20 | 12 | 12 | 12 | 12 | 7.5 | 85 Ohms | TOP=L2:L3=L2/L4:L6=L5/L7:BOTTOM=L7 |
| PCIE_RX_P62 | RXS62-DIFF1 | PAIR | 8 | 5.38 | 5 | 10 | 5 | 50 | 6 | 33 | 12 | 12 | 12 | 12 | 6.62 | 85 Ohms | TOP=L2:L3=L2/L4:L6=L5/L7:BOTTOM=L7 |
| PCIE_RX_N63 | RXS63-DIFF1 | PAIR | 1 | 5.38 | 5 | 10 | 5 | 50 | 6 | 33 | 12 | 12 | 12 | 12 | 6.62 | 85 Ohms | TOP=L2:L3=L2/L4:L6=L5/L7:BOTTOM=L7 |
| PCIE_RX_N63 | RXS63-DIFF1 | PAIR | 2 | 5.5 | 5 | 10 | 5 | 50 | 6 | 20 | 12 | 12 | 12 | 12 | 7.5 | 85 Ohms | TOP=L2:L3=L2/L4:L6=L5/L7:BOTTOM=L7 |
| PCIE_RX_N63 | RXS63-DIFF1 | PAIR | 3 | 5.5 | 5 | 10 | 5 | 50 | 6 | 20 | 12 | 12 | 12 | 12 | 7.5 | 85 Ohms | TOP=L2:L3=L2/L4:L6=L5/L7:BOTTOM=L7 |
| PCIE_RX_N63 | RXS63-DIFF1 | PAIR | 4 | 5.5 | 5 | 10 | 5 | 50 | 6 | 20 | 12 | 12 | 12 | 12 | 7.5 | 85 Ohms | TOP=L2:L3=L2/L4:L6=L5/L7:BOTTOM=L7 |
| PCIE_RX_N63 | RXS63-DIFF1 | PAIR | 5 | 5.5 | 5 | 10 | 5 | 50 | 6 | 20 | 12 | 12 | 12 | 12 | 7.5 | 85 Ohms | TOP=L2:L3=L2/L4:L6=L5/L7:BOTTOM=L7 |
| PCIE_RX_N63 | RXS63-DIFF1 | PAIR | 6 | 5.5 | 5 | 10 | 5 | 50 | 6 | 20 | 12 | 12 | 12 | 12 | 7.5 | 85 Ohms | TOP=L2:L3=L2/L4:L6=L5/L7:BOTTOM=L7 |
| PCIE_RX_N63 | RXS63-DIFF1 | PAIR | 7 | 5.5 | 5 | 10 | 5 | 50 | 6 | 20 | 12 | 12 | 12 | 12 | 7.5 | 85 Ohms | TOP=L2:L3=L2/L4:L6=L5/L7:BOTTOM=L7 |
| PCIE_RX_N63 | RXS63-DIFF1 | PAIR | 8 | 5.38 | 5 | 10 | 5 | 50 | 6 | 33 | 12 | 12 | 12 | 12 | 6.62 | 85 Ohms | TOP=L2:L3=L2/L4:L6=L5/L7:BOTTOM=L7 |
| PCIE_RX_P63 | RXS63-DIFF1 | PAIR | 1 | 5.38 | 5 | 10 | 5 | 50 | 6 | 33 | 12 | 12 | 12 | 12 | 6.62 | 85 Ohms | TOP=L2:L3=L2/L4:L6=L5/L7:BOTTOM=L7 |
| PCIE_RX_P63 | RXS63-DIFF1 | PAIR | 2 | 5.5 | 5 | 10 | 5 | 50 | 6 | 20 | 12 | 12 | 12 | 12 | 7.5 | 85 Ohms | TOP=L2:L3=L2/L4:L6=L5/L7:BOTTOM=L7 |
| PCIE_RX_P63 | RXS63-DIFF1 | PAIR | 3 | 5.5 | 5 | 10 | 5 | 50 | 6 | 20 | 12 | 12 | 12 | 12 | 7.5 | 85 Ohms | TOP=L2:L3=L2/L4:L6=L5/L7:BOTTOM=L7 |
| PCIE_RX_P63 | RXS63-DIFF1 | PAIR | 4 | 5.5 | 5 | 10 | 5 | 50 | 6 | 20 | 12 | 12 | 12 | 12 | 7.5 | 85 Ohms | TOP=L2:L3=L2/L4:L6=L5/L7:BOTTOM=L7 |
| PCIE_RX_P63 | RXS63-DIFF1 | PAIR | 5 | 5.5 | 5 | 10 | 5 | 50 | 6 | 20 | 12 | 12 | 12 | 12 | 7.5 | 85 Ohms | TOP=L2:L3=L2/L4:L6=L5/L7:BOTTOM=L7 |
| PCIE_RX_P63 | RXS63-DIFF1 | PAIR | 6 | 5.5 | 5 | 10 | 5 | 50 | 6 | 20 | 12 | 12 | 12 | 12 | 7.5 | 85 Ohms | TOP=L2:L3=L2/L4:L6=L5/L7:BOTTOM=L7 |
| PCIE_RX_P63 | RXS63-DIFF1 | PAIR | 7 | 5.5 | 5 | 10 | 5 | 50 | 6 | 20 | 12 | 12 | 12 | 12 | 7.5 | 85 Ohms | TOP=L2:L3=L2/L4:L6=L5/L7:BOTTOM=L7 |
| PCIE_RX_P63 | RXS63-DIFF1 | PAIR | 8 | 5.38 | 5 | 10 | 5 | 50 | 6 | 33 | 12 | 12 | 12 | 12 | 6.62 | 85 Ohms | TOP=L2:L3=L2/L4:L6=L5/L7:BOTTOM=L7 |
| PCIE_RX_N64 | RXS64-DIFF1 | PAIR | 1 | 5.38 | 5 | 10 | 5 | 50 | 6 | 33 | 12 | 12 | 12 | 12 | 6.62 | 85 Ohms | TOP=L2:L3=L2/L4:L6=L5/L7:BOTTOM=L7 |
| PCIE_RX_N64 | RXS64-DIFF1 | PAIR | 2 | 5.5 | 5 | 10 | 5 | 50 | 6 | 20 | 12 | 12 | 12 | 12 | 7.5 | 85 Ohms | TOP=L2:L3=L2/L4:L6=L5/L7:BOTTOM=L7 |
| PCIE_RX_N64 | RXS64-DIFF1 | PAIR | 3 | 5.5 | 5 | 10 | 5 | 50 | 6 | 20 | 12 | 12 | 12 | 12 | 7.5 | 85 Ohms | TOP=L2:L3=L2/L4:L6=L5/L7:BOTTOM=L7 |
| PCIE_RX_N64 | RXS64-DIFF1 | PAIR | 4 | 5.5 | 5 | 10 | 5 | 50 | 6 | 20 | 12 | 12 | 12 | 12 | 7.5 | 85 Ohms | TOP=L2:L3=L2/L4:L6=L5/L7:BOTTOM=L7 |
| PCIE_RX_N64 | RXS64-DIFF1 | PAIR | 5 | 5.5 | 5 | 10 | 5 | 50 | 6 | 20 | 12 | 12 | 12 | 12 | 7.5 | 85 Ohms | TOP=L2:L3=L2/L4:L6=L5/L7:BOTTOM=L7 |
| PCIE_RX_N64 | RXS64-DIFF1 | PAIR | 6 | 5.5 | 5 | 10 | 5 | 50 | 6 | 20 | 12 | 12 | 12 | 12 | 7.5 | 85 Ohms | TOP=L2:L3=L2/L4:L6=L5/L7:BOTTOM=L7 |
| PCIE_RX_N64 | RXS64-DIFF1 | PAIR | 7 | 5.5 | 5 | 10 | 5 | 50 | 6 | 20 | 12 | 12 | 12 | 12 | 7.5 | 85 Ohms | TOP=L2:L3=L2/L4:L6=L5/L7:BOTTOM=L7 |
| PCIE_RX_N64 | RXS64-DIFF1 | PAIR | 8 | 5.38 | 5 | 10 | 5 | 50 | 6 | 33 | 12 | 12 | 12 | 12 | 6.62 | 85 Ohms | TOP=L2:L3=L2/L4:L6=L5/L7:BOTTOM=L7 |
| PCIE_RX_P64 | RXS64-DIFF1 | PAIR | 1 | 5.38 | 5 | 10 | 5 | 50 | 6 | 33 | 12 | 12 | 12 | 12 | 6.62 | 85 Ohms | TOP=L2:L3=L2/L4:L6=L5/L7:BOTTOM=L7 |
| PCIE_RX_P64 | RXS64-DIFF1 | PAIR | 2 | 5.5 | 5 | 10 | 5 | 50 | 6 | 20 | 12 | 12 | 12 | 12 | 7.5 | 85 Ohms | TOP=L2:L3=L2/L4:L6=L5/L7:BOTTOM=L7 |
| PCIE_RX_P64 | RXS64-DIFF1 | PAIR | 3 | 5.5 | 5 | 10 | 5 | 50 | 6 | 20 | 12 | 12 | 12 | 12 | 7.5 | 85 Ohms | TOP=L2:L3=L2/L4:L6=L5/L7:BOTTOM=L7 |
| PCIE_RX_P64 | RXS64-DIFF1 | PAIR | 4 | 5.5 | 5 | 10 | 5 | 50 | 6 | 20 | 12 | 12 | 12 | 12 | 7.5 | 85 Ohms | TOP=L2:L3=L2/L4:L6=L5/L7:BOTTOM=L7 |
| PCIE_RX_P64 | RXS64-DIFF1 | PAIR | 5 | 5.5 | 5 | 10 | 5 | 50 | 6 | 20 | 12 | 12 | 12 | 12 | 7.5 | 85 Ohms | TOP=L2:L3=L2/L4:L6=L5/L7:BOTTOM=L7 |
| PCIE_RX_P64 | RXS64-DIFF1 | PAIR | 6 | 5.5 | 5 | 10 | 5 | 50 | 6 | 20 | 12 | 12 | 12 | 12 | 7.5 | 85 Ohms | TOP=L2:L3=L2/L4:L6=L5/L7:BOTTOM=L7 |
| PCIE_RX_P64 | RXS64-DIFF1 | PAIR | 7 | 5.5 | 5 | 10 | 5 | 50 | 6 | 20 | 12 | 12 | 12 | 12 | 7.5 | 85 Ohms | TOP=L2:L3=L2/L4:L6=L5/L7:BOTTOM=L7 |
| PCIE_RX_P64 | RXS64-DIFF1 | PAIR | 8 | 5.38 | 5 | 10 | 5 | 50 | 6 | 33 | 12 | 12 | 12 | 12 | 6.62 | 85 Ohms | TOP=L2:L3=L2/L4:L6=L5/L7:BOTTOM=L7 |
| PCIE_RX_N65 | RXS65-DIFF1 | PAIR | 1 | 5.38 | 5 | 10 | 5 | 50 | 6 | 33 | 12 | 12 | 12 | 12 | 6.62 | 85 Ohms | TOP=L2:L3=L2/L4:L6=L5/L7:BOTTOM=L7 |
| PCIE_RX_N65 | RXS65-DIFF1 | PAIR | 2 | 5.5 | 5 | 10 | 5 | 50 | 6 | 20 | 12 | 12 | 12 | 12 | 7.5 | 85 Ohms | TOP=L2:L3=L2/L4:L6=L5/L7:BOTTOM=L7 |
| PCIE_RX_N65 | RXS65-DIFF1 | PAIR | 3 | 5.5 | 5 | 10 | 5 | 50 | 6 | 20 | 12 | 12 | 12 | 12 | 7.5 | 85 Ohms | TOP=L2:L3=L2/L4:L6=L5/L7:BOTTOM=L7 |
| PCIE_RX_N65 | RXS65-DIFF1 | PAIR | 4 | 5.5 | 5 | 10 | 5 | 50 | 6 | 20 | 12 | 12 | 12 | 12 | 7.5 | 85 Ohms | TOP=L2:L3=L2/L4:L6=L5/L7:BOTTOM=L7 |
| PCIE_RX_N65 | RXS65-DIFF1 | PAIR | 5 | 5.5 | 5 | 10 | 5 | 50 | 6 | 20 | 12 | 12 | 12 | 12 | 7.5 | 85 Ohms | TOP=L2:L3=L2/L4:L6=L5/L7:BOTTOM=L7 |
| PCIE_RX_N65 | RXS65-DIFF1 | PAIR | 6 | 5.5 | 5 | 10 | 5 | 50 | 6 | 20 | 12 | 12 | 12 | 12 | 7.5 | 85 Ohms | TOP=L2:L3=L2/L4:L6=L5/L7:BOTTOM=L7 |
| PCIE_RX_N65 | RXS65-DIFF1 | PAIR | 7 | 5.5 | 5 | 10 | 5 | 50 | 6 | 20 | 12 | 12 | 12 | 12 | 7.5 | 85 Ohms | TOP=L2:L3=L2/L4:L6=L5/L7:BOTTOM=L7 |
| PCIE_RX_N65 | RXS65-DIFF1 | PAIR | 8 | 5.38 | 5 | 10 | 5 | 50 | 6 | 33 | 12 | 12 | 12 | 12 | 6.62 | 85 Ohms | TOP=L2:L3=L2/L4:L6=L5/L7:BOTTOM=L7 |
| PCIE_RX_P65 | RXS65-DIFF1 | PAIR | 1 | 5.38 | 5 | 10 | 5 | 50 | 6 | 33 | 12 | 12 | 12 | 12 | 6.62 | 85 Ohms | TOP=L2:L3=L2/L4:L6=L5/L7:BOTTOM=L7 |
| PCIE_RX_P65 | RXS65-DIFF1 | PAIR | 2 | 5.5 | 5 | 10 | 5 | 50 | 6 | 20 | 12 | 12 | 12 | 12 | 7.5 | 85 Ohms | TOP=L2:L3=L2/L4:L6=L5/L7:BOTTOM=L7 |
| PCIE_RX_P65 | RXS65-DIFF1 | PAIR | 3 | 5.5 | 5 | 10 | 5 | 50 | 6 | 20 | 12 | 12 | 12 | 12 | 7.5 | 85 Ohms | TOP=L2:L3=L2/L4:L6=L5/L7:BOTTOM=L7 |
| PCIE_RX_P65 | RXS65-DIFF1 | PAIR | 4 | 5.5 | 5 | 10 | 5 | 50 | 6 | 20 | 12 | 12 | 12 | 12 | 7.5 | 85 Ohms | TOP=L2:L3=L2/L4:L6=L5/L7:BOTTOM=L7 |
| PCIE_RX_P65 | RXS65-DIFF1 | PAIR | 5 | 5.5 | 5 | 10 | 5 | 50 | 6 | 20 | 12 | 12 | 12 | 12 | 7.5 | 85 Ohms | TOP=L2:L3=L2/L4:L6=L5/L7:BOTTOM=L7 |
| PCIE_RX_P65 | RXS65-DIFF1 | PAIR | 6 | 5.5 | 5 | 10 | 5 | 50 | 6 | 20 | 12 | 12 | 12 | 12 | 7.5 | 85 Ohms | TOP=L2:L3=L2/L4:L6=L5/L7:BOTTOM=L7 |
| PCIE_RX_P65 | RXS65-DIFF1 | PAIR | 7 | 5.5 | 5 | 10 | 5 | 50 | 6 | 20 | 12 | 12 | 12 | 12 | 7.5 | 85 Ohms | TOP=L2:L3=L2/L4:L6=L5/L7:BOTTOM=L7 |
| PCIE_RX_P65 | RXS65-DIFF1 | PAIR | 8 | 5.38 | 5 | 10 | 5 | 50 | 6 | 33 | 12 | 12 | 12 | 12 | 6.62 | 85 Ohms | TOP=L2:L3=L2/L4:L6=L5/L7:BOTTOM=L7 |
| PCIE_RX_N66 | RXS66-DIFF1 | PAIR | 1 | 5.38 | 5 | 10 | 5 | 50 | 6 | 33 | 12 | 12 | 12 | 12 | 6.62 | 85 Ohms | TOP=L2:L3=L2/L4:L6=L5/L7:BOTTOM=L7 |
| PCIE_RX_N66 | RXS66-DIFF1 | PAIR | 2 | 5.5 | 5 | 10 | 5 | 50 | 6 | 20 | 12 | 12 | 12 | 12 | 7.5 | 85 Ohms | TOP=L2:L3=L2/L4:L6=L5/L7:BOTTOM=L7 |
| PCIE_RX_N66 | RXS66-DIFF1 | PAIR | 3 | 5.5 | 5 | 10 | 5 | 50 | 6 | 20 | 12 | 12 | 12 | 12 | 7.5 | 85 Ohms | TOP=L2:L3=L2/L4:L6=L5/L7:BOTTOM=L7 |
| PCIE_RX_N66 | RXS66-DIFF1 | PAIR | 4 | 5.5 | 5 | 10 | 5 | 50 | 6 | 20 | 12 | 12 | 12 | 12 | 7.5 | 85 Ohms | TOP=L2:L3=L2/L4:L6=L5/L7:BOTTOM=L7 |
| PCIE_RX_N66 | RXS66-DIFF1 | PAIR | 5 | 5.5 | 5 | 10 | 5 | 50 | 6 | 20 | 12 | 12 | 12 | 12 | 7.5 | 85 Ohms | TOP=L2:L3=L2/L4:L6=L5/L7:BOTTOM=L7 |
| PCIE_RX_N66 | RXS66-DIFF1 | PAIR | 6 | 5.5 | 5 | 10 | 5 | 50 | 6 | 20 | 12 | 12 | 12 | 12 | 7.5 | 85 Ohms | TOP=L2:L3=L2/L4:L6=L5/L7:BOTTOM=L7 |
| PCIE_RX_N66 | RXS66-DIFF1 | PAIR | 7 | 5.5 | 5 | 10 | 5 | 50 | 6 | 20 | 12 | 12 | 12 | 12 | 7.5 | 85 Ohms | TOP=L2:L3=L2/L4:L6=L5/L7:BOTTOM=L7 |
| PCIE_RX_N66 | RXS66-DIFF1 | PAIR | 8 | 5.38 | 5 | 10 | 5 | 50 | 6 | 33 | 12 | 12 | 12 | 12 | 6.62 | 85 Ohms | TOP=L2:L3=L2/L4:L6=L5/L7:BOTTOM=L7 |
| PCIE_RX_P66 | RXS66-DIFF1 | PAIR | 1 | 5.38 | 5 | 10 | 5 | 50 | 6 | 33 | 12 | 12 | 12 | 12 | 6.62 | 85 Ohms | TOP=L2:L3=L2/L4:L6=L5/L7:BOTTOM=L7 |
| PCIE_RX_P66 | RXS66-DIFF1 | PAIR | 2 | 5.5 | 5 | 10 | 5 | 50 | 6 | 20 | 12 | 12 | 12 | 12 | 7.5 | 85 Ohms | TOP=L2:L3=L2/L4:L6=L5/L7:BOTTOM=L7 |
| PCIE_RX_P66 | RXS66-DIFF1 | PAIR | 3 | 5.5 | 5 | 10 | 5 | 50 | 6 | 20 | 12 | 12 | 12 | 12 | 7.5 | 85 Ohms | TOP=L2:L3=L2/L4:L6=L5/L7:BOTTOM=L7 |
| PCIE_RX_P66 | RXS66-DIFF1 | PAIR | 4 | 5.5 | 5 | 10 | 5 | 50 | 6 | 20 | 12 | 12 | 12 | 12 | 7.5 | 85 Ohms | TOP=L2:L3=L2/L4:L6=L5/L7:BOTTOM=L7 |
| PCIE_RX_P66 | RXS66-DIFF1 | PAIR | 5 | 5.5 | 5 | 10 | 5 | 50 | 6 | 20 | 12 | 12 | 12 | 12 | 7.5 | 85 Ohms | TOP=L2:L3=L2/L4:L6=L5/L7:BOTTOM=L7 |
| PCIE_RX_P66 | RXS66-DIFF1 | PAIR | 6 | 5.5 | 5 | 10 | 5 | 50 | 6 | 20 | 12 | 12 | 12 | 12 | 7.5 | 85 Ohms | TOP=L2:L3=L2/L4:L6=L5/L7:BOTTOM=L7 |
| PCIE_RX_P66 | RXS66-DIFF1 | PAIR | 7 | 5.5 | 5 | 10 | 5 | 50 | 6 | 20 | 12 | 12 | 12 | 12 | 7.5 | 85 Ohms | TOP=L2:L3=L2/L4:L6=L5/L7:BOTTOM=L7 |
| PCIE_RX_P66 | RXS66-DIFF1 | PAIR | 8 | 5.38 | 5 | 10 | 5 | 50 | 6 | 33 | 12 | 12 | 12 | 12 | 6.62 | 85 Ohms | TOP=L2:L3=L2/L4:L6=L5/L7:BOTTOM=L7 |
| PCIE_RX_N67 | RXS67-DIFF1 | PAIR | 1 | 5.38 | 5 | 10 | 5 | 50 | 6 | 33 | 12 | 12 | 12 | 12 | 6.62 | 85 Ohms | TOP=L2:L3=L2/L4:L6=L5/L7:BOTTOM=L7 |
| PCIE_RX_N67 | RXS67-DIFF1 | PAIR | 2 | 5.5 | 5 | 10 | 5 | 50 | 6 | 20 | 12 | 12 | 12 | 12 | 7.5 | 85 Ohms | TOP=L2:L3=L2/L4:L6=L5/L7:BOTTOM=L7 |
| PCIE_RX_N67 | RXS67-DIFF1 | PAIR | 3 | 5.5 | 5 | 10 | 5 | 50 | 6 | 20 | 12 | 12 | 12 | 12 | 7.5 | 85 Ohms | TOP=L2:L3=L2/L4:L6=L5/L7:BOTTOM=L7 |
| PCIE_RX_N67 | RXS67-DIFF1 | PAIR | 4 | 5.5 | 5 | 10 | 5 | 50 | 6 | 20 | 12 | 12 | 12 | 12 | 7.5 | 85 Ohms | TOP=L2:L3=L2/L4:L6=L5/L7:BOTTOM=L7 |
| PCIE_RX_N67 | RXS67-DIFF1 | PAIR | 5 | 5.5 | 5 | 10 | 5 | 50 | 6 | 20 | 12 | 12 | 12 | 12 | 7.5 | 85 Ohms | TOP=L2:L3=L2/L4:L6=L5/L7:BOTTOM=L7 |
| PCIE_RX_N67 | RXS67-DIFF1 | PAIR | 6 | 5.5 | 5 | 10 | 5 | 50 | 6 | 20 | 12 | 12 | 12 | 12 | 7.5 | 85 Ohms | TOP=L2:L3=L2/L4:L6=L5/L7:BOTTOM=L7 |
| PCIE_RX_N67 | RXS67-DIFF1 | PAIR | 7 | 5.5 | 5 | 10 | 5 | 50 | 6 | 20 | 12 | 12 | 12 | 12 | 7.5 | 85 Ohms | TOP=L2:L3=L2/L4:L6=L5/L7:BOTTOM=L7 |
| PCIE_RX_N67 | RXS67-DIFF1 | PAIR | 8 | 5.38 | 5 | 10 | 5 | 50 | 6 | 33 | 12 | 12 | 12 | 12 | 6.62 | 85 Ohms | TOP=L2:L3=L2/L4:L6=L5/L7:BOTTOM=L7 |
| PCIE_RX_P67 | RXS67-DIFF1 | PAIR | 1 | 5.38 | 5 | 10 | 5 | 50 | 6 | 33 | 12 | 12 | 12 | 12 | 6.62 | 85 Ohms | TOP=L2:L3=L2/L4:L6=L5/L7:BOTTOM=L7 |
| PCIE_RX_P67 | RXS67-DIFF1 | PAIR | 2 | 5.5 | 5 | 10 | 5 | 50 | 6 | 20 | 12 | 12 | 12 | 12 | 7.5 | 85 Ohms | TOP=L2:L3=L2/L4:L6=L5/L7:BOTTOM=L7 |
| PCIE_RX_P67 | RXS67-DIFF1 | PAIR | 3 | 5.5 | 5 | 10 | 5 | 50 | 6 | 20 | 12 | 12 | 12 | 12 | 7.5 | 85 Ohms | TOP=L2:L3=L2/L4:L6=L5/L7:BOTTOM=L7 |
| PCIE_RX_P67 | RXS67-DIFF1 | PAIR | 4 | 5.5 | 5 | 10 | 5 | 50 | 6 | 20 | 12 | 12 | 12 | 12 | 7.5 | 85 Ohms | TOP=L2:L3=L2/L4:L6=L5/L7:BOTTOM=L7 |
| PCIE_RX_P67 | RXS67-DIFF1 | PAIR | 5 | 5.5 | 5 | 10 | 5 | 50 | 6 | 20 | 12 | 12 | 12 | 12 | 7.5 | 85 Ohms | TOP=L2:L3=L2/L4:L6=L5/L7:BOTTOM=L7 |
| PCIE_RX_P67 | RXS67-DIFF1 | PAIR | 6 | 5.5 | 5 | 10 | 5 | 50 | 6 | 20 | 12 | 12 | 12 | 12 | 7.5 | 85 Ohms | TOP=L2:L3=L2/L4:L6=L5/L7:BOTTOM=L7 |
| PCIE_RX_P67 | RXS67-DIFF1 | PAIR | 7 | 5.5 | 5 | 10 | 5 | 50 | 6 | 20 | 12 | 12 | 12 | 12 | 7.5 | 85 Ohms | TOP=L2:L3=L2/L4:L6=L5/L7:BOTTOM=L7 |
| PCIE_RX_P67 | RXS67-DIFF1 | PAIR | 8 | 5.38 | 5 | 10 | 5 | 50 | 6 | 33 | 12 | 12 | 12 | 12 | 6.62 | 85 Ohms | TOP=L2:L3=L2/L4:L6=L5/L7:BOTTOM=L7 |
| PCIE_RX_N68 | RXS68-DIFF1 | PAIR | 1 | 5.38 | 5 | 10 | 5 | 50 | 6 | 33 | 12 | 12 | 12 | 12 | 6.62 | 85 Ohms | TOP=L2:L3=L2/L4:L6=L5/L7:BOTTOM=L7 |
| PCIE_RX_N68 | RXS68-DIFF1 | PAIR | 2 | 5.5 | 5 | 10 | 5 | 50 | 6 | 20 | 12 | 12 | 12 | 12 | 7.5 | 85 Ohms | TOP=L2:L3=L2/L4:L6=L5/L7:BOTTOM=L7 |
| PCIE_RX_N68 | RXS68-DIFF1 | PAIR | 3 | 5.5 | 5 | 10 | 5 | 50 | 6 | 20 | 12 | 12 | 12 | 12 | 7.5 | 85 Ohms | TOP=L2:L3=L2/L4:L6=L5/L7:BOTTOM=L7 |
| PCIE_RX_N68 | RXS68-DIFF1 | PAIR | 4 | 5.5 | 5 | 10 | 5 | 50 | 6 | 20 | 12 | 12 | 12 | 12 | 7.5 | 85 Ohms | TOP=L2:L3=L2/L4:L6=L5/L7:BOTTOM=L7 |
| PCIE_RX_N68 | RXS68-DIFF1 | PAIR | 5 | 5.5 | 5 | 10 | 5 | 50 | 6 | 20 | 12 | 12 | 12 | 12 | 7.5 | 85 Ohms | TOP=L2:L3=L2/L4:L6=L5/L7:BOTTOM=L7 |
| PCIE_RX_N68 | RXS68-DIFF1 | PAIR | 6 | 5.5 | 5 | 10 | 5 | 50 | 6 | 20 | 12 | 12 | 12 | 12 | 7.5 | 85 Ohms | TOP=L2:L3=L2/L4:L6=L5/L7:BOTTOM=L7 |
| PCIE_RX_N68 | RXS68-DIFF1 | PAIR | 7 | 5.5 | 5 | 10 | 5 | 50 | 6 | 20 | 12 | 12 | 12 | 12 | 7.5 | 85 Ohms | TOP=L2:L3=L2/L4:L6=L5/L7:BOTTOM=L7 |
| PCIE_RX_N68 | RXS68-DIFF1 | PAIR | 8 | 5.38 | 5 | 10 | 5 | 50 | 6 | 33 | 12 | 12 | 12 | 12 | 6.62 | 85 Ohms | TOP=L2:L3=L2/L4:L6=L5/L7:BOTTOM=L7 |
| PCIE_RX_P68 | RXS68-DIFF1 | PAIR | 1 | 5.38 | 5 | 10 | 5 | 50 | 6 | 33 | 12 | 12 | 12 | 12 | 6.62 | 85 Ohms | TOP=L2:L3=L2/L4:L6=L5/L7:BOTTOM=L7 |
| PCIE_RX_P68 | RXS68-DIFF1 | PAIR | 2 | 5.5 | 5 | 10 | 5 | 50 | 6 | 20 | 12 | 12 | 12 | 12 | 7.5 | 85 Ohms | TOP=L2:L3=L2/L4:L6=L5/L7:BOTTOM=L7 |
| PCIE_RX_P68 | RXS68-DIFF1 | PAIR | 3 | 5.5 | 5 | 10 | 5 | 50 | 6 | 20 | 12 | 12 | 12 | 12 | 7.5 | 85 Ohms | TOP=L2:L3=L2/L4:L6=L5/L7:BOTTOM=L7 |
| PCIE_RX_P68 | RXS68-DIFF1 | PAIR | 4 | 5.5 | 5 | 10 | 5 | 50 | 6 | 20 | 12 | 12 | 12 | 12 | 7.5 | 85 Ohms | TOP=L2:L3=L2/L4:L6=L5/L7:BOTTOM=L7 |
| PCIE_RX_P68 | RXS68-DIFF1 | PAIR | 5 | 5.5 | 5 | 10 | 5 | 50 | 6 | 20 | 12 | 12 | 12 | 12 | 7.5 | 85 Ohms | TOP=L2:L3=L2/L4:L6=L5/L7:BOTTOM=L7 |
| PCIE_RX_P68 | RXS68-DIFF1 | PAIR | 6 | 5.5 | 5 | 10 | 5 | 50 | 6 | 20 | 12 | 12 | 12 | 12 | 7.5 | 85 Ohms | TOP=L2:L3=L2/L4:L6=L5/L7:BOTTOM=L7 |
| PCIE_RX_P68 | RXS68-DIFF1 | PAIR | 7 | 5.5 | 5 | 10 | 5 | 50 | 6 | 20 | 12 | 12 | 12 | 12 | 7.5 | 85 Ohms | TOP=L2:L3=L2/L4:L6=L5/L7:BOTTOM=L7 |
| PCIE_RX_P68 | RXS68-DIFF1 | PAIR | 8 | 5.38 | 5 | 10 | 5 | 50 | 6 | 33 | 12 | 12 | 12 | 12 | 6.62 | 85 Ohms | TOP=L2:L3=L2/L4:L6=L5/L7:BOTTOM=L7 |
| PCIE_RX_N69 | RXS69-DIFF1 | PAIR | 1 | 5.38 | 5 | 10 | 5 | 50 | 6 | 33 | 12 | 12 | 12 | 12 | 6.62 | 85 Ohms | TOP=L2:L3=L2/L4:L6=L5/L7:BOTTOM=L7 |
| PCIE_RX_N69 | RXS69-DIFF1 | PAIR | 2 | 5.5 | 5 | 10 | 5 | 50 | 6 | 20 | 12 | 12 | 12 | 12 | 7.5 | 85 Ohms | TOP=L2:L3=L2/L4:L6=L5/L7:BOTTOM=L7 |
| PCIE_RX_N69 | RXS69-DIFF1 | PAIR | 3 | 5.5 | 5 | 10 | 5 | 50 | 6 | 20 | 12 | 12 | 12 | 12 | 7.5 | 85 Ohms | TOP=L2:L3=L2/L4:L6=L5/L7:BOTTOM=L7 |
| PCIE_RX_N69 | RXS69-DIFF1 | PAIR | 4 | 5.5 | 5 | 10 | 5 | 50 | 6 | 20 | 12 | 12 | 12 | 12 | 7.5 | 85 Ohms | TOP=L2:L3=L2/L4:L6=L5/L7:BOTTOM=L7 |
| PCIE_RX_N69 | RXS69-DIFF1 | PAIR | 5 | 5.5 | 5 | 10 | 5 | 50 | 6 | 20 | 12 | 12 | 12 | 12 | 7.5 | 85 Ohms | TOP=L2:L3=L2/L4:L6=L5/L7:BOTTOM=L7 |
| PCIE_RX_N69 | RXS69-DIFF1 | PAIR | 6 | 5.5 | 5 | 10 | 5 | 50 | 6 | 20 | 12 | 12 | 12 | 12 | 7.5 | 85 Ohms | TOP=L2:L3=L2/L4:L6=L5/L7:BOTTOM=L7 |
| PCIE_RX_N69 | RXS69-DIFF1 | PAIR | 7 | 5.5 | 5 | 10 | 5 | 50 | 6 | 20 | 12 | 12 | 12 | 12 | 7.5 | 85 Ohms | TOP=L2:L3=L2/L4:L6=L5/L7:BOTTOM=L7 |
| PCIE_RX_N69 | RXS69-DIFF1 | PAIR | 8 | 5.38 | 5 | 10 | 5 | 50 | 6 | 33 | 12 | 12 | 12 | 12 | 6.62 | 85 Ohms | TOP=L2:L3=L2/L4:L6=L5/L7:BOTTOM=L7 |
| PCIE_RX_P69 | RXS69-DIFF1 | PAIR | 1 | 5.38 | 5 | 10 | 5 | 50 | 6 | 33 | 12 | 12 | 12 | 12 | 6.62 | 85 Ohms | TOP=L2:L3=L2/L4:L6=L5/L7:BOTTOM=L7 |
| PCIE_RX_P69 | RXS69-DIFF1 | PAIR | 2 | 5.5 | 5 | 10 | 5 | 50 | 6 | 20 | 12 | 12 | 12 | 12 | 7.5 | 85 Ohms | TOP=L2:L3=L2/L4:L6=L5/L7:BOTTOM=L7 |
| PCIE_RX_P69 | RXS69-DIFF1 | PAIR | 3 | 5.5 | 5 | 10 | 5 | 50 | 6 | 20 | 12 | 12 | 12 | 12 | 7.5 | 85 Ohms | TOP=L2:L3=L2/L4:L6=L5/L7:BOTTOM=L7 |
| PCIE_RX_P69 | RXS69-DIFF1 | PAIR | 4 | 5.5 | 5 | 10 | 5 | 50 | 6 | 20 | 12 | 12 | 12 | 12 | 7.5 | 85 Ohms | TOP=L2:L3=L2/L4:L6=L5/L7:BOTTOM=L7 |
| PCIE_RX_P69 | RXS69-DIFF1 | PAIR | 5 | 5.5 | 5 | 10 | 5 | 50 | 6 | 20 | 12 | 12 | 12 | 12 | 7.5 | 85 Ohms | TOP=L2:L3=L2/L4:L6=L5/L7:BOTTOM=L7 |
| PCIE_RX_P69 | RXS69-DIFF1 | PAIR | 6 | 5.5 | 5 | 10 | 5 | 50 | 6 | 20 | 12 | 12 | 12 | 12 | 7.5 | 85 Ohms | TOP=L2:L3=L2/L4:L6=L5/L7:BOTTOM=L7 |
| PCIE_RX_P69 | RXS69-DIFF1 | PAIR | 7 | 5.5 | 5 | 10 | 5 | 50 | 6 | 20 | 12 | 12 | 12 | 12 | 7.5 | 85 Ohms | TOP=L2:L3=L2/L4:L6=L5/L7:BOTTOM=L7 |
| PCIE_RX_P69 | RXS69-DIFF1 | PAIR | 8 | 5.38 | 5 | 10 | 5 | 50 | 6 | 33 | 12 | 12 | 12 | 12 | 6.62 | 85 Ohms | TOP=L2:L3=L2/L4:L6=L5/L7:BOTTOM=L7 |
| PCIE_RX_N6 | RXS6-DIFF1 | PAIR | 1 | 5.38 | 5 | 10 | 5 | 50 | 6 | 33 | 12 | 12 | 12 | 12 | 6.62 | 85 Ohms | TOP=L2:L3=L2/L4:L6=L5/L7:BOTTOM=L7 |
| PCIE_RX_N6 | RXS6-DIFF1 | PAIR | 2 | 5.5 | 5 | 10 | 5 | 50 | 6 | 20 | 12 | 12 | 12 | 12 | 7.5 | 85 Ohms | TOP=L2:L3=L2/L4:L6=L5/L7:BOTTOM=L7 |
| PCIE_RX_N6 | RXS6-DIFF1 | PAIR | 3 | 5.5 | 5 | 10 | 5 | 50 | 6 | 20 | 12 | 12 | 12 | 12 | 7.5 | 85 Ohms | TOP=L2:L3=L2/L4:L6=L5/L7:BOTTOM=L7 |
| PCIE_RX_N6 | RXS6-DIFF1 | PAIR | 4 | 5.5 | 5 | 10 | 5 | 50 | 6 | 20 | 12 | 12 | 12 | 12 | 7.5 | 85 Ohms | TOP=L2:L3=L2/L4:L6=L5/L7:BOTTOM=L7 |
| PCIE_RX_N6 | RXS6-DIFF1 | PAIR | 5 | 5.5 | 5 | 10 | 5 | 50 | 6 | 20 | 12 | 12 | 12 | 12 | 7.5 | 85 Ohms | TOP=L2:L3=L2/L4:L6=L5/L7:BOTTOM=L7 |
| PCIE_RX_N6 | RXS6-DIFF1 | PAIR | 6 | 5.5 | 5 | 10 | 5 | 50 | 6 | 20 | 12 | 12 | 12 | 12 | 7.5 | 85 Ohms | TOP=L2:L3=L2/L4:L6=L5/L7:BOTTOM=L7 |
| PCIE_RX_N6 | RXS6-DIFF1 | PAIR | 7 | 5.5 | 5 | 10 | 5 | 50 | 6 | 20 | 12 | 12 | 12 | 12 | 7.5 | 85 Ohms | TOP=L2:L3=L2/L4:L6=L5/L7:BOTTOM=L7 |
| PCIE_RX_N6 | RXS6-DIFF1 | PAIR | 8 | 5.38 | 5 | 10 | 5 | 50 | 6 | 33 | 12 | 12 | 12 | 12 | 6.62 | 85 Ohms | TOP=L2:L3=L2/L4:L6=L5/L7:BOTTOM=L7 |
| PCIE_RX_P6 | RXS6-DIFF1 | PAIR | 1 | 5.38 | 5 | 10 | 5 | 50 | 6 | 33 | 12 | 12 | 12 | 12 | 6.62 | 85 Ohms | TOP=L2:L3=L2/L4:L6=L5/L7:BOTTOM=L7 |
| PCIE_RX_P6 | RXS6-DIFF1 | PAIR | 2 | 5.5 | 5 | 10 | 5 | 50 | 6 | 20 | 12 | 12 | 12 | 12 | 7.5 | 85 Ohms | TOP=L2:L3=L2/L4:L6=L5/L7:BOTTOM=L7 |
| PCIE_RX_P6 | RXS6-DIFF1 | PAIR | 3 | 5.5 | 5 | 10 | 5 | 50 | 6 | 20 | 12 | 12 | 12 | 12 | 7.5 | 85 Ohms | TOP=L2:L3=L2/L4:L6=L5/L7:BOTTOM=L7 |
| PCIE_RX_P6 | RXS6-DIFF1 | PAIR | 4 | 5.5 | 5 | 10 | 5 | 50 | 6 | 20 | 12 | 12 | 12 | 12 | 7.5 | 85 Ohms | TOP=L2:L3=L2/L4:L6=L5/L7:BOTTOM=L7 |
| PCIE_RX_P6 | RXS6-DIFF1 | PAIR | 5 | 5.5 | 5 | 10 | 5 | 50 | 6 | 20 | 12 | 12 | 12 | 12 | 7.5 | 85 Ohms | TOP=L2:L3=L2/L4:L6=L5/L7:BOTTOM=L7 |
| PCIE_RX_P6 | RXS6-DIFF1 | PAIR | 6 | 5.5 | 5 | 10 | 5 | 50 | 6 | 20 | 12 | 12 | 12 | 12 | 7.5 | 85 Ohms | TOP=L2:L3=L2/L4:L6=L5/L7:BOTTOM=L7 |
| PCIE_RX_P6 | RXS6-DIFF1 | PAIR | 7 | 5.5 | 5 | 10 | 5 | 50 | 6 | 20 | 12 | 12 | 12 | 12 | 7.5 | 85 Ohms | TOP=L2:L3=L2/L4:L6=L5/L7:BOTTOM=L7 |
| PCIE_RX_P6 | RXS6-DIFF1 | PAIR | 8 | 5.38 | 5 | 10 | 5 | 50 | 6 | 33 | 12 | 12 | 12 | 12 | 6.62 | 85 Ohms | TOP=L2:L3=L2/L4:L6=L5/L7:BOTTOM=L7 |
| PCIE_RX_N70 | RXS70-DIFF1 | PAIR | 1 | 5.38 | 5 | 10 | 5 | 50 | 6 | 33 | 12 | 12 | 12 | 12 | 6.62 | 85 Ohms | TOP=L2:L3=L2/L4:L6=L5/L7:BOTTOM=L7 |
| PCIE_RX_N70 | RXS70-DIFF1 | PAIR | 2 | 5.5 | 5 | 10 | 5 | 50 | 6 | 20 | 12 | 12 | 12 | 12 | 7.5 | 85 Ohms | TOP=L2:L3=L2/L4:L6=L5/L7:BOTTOM=L7 |
| PCIE_RX_N70 | RXS70-DIFF1 | PAIR | 3 | 5.5 | 5 | 10 | 5 | 50 | 6 | 20 | 12 | 12 | 12 | 12 | 7.5 | 85 Ohms | TOP=L2:L3=L2/L4:L6=L5/L7:BOTTOM=L7 |
| PCIE_RX_N70 | RXS70-DIFF1 | PAIR | 4 | 5.5 | 5 | 10 | 5 | 50 | 6 | 20 | 12 | 12 | 12 | 12 | 7.5 | 85 Ohms | TOP=L2:L3=L2/L4:L6=L5/L7:BOTTOM=L7 |
| PCIE_RX_N70 | RXS70-DIFF1 | PAIR | 5 | 5.5 | 5 | 10 | 5 | 50 | 6 | 20 | 12 | 12 | 12 | 12 | 7.5 | 85 Ohms | TOP=L2:L3=L2/L4:L6=L5/L7:BOTTOM=L7 |
| PCIE_RX_N70 | RXS70-DIFF1 | PAIR | 6 | 5.5 | 5 | 10 | 5 | 50 | 6 | 20 | 12 | 12 | 12 | 12 | 7.5 | 85 Ohms | TOP=L2:L3=L2/L4:L6=L5/L7:BOTTOM=L7 |
| PCIE_RX_N70 | RXS70-DIFF1 | PAIR | 7 | 5.5 | 5 | 10 | 5 | 50 | 6 | 20 | 12 | 12 | 12 | 12 | 7.5 | 85 Ohms | TOP=L2:L3=L2/L4:L6=L5/L7:BOTTOM=L7 |
| PCIE_RX_N70 | RXS70-DIFF1 | PAIR | 8 | 5.38 | 5 | 10 | 5 | 50 | 6 | 33 | 12 | 12 | 12 | 12 | 6.62 | 85 Ohms | TOP=L2:L3=L2/L4:L6=L5/L7:BOTTOM=L7 |
| PCIE_RX_P70 | RXS70-DIFF1 | PAIR | 1 | 5.38 | 5 | 10 | 5 | 50 | 6 | 33 | 12 | 12 | 12 | 12 | 6.62 | 85 Ohms | TOP=L2:L3=L2/L4:L6=L5/L7:BOTTOM=L7 |
| PCIE_RX_P70 | RXS70-DIFF1 | PAIR | 2 | 5.5 | 5 | 10 | 5 | 50 | 6 | 20 | 12 | 12 | 12 | 12 | 7.5 | 85 Ohms | TOP=L2:L3=L2/L4:L6=L5/L7:BOTTOM=L7 |
| PCIE_RX_P70 | RXS70-DIFF1 | PAIR | 3 | 5.5 | 5 | 10 | 5 | 50 | 6 | 20 | 12 | 12 | 12 | 12 | 7.5 | 85 Ohms | TOP=L2:L3=L2/L4:L6=L5/L7:BOTTOM=L7 |
| PCIE_RX_P70 | RXS70-DIFF1 | PAIR | 4 | 5.5 | 5 | 10 | 5 | 50 | 6 | 20 | 12 | 12 | 12 | 12 | 7.5 | 85 Ohms | TOP=L2:L3=L2/L4:L6=L5/L7:BOTTOM=L7 |
| PCIE_RX_P70 | RXS70-DIFF1 | PAIR | 5 | 5.5 | 5 | 10 | 5 | 50 | 6 | 20 | 12 | 12 | 12 | 12 | 7.5 | 85 Ohms | TOP=L2:L3=L2/L4:L6=L5/L7:BOTTOM=L7 |
| PCIE_RX_P70 | RXS70-DIFF1 | PAIR | 6 | 5.5 | 5 | 10 | 5 | 50 | 6 | 20 | 12 | 12 | 12 | 12 | 7.5 | 85 Ohms | TOP=L2:L3=L2/L4:L6=L5/L7:BOTTOM=L7 |
| PCIE_RX_P70 | RXS70-DIFF1 | PAIR | 7 | 5.5 | 5 | 10 | 5 | 50 | 6 | 20 | 12 | 12 | 12 | 12 | 7.5 | 85 Ohms | TOP=L2:L3=L2/L4:L6=L5/L7:BOTTOM=L7 |
| PCIE_RX_P70 | RXS70-DIFF1 | PAIR | 8 | 5.38 | 5 | 10 | 5 | 50 | 6 | 33 | 12 | 12 | 12 | 12 | 6.62 | 85 Ohms | TOP=L2:L3=L2/L4:L6=L5/L7:BOTTOM=L7 |
| PCIE_RX_N71 | RXS71-DIFF1 | PAIR | 1 | 5.38 | 5 | 10 | 5 | 50 | 6 | 33 | 12 | 12 | 12 | 12 | 6.62 | 85 Ohms | TOP=L2:L3=L2/L4:L6=L5/L7:BOTTOM=L7 |
| PCIE_RX_N71 | RXS71-DIFF1 | PAIR | 2 | 5.5 | 5 | 10 | 5 | 50 | 6 | 20 | 12 | 12 | 12 | 12 | 7.5 | 85 Ohms | TOP=L2:L3=L2/L4:L6=L5/L7:BOTTOM=L7 |
| PCIE_RX_N71 | RXS71-DIFF1 | PAIR | 3 | 5.5 | 5 | 10 | 5 | 50 | 6 | 20 | 12 | 12 | 12 | 12 | 7.5 | 85 Ohms | TOP=L2:L3=L2/L4:L6=L5/L7:BOTTOM=L7 |
| PCIE_RX_N71 | RXS71-DIFF1 | PAIR | 4 | 5.5 | 5 | 10 | 5 | 50 | 6 | 20 | 12 | 12 | 12 | 12 | 7.5 | 85 Ohms | TOP=L2:L3=L2/L4:L6=L5/L7:BOTTOM=L7 |
| PCIE_RX_N71 | RXS71-DIFF1 | PAIR | 5 | 5.5 | 5 | 10 | 5 | 50 | 6 | 20 | 12 | 12 | 12 | 12 | 7.5 | 85 Ohms | TOP=L2:L3=L2/L4:L6=L5/L7:BOTTOM=L7 |
| PCIE_RX_N71 | RXS71-DIFF1 | PAIR | 6 | 5.5 | 5 | 10 | 5 | 50 | 6 | 20 | 12 | 12 | 12 | 12 | 7.5 | 85 Ohms | TOP=L2:L3=L2/L4:L6=L5/L7:BOTTOM=L7 |
| PCIE_RX_N71 | RXS71-DIFF1 | PAIR | 7 | 5.5 | 5 | 10 | 5 | 50 | 6 | 20 | 12 | 12 | 12 | 12 | 7.5 | 85 Ohms | TOP=L2:L3=L2/L4:L6=L5/L7:BOTTOM=L7 |
| PCIE_RX_N71 | RXS71-DIFF1 | PAIR | 8 | 5.38 | 5 | 10 | 5 | 50 | 6 | 33 | 12 | 12 | 12 | 12 | 6.62 | 85 Ohms | TOP=L2:L3=L2/L4:L6=L5/L7:BOTTOM=L7 |
| PCIE_RX_P71 | RXS71-DIFF1 | PAIR | 1 | 5.38 | 5 | 10 | 5 | 50 | 6 | 33 | 12 | 12 | 12 | 12 | 6.62 | 85 Ohms | TOP=L2:L3=L2/L4:L6=L5/L7:BOTTOM=L7 |
| PCIE_RX_P71 | RXS71-DIFF1 | PAIR | 2 | 5.5 | 5 | 10 | 5 | 50 | 6 | 20 | 12 | 12 | 12 | 12 | 7.5 | 85 Ohms | TOP=L2:L3=L2/L4:L6=L5/L7:BOTTOM=L7 |
| PCIE_RX_P71 | RXS71-DIFF1 | PAIR | 3 | 5.5 | 5 | 10 | 5 | 50 | 6 | 20 | 12 | 12 | 12 | 12 | 7.5 | 85 Ohms | TOP=L2:L3=L2/L4:L6=L5/L7:BOTTOM=L7 |
| PCIE_RX_P71 | RXS71-DIFF1 | PAIR | 4 | 5.5 | 5 | 10 | 5 | 50 | 6 | 20 | 12 | 12 | 12 | 12 | 7.5 | 85 Ohms | TOP=L2:L3=L2/L4:L6=L5/L7:BOTTOM=L7 |
| PCIE_RX_P71 | RXS71-DIFF1 | PAIR | 5 | 5.5 | 5 | 10 | 5 | 50 | 6 | 20 | 12 | 12 | 12 | 12 | 7.5 | 85 Ohms | TOP=L2:L3=L2/L4:L6=L5/L7:BOTTOM=L7 |
| PCIE_RX_P71 | RXS71-DIFF1 | PAIR | 6 | 5.5 | 5 | 10 | 5 | 50 | 6 | 20 | 12 | 12 | 12 | 12 | 7.5 | 85 Ohms | TOP=L2:L3=L2/L4:L6=L5/L7:BOTTOM=L7 |
| PCIE_RX_P71 | RXS71-DIFF1 | PAIR | 7 | 5.5 | 5 | 10 | 5 | 50 | 6 | 20 | 12 | 12 | 12 | 12 | 7.5 | 85 Ohms | TOP=L2:L3=L2/L4:L6=L5/L7:BOTTOM=L7 |
| PCIE_RX_P71 | RXS71-DIFF1 | PAIR | 8 | 5.38 | 5 | 10 | 5 | 50 | 6 | 33 | 12 | 12 | 12 | 12 | 6.62 | 85 Ohms | TOP=L2:L3=L2/L4:L6=L5/L7:BOTTOM=L7 |
| PCIE_RX_N72 | RXS72-DIFF1 | PAIR | 1 | 5.38 | 5 | 10 | 5 | 50 | 6 | 33 | 12 | 12 | 12 | 12 | 6.62 | 85 Ohms | TOP=L2:L3=L2/L4:L6=L5/L7:BOTTOM=L7 |
| PCIE_RX_N72 | RXS72-DIFF1 | PAIR | 2 | 5.5 | 5 | 10 | 5 | 50 | 6 | 20 | 12 | 12 | 12 | 12 | 7.5 | 85 Ohms | TOP=L2:L3=L2/L4:L6=L5/L7:BOTTOM=L7 |
| PCIE_RX_N72 | RXS72-DIFF1 | PAIR | 3 | 5.5 | 5 | 10 | 5 | 50 | 6 | 20 | 12 | 12 | 12 | 12 | 7.5 | 85 Ohms | TOP=L2:L3=L2/L4:L6=L5/L7:BOTTOM=L7 |
| PCIE_RX_N72 | RXS72-DIFF1 | PAIR | 4 | 5.5 | 5 | 10 | 5 | 50 | 6 | 20 | 12 | 12 | 12 | 12 | 7.5 | 85 Ohms | TOP=L2:L3=L2/L4:L6=L5/L7:BOTTOM=L7 |
| PCIE_RX_N72 | RXS72-DIFF1 | PAIR | 5 | 5.5 | 5 | 10 | 5 | 50 | 6 | 20 | 12 | 12 | 12 | 12 | 7.5 | 85 Ohms | TOP=L2:L3=L2/L4:L6=L5/L7:BOTTOM=L7 |
| PCIE_RX_N72 | RXS72-DIFF1 | PAIR | 6 | 5.5 | 5 | 10 | 5 | 50 | 6 | 20 | 12 | 12 | 12 | 12 | 7.5 | 85 Ohms | TOP=L2:L3=L2/L4:L6=L5/L7:BOTTOM=L7 |
| PCIE_RX_N72 | RXS72-DIFF1 | PAIR | 7 | 5.5 | 5 | 10 | 5 | 50 | 6 | 20 | 12 | 12 | 12 | 12 | 7.5 | 85 Ohms | TOP=L2:L3=L2/L4:L6=L5/L7:BOTTOM=L7 |
| PCIE_RX_N72 | RXS72-DIFF1 | PAIR | 8 | 5.38 | 5 | 10 | 5 | 50 | 6 | 33 | 12 | 12 | 12 | 12 | 6.62 | 85 Ohms | TOP=L2:L3=L2/L4:L6=L5/L7:BOTTOM=L7 |
| PCIE_RX_P72 | RXS72-DIFF1 | PAIR | 1 | 5.38 | 5 | 10 | 5 | 50 | 6 | 33 | 12 | 12 | 12 | 12 | 6.62 | 85 Ohms | TOP=L2:L3=L2/L4:L6=L5/L7:BOTTOM=L7 |
| PCIE_RX_P72 | RXS72-DIFF1 | PAIR | 2 | 5.5 | 5 | 10 | 5 | 50 | 6 | 20 | 12 | 12 | 12 | 12 | 7.5 | 85 Ohms | TOP=L2:L3=L2/L4:L6=L5/L7:BOTTOM=L7 |
| PCIE_RX_P72 | RXS72-DIFF1 | PAIR | 3 | 5.5 | 5 | 10 | 5 | 50 | 6 | 20 | 12 | 12 | 12 | 12 | 7.5 | 85 Ohms | TOP=L2:L3=L2/L4:L6=L5/L7:BOTTOM=L7 |
| PCIE_RX_P72 | RXS72-DIFF1 | PAIR | 4 | 5.5 | 5 | 10 | 5 | 50 | 6 | 20 | 12 | 12 | 12 | 12 | 7.5 | 85 Ohms | TOP=L2:L3=L2/L4:L6=L5/L7:BOTTOM=L7 |
| PCIE_RX_P72 | RXS72-DIFF1 | PAIR | 5 | 5.5 | 5 | 10 | 5 | 50 | 6 | 20 | 12 | 12 | 12 | 12 | 7.5 | 85 Ohms | TOP=L2:L3=L2/L4:L6=L5/L7:BOTTOM=L7 |
| PCIE_RX_P72 | RXS72-DIFF1 | PAIR | 6 | 5.5 | 5 | 10 | 5 | 50 | 6 | 20 | 12 | 12 | 12 | 12 | 7.5 | 85 Ohms | TOP=L2:L3=L2/L4:L6=L5/L7:BOTTOM=L7 |
| PCIE_RX_P72 | RXS72-DIFF1 | PAIR | 7 | 5.5 | 5 | 10 | 5 | 50 | 6 | 20 | 12 | 12 | 12 | 12 | 7.5 | 85 Ohms | TOP=L2:L3=L2/L4:L6=L5/L7:BOTTOM=L7 |
| PCIE_RX_P72 | RXS72-DIFF1 | PAIR | 8 | 5.38 | 5 | 10 | 5 | 50 | 6 | 33 | 12 | 12 | 12 | 12 | 6.62 | 85 Ohms | TOP=L2:L3=L2/L4:L6=L5/L7:BOTTOM=L7 |
| PCIE_RX_N73 | RXS73-DIFF1 | PAIR | 1 | 5.38 | 5 | 10 | 5 | 50 | 6 | 33 | 12 | 12 | 12 | 12 | 6.62 | 85 Ohms | TOP=L2:L3=L2/L4:L6=L5/L7:BOTTOM=L7 |
| PCIE_RX_N73 | RXS73-DIFF1 | PAIR | 2 | 5.5 | 5 | 10 | 5 | 50 | 6 | 20 | 12 | 12 | 12 | 12 | 7.5 | 85 Ohms | TOP=L2:L3=L2/L4:L6=L5/L7:BOTTOM=L7 |
| PCIE_RX_N73 | RXS73-DIFF1 | PAIR | 3 | 5.5 | 5 | 10 | 5 | 50 | 6 | 20 | 12 | 12 | 12 | 12 | 7.5 | 85 Ohms | TOP=L2:L3=L2/L4:L6=L5/L7:BOTTOM=L7 |
| PCIE_RX_N73 | RXS73-DIFF1 | PAIR | 4 | 5.5 | 5 | 10 | 5 | 50 | 6 | 20 | 12 | 12 | 12 | 12 | 7.5 | 85 Ohms | TOP=L2:L3=L2/L4:L6=L5/L7:BOTTOM=L7 |
| PCIE_RX_N73 | RXS73-DIFF1 | PAIR | 5 | 5.5 | 5 | 10 | 5 | 50 | 6 | 20 | 12 | 12 | 12 | 12 | 7.5 | 85 Ohms | TOP=L2:L3=L2/L4:L6=L5/L7:BOTTOM=L7 |
| PCIE_RX_N73 | RXS73-DIFF1 | PAIR | 6 | 5.5 | 5 | 10 | 5 | 50 | 6 | 20 | 12 | 12 | 12 | 12 | 7.5 | 85 Ohms | TOP=L2:L3=L2/L4:L6=L5/L7:BOTTOM=L7 |
| PCIE_RX_N73 | RXS73-DIFF1 | PAIR | 7 | 5.5 | 5 | 10 | 5 | 50 | 6 | 20 | 12 | 12 | 12 | 12 | 7.5 | 85 Ohms | TOP=L2:L3=L2/L4:L6=L5/L7:BOTTOM=L7 |
| PCIE_RX_N73 | RXS73-DIFF1 | PAIR | 8 | 5.38 | 5 | 10 | 5 | 50 | 6 | 33 | 12 | 12 | 12 | 12 | 6.62 | 85 Ohms | TOP=L2:L3=L2/L4:L6=L5/L7:BOTTOM=L7 |
| PCIE_RX_P73 | RXS73-DIFF1 | PAIR | 1 | 5.38 | 5 | 10 | 5 | 50 | 6 | 33 | 12 | 12 | 12 | 12 | 6.62 | 85 Ohms | TOP=L2:L3=L2/L4:L6=L5/L7:BOTTOM=L7 |
| PCIE_RX_P73 | RXS73-DIFF1 | PAIR | 2 | 5.5 | 5 | 10 | 5 | 50 | 6 | 20 | 12 | 12 | 12 | 12 | 7.5 | 85 Ohms | TOP=L2:L3=L2/L4:L6=L5/L7:BOTTOM=L7 |
| PCIE_RX_P73 | RXS73-DIFF1 | PAIR | 3 | 5.5 | 5 | 10 | 5 | 50 | 6 | 20 | 12 | 12 | 12 | 12 | 7.5 | 85 Ohms | TOP=L2:L3=L2/L4:L6=L5/L7:BOTTOM=L7 |
| PCIE_RX_P73 | RXS73-DIFF1 | PAIR | 4 | 5.5 | 5 | 10 | 5 | 50 | 6 | 20 | 12 | 12 | 12 | 12 | 7.5 | 85 Ohms | TOP=L2:L3=L2/L4:L6=L5/L7:BOTTOM=L7 |
| PCIE_RX_P73 | RXS73-DIFF1 | PAIR | 5 | 5.5 | 5 | 10 | 5 | 50 | 6 | 20 | 12 | 12 | 12 | 12 | 7.5 | 85 Ohms | TOP=L2:L3=L2/L4:L6=L5/L7:BOTTOM=L7 |
| PCIE_RX_P73 | RXS73-DIFF1 | PAIR | 6 | 5.5 | 5 | 10 | 5 | 50 | 6 | 20 | 12 | 12 | 12 | 12 | 7.5 | 85 Ohms | TOP=L2:L3=L2/L4:L6=L5/L7:BOTTOM=L7 |
| PCIE_RX_P73 | RXS73-DIFF1 | PAIR | 7 | 5.5 | 5 | 10 | 5 | 50 | 6 | 20 | 12 | 12 | 12 | 12 | 7.5 | 85 Ohms | TOP=L2:L3=L2/L4:L6=L5/L7:BOTTOM=L7 |
| PCIE_RX_P73 | RXS73-DIFF1 | PAIR | 8 | 5.38 | 5 | 10 | 5 | 50 | 6 | 33 | 12 | 12 | 12 | 12 | 6.62 | 85 Ohms | TOP=L2:L3=L2/L4:L6=L5/L7:BOTTOM=L7 |
| PCIE_RX_N74 | RXS74-DIFF1 | PAIR | 1 | 5.38 | 5 | 10 | 5 | 50 | 6 | 33 | 12 | 12 | 12 | 12 | 6.62 | 85 Ohms | TOP=L2:L3=L2/L4:L6=L5/L7:BOTTOM=L7 |
| PCIE_RX_N74 | RXS74-DIFF1 | PAIR | 2 | 5.5 | 5 | 10 | 5 | 50 | 6 | 20 | 12 | 12 | 12 | 12 | 7.5 | 85 Ohms | TOP=L2:L3=L2/L4:L6=L5/L7:BOTTOM=L7 |
| PCIE_RX_N74 | RXS74-DIFF1 | PAIR | 3 | 5.5 | 5 | 10 | 5 | 50 | 6 | 20 | 12 | 12 | 12 | 12 | 7.5 | 85 Ohms | TOP=L2:L3=L2/L4:L6=L5/L7:BOTTOM=L7 |
| PCIE_RX_N74 | RXS74-DIFF1 | PAIR | 4 | 5.5 | 5 | 10 | 5 | 50 | 6 | 20 | 12 | 12 | 12 | 12 | 7.5 | 85 Ohms | TOP=L2:L3=L2/L4:L6=L5/L7:BOTTOM=L7 |
| PCIE_RX_N74 | RXS74-DIFF1 | PAIR | 5 | 5.5 | 5 | 10 | 5 | 50 | 6 | 20 | 12 | 12 | 12 | 12 | 7.5 | 85 Ohms | TOP=L2:L3=L2/L4:L6=L5/L7:BOTTOM=L7 |
| PCIE_RX_N74 | RXS74-DIFF1 | PAIR | 6 | 5.5 | 5 | 10 | 5 | 50 | 6 | 20 | 12 | 12 | 12 | 12 | 7.5 | 85 Ohms | TOP=L2:L3=L2/L4:L6=L5/L7:BOTTOM=L7 |
| PCIE_RX_N74 | RXS74-DIFF1 | PAIR | 7 | 5.5 | 5 | 10 | 5 | 50 | 6 | 20 | 12 | 12 | 12 | 12 | 7.5 | 85 Ohms | TOP=L2:L3=L2/L4:L6=L5/L7:BOTTOM=L7 |
| PCIE_RX_N74 | RXS74-DIFF1 | PAIR | 8 | 5.38 | 5 | 10 | 5 | 50 | 6 | 33 | 12 | 12 | 12 | 12 | 6.62 | 85 Ohms | TOP=L2:L3=L2/L4:L6=L5/L7:BOTTOM=L7 |
| PCIE_RX_P74 | RXS74-DIFF1 | PAIR | 1 | 5.38 | 5 | 10 | 5 | 50 | 6 | 33 | 12 | 12 | 12 | 12 | 6.62 | 85 Ohms | TOP=L2:L3=L2/L4:L6=L5/L7:BOTTOM=L7 |
| PCIE_RX_P74 | RXS74-DIFF1 | PAIR | 2 | 5.5 | 5 | 10 | 5 | 50 | 6 | 20 | 12 | 12 | 12 | 12 | 7.5 | 85 Ohms | TOP=L2:L3=L2/L4:L6=L5/L7:BOTTOM=L7 |
| PCIE_RX_P74 | RXS74-DIFF1 | PAIR | 3 | 5.5 | 5 | 10 | 5 | 50 | 6 | 20 | 12 | 12 | 12 | 12 | 7.5 | 85 Ohms | TOP=L2:L3=L2/L4:L6=L5/L7:BOTTOM=L7 |
| PCIE_RX_P74 | RXS74-DIFF1 | PAIR | 4 | 5.5 | 5 | 10 | 5 | 50 | 6 | 20 | 12 | 12 | 12 | 12 | 7.5 | 85 Ohms | TOP=L2:L3=L2/L4:L6=L5/L7:BOTTOM=L7 |
| PCIE_RX_P74 | RXS74-DIFF1 | PAIR | 5 | 5.5 | 5 | 10 | 5 | 50 | 6 | 20 | 12 | 12 | 12 | 12 | 7.5 | 85 Ohms | TOP=L2:L3=L2/L4:L6=L5/L7:BOTTOM=L7 |
| PCIE_RX_P74 | RXS74-DIFF1 | PAIR | 6 | 5.5 | 5 | 10 | 5 | 50 | 6 | 20 | 12 | 12 | 12 | 12 | 7.5 | 85 Ohms | TOP=L2:L3=L2/L4:L6=L5/L7:BOTTOM=L7 |
| PCIE_RX_P74 | RXS74-DIFF1 | PAIR | 7 | 5.5 | 5 | 10 | 5 | 50 | 6 | 20 | 12 | 12 | 12 | 12 | 7.5 | 85 Ohms | TOP=L2:L3=L2/L4:L6=L5/L7:BOTTOM=L7 |
| PCIE_RX_P74 | RXS74-DIFF1 | PAIR | 8 | 5.38 | 5 | 10 | 5 | 50 | 6 | 33 | 12 | 12 | 12 | 12 | 6.62 | 85 Ohms | TOP=L2:L3=L2/L4:L6=L5/L7:BOTTOM=L7 |
| PCIE_RX_N75 | RXS75-DIFF1 | PAIR | 1 | 5.38 | 5 | 10 | 5 | 50 | 6 | 33 | 12 | 12 | 12 | 12 | 6.62 | 85 Ohms | TOP=L2:L3=L2/L4:L6=L5/L7:BOTTOM=L7 |
| PCIE_RX_N75 | RXS75-DIFF1 | PAIR | 2 | 5.5 | 5 | 10 | 5 | 50 | 6 | 20 | 12 | 12 | 12 | 12 | 7.5 | 85 Ohms | TOP=L2:L3=L2/L4:L6=L5/L7:BOTTOM=L7 |
| PCIE_RX_N75 | RXS75-DIFF1 | PAIR | 3 | 5.5 | 5 | 10 | 5 | 50 | 6 | 20 | 12 | 12 | 12 | 12 | 7.5 | 85 Ohms | TOP=L2:L3=L2/L4:L6=L5/L7:BOTTOM=L7 |
| PCIE_RX_N75 | RXS75-DIFF1 | PAIR | 4 | 5.5 | 5 | 10 | 5 | 50 | 6 | 20 | 12 | 12 | 12 | 12 | 7.5 | 85 Ohms | TOP=L2:L3=L2/L4:L6=L5/L7:BOTTOM=L7 |
| PCIE_RX_N75 | RXS75-DIFF1 | PAIR | 5 | 5.5 | 5 | 10 | 5 | 50 | 6 | 20 | 12 | 12 | 12 | 12 | 7.5 | 85 Ohms | TOP=L2:L3=L2/L4:L6=L5/L7:BOTTOM=L7 |
| PCIE_RX_N75 | RXS75-DIFF1 | PAIR | 6 | 5.5 | 5 | 10 | 5 | 50 | 6 | 20 | 12 | 12 | 12 | 12 | 7.5 | 85 Ohms | TOP=L2:L3=L2/L4:L6=L5/L7:BOTTOM=L7 |
| PCIE_RX_N75 | RXS75-DIFF1 | PAIR | 7 | 5.5 | 5 | 10 | 5 | 50 | 6 | 20 | 12 | 12 | 12 | 12 | 7.5 | 85 Ohms | TOP=L2:L3=L2/L4:L6=L5/L7:BOTTOM=L7 |
| PCIE_RX_N75 | RXS75-DIFF1 | PAIR | 8 | 5.38 | 5 | 10 | 5 | 50 | 6 | 33 | 12 | 12 | 12 | 12 | 6.62 | 85 Ohms | TOP=L2:L3=L2/L4:L6=L5/L7:BOTTOM=L7 |
| PCIE_RX_P75 | RXS75-DIFF1 | PAIR | 1 | 5.38 | 5 | 10 | 5 | 50 | 6 | 33 | 12 | 12 | 12 | 12 | 6.62 | 85 Ohms | TOP=L2:L3=L2/L4:L6=L5/L7:BOTTOM=L7 |
| PCIE_RX_P75 | RXS75-DIFF1 | PAIR | 2 | 5.5 | 5 | 10 | 5 | 50 | 6 | 20 | 12 | 12 | 12 | 12 | 7.5 | 85 Ohms | TOP=L2:L3=L2/L4:L6=L5/L7:BOTTOM=L7 |
| PCIE_RX_P75 | RXS75-DIFF1 | PAIR | 3 | 5.5 | 5 | 10 | 5 | 50 | 6 | 20 | 12 | 12 | 12 | 12 | 7.5 | 85 Ohms | TOP=L2:L3=L2/L4:L6=L5/L7:BOTTOM=L7 |
| PCIE_RX_P75 | RXS75-DIFF1 | PAIR | 4 | 5.5 | 5 | 10 | 5 | 50 | 6 | 20 | 12 | 12 | 12 | 12 | 7.5 | 85 Ohms | TOP=L2:L3=L2/L4:L6=L5/L7:BOTTOM=L7 |
| PCIE_RX_P75 | RXS75-DIFF1 | PAIR | 5 | 5.5 | 5 | 10 | 5 | 50 | 6 | 20 | 12 | 12 | 12 | 12 | 7.5 | 85 Ohms | TOP=L2:L3=L2/L4:L6=L5/L7:BOTTOM=L7 |
| PCIE_RX_P75 | RXS75-DIFF1 | PAIR | 6 | 5.5 | 5 | 10 | 5 | 50 | 6 | 20 | 12 | 12 | 12 | 12 | 7.5 | 85 Ohms | TOP=L2:L3=L2/L4:L6=L5/L7:BOTTOM=L7 |
| PCIE_RX_P75 | RXS75-DIFF1 | PAIR | 7 | 5.5 | 5 | 10 | 5 | 50 | 6 | 20 | 12 | 12 | 12 | 12 | 7.5 | 85 Ohms | TOP=L2:L3=L2/L4:L6=L5/L7:BOTTOM=L7 |
| PCIE_RX_P75 | RXS75-DIFF1 | PAIR | 8 | 5.38 | 5 | 10 | 5 | 50 | 6 | 33 | 12 | 12 | 12 | 12 | 6.62 | 85 Ohms | TOP=L2:L3=L2/L4:L6=L5/L7:BOTTOM=L7 |
| PCIE_RX_N76 | RXS76-DIFF1 | PAIR | 1 | 5.38 | 5 | 10 | 5 | 50 | 6 | 33 | 12 | 12 | 12 | 12 | 6.62 | 85 Ohms | TOP=L2:L3=L2/L4:L6=L5/L7:BOTTOM=L7 |
| PCIE_RX_N76 | RXS76-DIFF1 | PAIR | 2 | 5.5 | 5 | 10 | 5 | 50 | 6 | 20 | 12 | 12 | 12 | 12 | 7.5 | 85 Ohms | TOP=L2:L3=L2/L4:L6=L5/L7:BOTTOM=L7 |
| PCIE_RX_N76 | RXS76-DIFF1 | PAIR | 3 | 5.5 | 5 | 10 | 5 | 50 | 6 | 20 | 12 | 12 | 12 | 12 | 7.5 | 85 Ohms | TOP=L2:L3=L2/L4:L6=L5/L7:BOTTOM=L7 |
| PCIE_RX_N76 | RXS76-DIFF1 | PAIR | 4 | 5.5 | 5 | 10 | 5 | 50 | 6 | 20 | 12 | 12 | 12 | 12 | 7.5 | 85 Ohms | TOP=L2:L3=L2/L4:L6=L5/L7:BOTTOM=L7 |
| PCIE_RX_N76 | RXS76-DIFF1 | PAIR | 5 | 5.5 | 5 | 10 | 5 | 50 | 6 | 20 | 12 | 12 | 12 | 12 | 7.5 | 85 Ohms | TOP=L2:L3=L2/L4:L6=L5/L7:BOTTOM=L7 |
| PCIE_RX_N76 | RXS76-DIFF1 | PAIR | 6 | 5.5 | 5 | 10 | 5 | 50 | 6 | 20 | 12 | 12 | 12 | 12 | 7.5 | 85 Ohms | TOP=L2:L3=L2/L4:L6=L5/L7:BOTTOM=L7 |
| PCIE_RX_N76 | RXS76-DIFF1 | PAIR | 7 | 5.5 | 5 | 10 | 5 | 50 | 6 | 20 | 12 | 12 | 12 | 12 | 7.5 | 85 Ohms | TOP=L2:L3=L2/L4:L6=L5/L7:BOTTOM=L7 |
| PCIE_RX_N76 | RXS76-DIFF1 | PAIR | 8 | 5.38 | 5 | 10 | 5 | 50 | 6 | 33 | 12 | 12 | 12 | 12 | 6.62 | 85 Ohms | TOP=L2:L3=L2/L4:L6=L5/L7:BOTTOM=L7 |
| PCIE_RX_P76 | RXS76-DIFF1 | PAIR | 1 | 5.38 | 5 | 10 | 5 | 50 | 6 | 33 | 12 | 12 | 12 | 12 | 6.62 | 85 Ohms | TOP=L2:L3=L2/L4:L6=L5/L7:BOTTOM=L7 |
| PCIE_RX_P76 | RXS76-DIFF1 | PAIR | 2 | 5.5 | 5 | 10 | 5 | 50 | 6 | 20 | 12 | 12 | 12 | 12 | 7.5 | 85 Ohms | TOP=L2:L3=L2/L4:L6=L5/L7:BOTTOM=L7 |
| PCIE_RX_P76 | RXS76-DIFF1 | PAIR | 3 | 5.5 | 5 | 10 | 5 | 50 | 6 | 20 | 12 | 12 | 12 | 12 | 7.5 | 85 Ohms | TOP=L2:L3=L2/L4:L6=L5/L7:BOTTOM=L7 |
| PCIE_RX_P76 | RXS76-DIFF1 | PAIR | 4 | 5.5 | 5 | 10 | 5 | 50 | 6 | 20 | 12 | 12 | 12 | 12 | 7.5 | 85 Ohms | TOP=L2:L3=L2/L4:L6=L5/L7:BOTTOM=L7 |
| PCIE_RX_P76 | RXS76-DIFF1 | PAIR | 5 | 5.5 | 5 | 10 | 5 | 50 | 6 | 20 | 12 | 12 | 12 | 12 | 7.5 | 85 Ohms | TOP=L2:L3=L2/L4:L6=L5/L7:BOTTOM=L7 |
| PCIE_RX_P76 | RXS76-DIFF1 | PAIR | 6 | 5.5 | 5 | 10 | 5 | 50 | 6 | 20 | 12 | 12 | 12 | 12 | 7.5 | 85 Ohms | TOP=L2:L3=L2/L4:L6=L5/L7:BOTTOM=L7 |
| PCIE_RX_P76 | RXS76-DIFF1 | PAIR | 7 | 5.5 | 5 | 10 | 5 | 50 | 6 | 20 | 12 | 12 | 12 | 12 | 7.5 | 85 Ohms | TOP=L2:L3=L2/L4:L6=L5/L7:BOTTOM=L7 |
| PCIE_RX_P76 | RXS76-DIFF1 | PAIR | 8 | 5.38 | 5 | 10 | 5 | 50 | 6 | 33 | 12 | 12 | 12 | 12 | 6.62 | 85 Ohms | TOP=L2:L3=L2/L4:L6=L5/L7:BOTTOM=L7 |
| PCIE_RX_N78 | RXS78-DIFF1 | PAIR | 1 | 5.38 | 5 | 10 | 5 | 50 | 6 | 33 | 12 | 12 | 12 | 12 | 6.62 | 85 Ohms | TOP=L2:L3=L2/L4:L6=L5/L7:BOTTOM=L7 |
| PCIE_RX_N78 | RXS78-DIFF1 | PAIR | 2 | 5.5 | 5 | 10 | 5 | 50 | 6 | 20 | 12 | 12 | 12 | 12 | 7.5 | 85 Ohms | TOP=L2:L3=L2/L4:L6=L5/L7:BOTTOM=L7 |
| PCIE_RX_N78 | RXS78-DIFF1 | PAIR | 3 | 5.5 | 5 | 10 | 5 | 50 | 6 | 20 | 12 | 12 | 12 | 12 | 7.5 | 85 Ohms | TOP=L2:L3=L2/L4:L6=L5/L7:BOTTOM=L7 |
| PCIE_RX_N78 | RXS78-DIFF1 | PAIR | 4 | 5.5 | 5 | 10 | 5 | 50 | 6 | 20 | 12 | 12 | 12 | 12 | 7.5 | 85 Ohms | TOP=L2:L3=L2/L4:L6=L5/L7:BOTTOM=L7 |
| PCIE_RX_N78 | RXS78-DIFF1 | PAIR | 5 | 5.5 | 5 | 10 | 5 | 50 | 6 | 20 | 12 | 12 | 12 | 12 | 7.5 | 85 Ohms | TOP=L2:L3=L2/L4:L6=L5/L7:BOTTOM=L7 |
| PCIE_RX_N78 | RXS78-DIFF1 | PAIR | 6 | 5.5 | 5 | 10 | 5 | 50 | 6 | 20 | 12 | 12 | 12 | 12 | 7.5 | 85 Ohms | TOP=L2:L3=L2/L4:L6=L5/L7:BOTTOM=L7 |
| PCIE_RX_N78 | RXS78-DIFF1 | PAIR | 7 | 5.5 | 5 | 10 | 5 | 50 | 6 | 20 | 12 | 12 | 12 | 12 | 7.5 | 85 Ohms | TOP=L2:L3=L2/L4:L6=L5/L7:BOTTOM=L7 |
| PCIE_RX_N78 | RXS78-DIFF1 | PAIR | 8 | 5.38 | 5 | 10 | 5 | 50 | 6 | 33 | 12 | 12 | 12 | 12 | 6.62 | 85 Ohms | TOP=L2:L3=L2/L4:L6=L5/L7:BOTTOM=L7 |
| PCIE_RX_P78 | RXS78-DIFF1 | PAIR | 1 | 5.38 | 5 | 10 | 5 | 50 | 6 | 33 | 12 | 12 | 12 | 12 | 6.62 | 85 Ohms | TOP=L2:L3=L2/L4:L6=L5/L7:BOTTOM=L7 |
| PCIE_RX_P78 | RXS78-DIFF1 | PAIR | 2 | 5.5 | 5 | 10 | 5 | 50 | 6 | 20 | 12 | 12 | 12 | 12 | 7.5 | 85 Ohms | TOP=L2:L3=L2/L4:L6=L5/L7:BOTTOM=L7 |
| PCIE_RX_P78 | RXS78-DIFF1 | PAIR | 3 | 5.5 | 5 | 10 | 5 | 50 | 6 | 20 | 12 | 12 | 12 | 12 | 7.5 | 85 Ohms | TOP=L2:L3=L2/L4:L6=L5/L7:BOTTOM=L7 |
| PCIE_RX_P78 | RXS78-DIFF1 | PAIR | 4 | 5.5 | 5 | 10 | 5 | 50 | 6 | 20 | 12 | 12 | 12 | 12 | 7.5 | 85 Ohms | TOP=L2:L3=L2/L4:L6=L5/L7:BOTTOM=L7 |
| PCIE_RX_P78 | RXS78-DIFF1 | PAIR | 5 | 5.5 | 5 | 10 | 5 | 50 | 6 | 20 | 12 | 12 | 12 | 12 | 7.5 | 85 Ohms | TOP=L2:L3=L2/L4:L6=L5/L7:BOTTOM=L7 |
| PCIE_RX_P78 | RXS78-DIFF1 | PAIR | 6 | 5.5 | 5 | 10 | 5 | 50 | 6 | 20 | 12 | 12 | 12 | 12 | 7.5 | 85 Ohms | TOP=L2:L3=L2/L4:L6=L5/L7:BOTTOM=L7 |
| PCIE_RX_P78 | RXS78-DIFF1 | PAIR | 7 | 5.5 | 5 | 10 | 5 | 50 | 6 | 20 | 12 | 12 | 12 | 12 | 7.5 | 85 Ohms | TOP=L2:L3=L2/L4:L6=L5/L7:BOTTOM=L7 |
| PCIE_RX_P78 | RXS78-DIFF1 | PAIR | 8 | 5.38 | 5 | 10 | 5 | 50 | 6 | 33 | 12 | 12 | 12 | 12 | 6.62 | 85 Ohms | TOP=L2:L3=L2/L4:L6=L5/L7:BOTTOM=L7 |
| PCIE_RX_N7 | RXS7-DIFF1 | PAIR | 1 | 5.38 | 5 | 10 | 5 | 50 | 6 | 33 | 12 | 12 | 12 | 12 | 6.62 | 85 Ohms | TOP=L2:L3=L2/L4:L6=L5/L7:BOTTOM=L7 |
| PCIE_RX_N7 | RXS7-DIFF1 | PAIR | 2 | 5.5 | 5 | 10 | 5 | 50 | 6 | 20 | 12 | 12 | 12 | 12 | 7.5 | 85 Ohms | TOP=L2:L3=L2/L4:L6=L5/L7:BOTTOM=L7 |
| PCIE_RX_N7 | RXS7-DIFF1 | PAIR | 3 | 5.5 | 5 | 10 | 5 | 50 | 6 | 20 | 12 | 12 | 12 | 12 | 7.5 | 85 Ohms | TOP=L2:L3=L2/L4:L6=L5/L7:BOTTOM=L7 |
| PCIE_RX_N7 | RXS7-DIFF1 | PAIR | 4 | 5.5 | 5 | 10 | 5 | 50 | 6 | 20 | 12 | 12 | 12 | 12 | 7.5 | 85 Ohms | TOP=L2:L3=L2/L4:L6=L5/L7:BOTTOM=L7 |
| PCIE_RX_N7 | RXS7-DIFF1 | PAIR | 5 | 5.5 | 5 | 10 | 5 | 50 | 6 | 20 | 12 | 12 | 12 | 12 | 7.5 | 85 Ohms | TOP=L2:L3=L2/L4:L6=L5/L7:BOTTOM=L7 |
| PCIE_RX_N7 | RXS7-DIFF1 | PAIR | 6 | 5.5 | 5 | 10 | 5 | 50 | 6 | 20 | 12 | 12 | 12 | 12 | 7.5 | 85 Ohms | TOP=L2:L3=L2/L4:L6=L5/L7:BOTTOM=L7 |
| PCIE_RX_N7 | RXS7-DIFF1 | PAIR | 7 | 5.5 | 5 | 10 | 5 | 50 | 6 | 20 | 12 | 12 | 12 | 12 | 7.5 | 85 Ohms | TOP=L2:L3=L2/L4:L6=L5/L7:BOTTOM=L7 |
| PCIE_RX_N7 | RXS7-DIFF1 | PAIR | 8 | 5.38 | 5 | 10 | 5 | 50 | 6 | 33 | 12 | 12 | 12 | 12 | 6.62 | 85 Ohms | TOP=L2:L3=L2/L4:L6=L5/L7:BOTTOM=L7 |
| PCIE_RX_P7 | RXS7-DIFF1 | PAIR | 1 | 5.38 | 5 | 10 | 5 | 50 | 6 | 33 | 12 | 12 | 12 | 12 | 6.62 | 85 Ohms | TOP=L2:L3=L2/L4:L6=L5/L7:BOTTOM=L7 |
| PCIE_RX_P7 | RXS7-DIFF1 | PAIR | 2 | 5.5 | 5 | 10 | 5 | 50 | 6 | 20 | 12 | 12 | 12 | 12 | 7.5 | 85 Ohms | TOP=L2:L3=L2/L4:L6=L5/L7:BOTTOM=L7 |
| PCIE_RX_P7 | RXS7-DIFF1 | PAIR | 3 | 5.5 | 5 | 10 | 5 | 50 | 6 | 20 | 12 | 12 | 12 | 12 | 7.5 | 85 Ohms | TOP=L2:L3=L2/L4:L6=L5/L7:BOTTOM=L7 |
| PCIE_RX_P7 | RXS7-DIFF1 | PAIR | 4 | 5.5 | 5 | 10 | 5 | 50 | 6 | 20 | 12 | 12 | 12 | 12 | 7.5 | 85 Ohms | TOP=L2:L3=L2/L4:L6=L5/L7:BOTTOM=L7 |
| PCIE_RX_P7 | RXS7-DIFF1 | PAIR | 5 | 5.5 | 5 | 10 | 5 | 50 | 6 | 20 | 12 | 12 | 12 | 12 | 7.5 | 85 Ohms | TOP=L2:L3=L2/L4:L6=L5/L7:BOTTOM=L7 |
| PCIE_RX_P7 | RXS7-DIFF1 | PAIR | 6 | 5.5 | 5 | 10 | 5 | 50 | 6 | 20 | 12 | 12 | 12 | 12 | 7.5 | 85 Ohms | TOP=L2:L3=L2/L4:L6=L5/L7:BOTTOM=L7 |
| PCIE_RX_P7 | RXS7-DIFF1 | PAIR | 7 | 5.5 | 5 | 10 | 5 | 50 | 6 | 20 | 12 | 12 | 12 | 12 | 7.5 | 85 Ohms | TOP=L2:L3=L2/L4:L6=L5/L7:BOTTOM=L7 |
| PCIE_RX_P7 | RXS7-DIFF1 | PAIR | 8 | 5.38 | 5 | 10 | 5 | 50 | 6 | 33 | 12 | 12 | 12 | 12 | 6.62 | 85 Ohms | TOP=L2:L3=L2/L4:L6=L5/L7:BOTTOM=L7 |
| PCIE_RX_N80 | RXS80-DIFF1 | PAIR | 1 | 5.38 | 5 | 10 | 5 | 50 | 6 | 33 | 12 | 12 | 12 | 12 | 6.62 | 85 Ohms | TOP=L2:L3=L2/L4:L6=L5/L7:BOTTOM=L7 |
| PCIE_RX_N80 | RXS80-DIFF1 | PAIR | 2 | 5.5 | 5 | 10 | 5 | 50 | 6 | 20 | 12 | 12 | 12 | 12 | 7.5 | 85 Ohms | TOP=L2:L3=L2/L4:L6=L5/L7:BOTTOM=L7 |
| PCIE_RX_N80 | RXS80-DIFF1 | PAIR | 3 | 5.5 | 5 | 10 | 5 | 50 | 6 | 20 | 12 | 12 | 12 | 12 | 7.5 | 85 Ohms | TOP=L2:L3=L2/L4:L6=L5/L7:BOTTOM=L7 |
| PCIE_RX_N80 | RXS80-DIFF1 | PAIR | 4 | 5.5 | 5 | 10 | 5 | 50 | 6 | 20 | 12 | 12 | 12 | 12 | 7.5 | 85 Ohms | TOP=L2:L3=L2/L4:L6=L5/L7:BOTTOM=L7 |
| PCIE_RX_N80 | RXS80-DIFF1 | PAIR | 5 | 5.5 | 5 | 10 | 5 | 50 | 6 | 20 | 12 | 12 | 12 | 12 | 7.5 | 85 Ohms | TOP=L2:L3=L2/L4:L6=L5/L7:BOTTOM=L7 |
| PCIE_RX_N80 | RXS80-DIFF1 | PAIR | 6 | 5.5 | 5 | 10 | 5 | 50 | 6 | 20 | 12 | 12 | 12 | 12 | 7.5 | 85 Ohms | TOP=L2:L3=L2/L4:L6=L5/L7:BOTTOM=L7 |
| PCIE_RX_N80 | RXS80-DIFF1 | PAIR | 7 | 5.5 | 5 | 10 | 5 | 50 | 6 | 20 | 12 | 12 | 12 | 12 | 7.5 | 85 Ohms | TOP=L2:L3=L2/L4:L6=L5/L7:BOTTOM=L7 |
| PCIE_RX_N80 | RXS80-DIFF1 | PAIR | 8 | 5.38 | 5 | 10 | 5 | 50 | 6 | 33 | 12 | 12 | 12 | 12 | 6.62 | 85 Ohms | TOP=L2:L3=L2/L4:L6=L5/L7:BOTTOM=L7 |
| PCIE_RX_P80 | RXS80-DIFF1 | PAIR | 1 | 5.38 | 5 | 10 | 5 | 50 | 6 | 33 | 12 | 12 | 12 | 12 | 6.62 | 85 Ohms | TOP=L2:L3=L2/L4:L6=L5/L7:BOTTOM=L7 |
| PCIE_RX_P80 | RXS80-DIFF1 | PAIR | 2 | 5.5 | 5 | 10 | 5 | 50 | 6 | 20 | 12 | 12 | 12 | 12 | 7.5 | 85 Ohms | TOP=L2:L3=L2/L4:L6=L5/L7:BOTTOM=L7 |
| PCIE_RX_P80 | RXS80-DIFF1 | PAIR | 3 | 5.5 | 5 | 10 | 5 | 50 | 6 | 20 | 12 | 12 | 12 | 12 | 7.5 | 85 Ohms | TOP=L2:L3=L2/L4:L6=L5/L7:BOTTOM=L7 |
| PCIE_RX_P80 | RXS80-DIFF1 | PAIR | 4 | 5.5 | 5 | 10 | 5 | 50 | 6 | 20 | 12 | 12 | 12 | 12 | 7.5 | 85 Ohms | TOP=L2:L3=L2/L4:L6=L5/L7:BOTTOM=L7 |
| PCIE_RX_P80 | RXS80-DIFF1 | PAIR | 5 | 5.5 | 5 | 10 | 5 | 50 | 6 | 20 | 12 | 12 | 12 | 12 | 7.5 | 85 Ohms | TOP=L2:L3=L2/L4:L6=L5/L7:BOTTOM=L7 |
| PCIE_RX_P80 | RXS80-DIFF1 | PAIR | 6 | 5.5 | 5 | 10 | 5 | 50 | 6 | 20 | 12 | 12 | 12 | 12 | 7.5 | 85 Ohms | TOP=L2:L3=L2/L4:L6=L5/L7:BOTTOM=L7 |
| PCIE_RX_P80 | RXS80-DIFF1 | PAIR | 7 | 5.5 | 5 | 10 | 5 | 50 | 6 | 20 | 12 | 12 | 12 | 12 | 7.5 | 85 Ohms | TOP=L2:L3=L2/L4:L6=L5/L7:BOTTOM=L7 |
| PCIE_RX_P80 | RXS80-DIFF1 | PAIR | 8 | 5.38 | 5 | 10 | 5 | 50 | 6 | 33 | 12 | 12 | 12 | 12 | 6.62 | 85 Ohms | TOP=L2:L3=L2/L4:L6=L5/L7:BOTTOM=L7 |
| PCIE_RX_N81 | RXS81-DIFF1 | PAIR | 1 | 5.38 | 5 | 10 | 5 | 50 | 6 | 33 | 12 | 12 | 12 | 12 | 6.62 | 85 Ohms | TOP=L2:L3=L2/L4:L6=L5/L7:BOTTOM=L7 |
| PCIE_RX_N81 | RXS81-DIFF1 | PAIR | 2 | 5.5 | 5 | 10 | 5 | 50 | 6 | 20 | 12 | 12 | 12 | 12 | 7.5 | 85 Ohms | TOP=L2:L3=L2/L4:L6=L5/L7:BOTTOM=L7 |
| PCIE_RX_N81 | RXS81-DIFF1 | PAIR | 3 | 5.5 | 5 | 10 | 5 | 50 | 6 | 20 | 12 | 12 | 12 | 12 | 7.5 | 85 Ohms | TOP=L2:L3=L2/L4:L6=L5/L7:BOTTOM=L7 |
| PCIE_RX_N81 | RXS81-DIFF1 | PAIR | 4 | 5.5 | 5 | 10 | 5 | 50 | 6 | 20 | 12 | 12 | 12 | 12 | 7.5 | 85 Ohms | TOP=L2:L3=L2/L4:L6=L5/L7:BOTTOM=L7 |
| PCIE_RX_N81 | RXS81-DIFF1 | PAIR | 5 | 5.5 | 5 | 10 | 5 | 50 | 6 | 20 | 12 | 12 | 12 | 12 | 7.5 | 85 Ohms | TOP=L2:L3=L2/L4:L6=L5/L7:BOTTOM=L7 |
| PCIE_RX_N81 | RXS81-DIFF1 | PAIR | 6 | 5.5 | 5 | 10 | 5 | 50 | 6 | 20 | 12 | 12 | 12 | 12 | 7.5 | 85 Ohms | TOP=L2:L3=L2/L4:L6=L5/L7:BOTTOM=L7 |
| PCIE_RX_N81 | RXS81-DIFF1 | PAIR | 7 | 5.5 | 5 | 10 | 5 | 50 | 6 | 20 | 12 | 12 | 12 | 12 | 7.5 | 85 Ohms | TOP=L2:L3=L2/L4:L6=L5/L7:BOTTOM=L7 |
| PCIE_RX_N81 | RXS81-DIFF1 | PAIR | 8 | 5.38 | 5 | 10 | 5 | 50 | 6 | 33 | 12 | 12 | 12 | 12 | 6.62 | 85 Ohms | TOP=L2:L3=L2/L4:L6=L5/L7:BOTTOM=L7 |
| PCIE_RX_P81 | RXS81-DIFF1 | PAIR | 1 | 5.38 | 5 | 10 | 5 | 50 | 6 | 33 | 12 | 12 | 12 | 12 | 6.62 | 85 Ohms | TOP=L2:L3=L2/L4:L6=L5/L7:BOTTOM=L7 |
| PCIE_RX_P81 | RXS81-DIFF1 | PAIR | 2 | 5.5 | 5 | 10 | 5 | 50 | 6 | 20 | 12 | 12 | 12 | 12 | 7.5 | 85 Ohms | TOP=L2:L3=L2/L4:L6=L5/L7:BOTTOM=L7 |
| PCIE_RX_P81 | RXS81-DIFF1 | PAIR | 3 | 5.5 | 5 | 10 | 5 | 50 | 6 | 20 | 12 | 12 | 12 | 12 | 7.5 | 85 Ohms | TOP=L2:L3=L2/L4:L6=L5/L7:BOTTOM=L7 |
| PCIE_RX_P81 | RXS81-DIFF1 | PAIR | 4 | 5.5 | 5 | 10 | 5 | 50 | 6 | 20 | 12 | 12 | 12 | 12 | 7.5 | 85 Ohms | TOP=L2:L3=L2/L4:L6=L5/L7:BOTTOM=L7 |
| PCIE_RX_P81 | RXS81-DIFF1 | PAIR | 5 | 5.5 | 5 | 10 | 5 | 50 | 6 | 20 | 12 | 12 | 12 | 12 | 7.5 | 85 Ohms | TOP=L2:L3=L2/L4:L6=L5/L7:BOTTOM=L7 |
| PCIE_RX_P81 | RXS81-DIFF1 | PAIR | 6 | 5.5 | 5 | 10 | 5 | 50 | 6 | 20 | 12 | 12 | 12 | 12 | 7.5 | 85 Ohms | TOP=L2:L3=L2/L4:L6=L5/L7:BOTTOM=L7 |
| PCIE_RX_P81 | RXS81-DIFF1 | PAIR | 7 | 5.5 | 5 | 10 | 5 | 50 | 6 | 20 | 12 | 12 | 12 | 12 | 7.5 | 85 Ohms | TOP=L2:L3=L2/L4:L6=L5/L7:BOTTOM=L7 |
| PCIE_RX_P81 | RXS81-DIFF1 | PAIR | 8 | 5.38 | 5 | 10 | 5 | 50 | 6 | 33 | 12 | 12 | 12 | 12 | 6.62 | 85 Ohms | TOP=L2:L3=L2/L4:L6=L5/L7:BOTTOM=L7 |
| PCIE_RX_N83 | RXS83-DIFF1 | PAIR | 1 | 5.38 | 5 | 10 | 5 | 50 | 6 | 33 | 12 | 12 | 12 | 12 | 6.62 | 85 Ohms | TOP=L2:L3=L2/L4:L6=L5/L7:BOTTOM=L7 |
| PCIE_RX_N83 | RXS83-DIFF1 | PAIR | 2 | 5.5 | 5 | 10 | 5 | 50 | 6 | 20 | 12 | 12 | 12 | 12 | 7.5 | 85 Ohms | TOP=L2:L3=L2/L4:L6=L5/L7:BOTTOM=L7 |
| PCIE_RX_N83 | RXS83-DIFF1 | PAIR | 3 | 5.5 | 5 | 10 | 5 | 50 | 6 | 20 | 12 | 12 | 12 | 12 | 7.5 | 85 Ohms | TOP=L2:L3=L2/L4:L6=L5/L7:BOTTOM=L7 |
| PCIE_RX_N83 | RXS83-DIFF1 | PAIR | 4 | 5.5 | 5 | 10 | 5 | 50 | 6 | 20 | 12 | 12 | 12 | 12 | 7.5 | 85 Ohms | TOP=L2:L3=L2/L4:L6=L5/L7:BOTTOM=L7 |
| PCIE_RX_N83 | RXS83-DIFF1 | PAIR | 5 | 5.5 | 5 | 10 | 5 | 50 | 6 | 20 | 12 | 12 | 12 | 12 | 7.5 | 85 Ohms | TOP=L2:L3=L2/L4:L6=L5/L7:BOTTOM=L7 |
| PCIE_RX_N83 | RXS83-DIFF1 | PAIR | 6 | 5.5 | 5 | 10 | 5 | 50 | 6 | 20 | 12 | 12 | 12 | 12 | 7.5 | 85 Ohms | TOP=L2:L3=L2/L4:L6=L5/L7:BOTTOM=L7 |
| PCIE_RX_N83 | RXS83-DIFF1 | PAIR | 7 | 5.5 | 5 | 10 | 5 | 50 | 6 | 20 | 12 | 12 | 12 | 12 | 7.5 | 85 Ohms | TOP=L2:L3=L2/L4:L6=L5/L7:BOTTOM=L7 |
| PCIE_RX_N83 | RXS83-DIFF1 | PAIR | 8 | 5.38 | 5 | 10 | 5 | 50 | 6 | 33 | 12 | 12 | 12 | 12 | 6.62 | 85 Ohms | TOP=L2:L3=L2/L4:L6=L5/L7:BOTTOM=L7 |
| PCIE_RX_P83 | RXS83-DIFF1 | PAIR | 1 | 5.38 | 5 | 10 | 5 | 50 | 6 | 33 | 12 | 12 | 12 | 12 | 6.62 | 85 Ohms | TOP=L2:L3=L2/L4:L6=L5/L7:BOTTOM=L7 |
| PCIE_RX_P83 | RXS83-DIFF1 | PAIR | 2 | 5.5 | 5 | 10 | 5 | 50 | 6 | 20 | 12 | 12 | 12 | 12 | 7.5 | 85 Ohms | TOP=L2:L3=L2/L4:L6=L5/L7:BOTTOM=L7 |
| PCIE_RX_P83 | RXS83-DIFF1 | PAIR | 3 | 5.5 | 5 | 10 | 5 | 50 | 6 | 20 | 12 | 12 | 12 | 12 | 7.5 | 85 Ohms | TOP=L2:L3=L2/L4:L6=L5/L7:BOTTOM=L7 |
| PCIE_RX_P83 | RXS83-DIFF1 | PAIR | 4 | 5.5 | 5 | 10 | 5 | 50 | 6 | 20 | 12 | 12 | 12 | 12 | 7.5 | 85 Ohms | TOP=L2:L3=L2/L4:L6=L5/L7:BOTTOM=L7 |
| PCIE_RX_P83 | RXS83-DIFF1 | PAIR | 5 | 5.5 | 5 | 10 | 5 | 50 | 6 | 20 | 12 | 12 | 12 | 12 | 7.5 | 85 Ohms | TOP=L2:L3=L2/L4:L6=L5/L7:BOTTOM=L7 |
| PCIE_RX_P83 | RXS83-DIFF1 | PAIR | 6 | 5.5 | 5 | 10 | 5 | 50 | 6 | 20 | 12 | 12 | 12 | 12 | 7.5 | 85 Ohms | TOP=L2:L3=L2/L4:L6=L5/L7:BOTTOM=L7 |
| PCIE_RX_P83 | RXS83-DIFF1 | PAIR | 7 | 5.5 | 5 | 10 | 5 | 50 | 6 | 20 | 12 | 12 | 12 | 12 | 7.5 | 85 Ohms | TOP=L2:L3=L2/L4:L6=L5/L7:BOTTOM=L7 |
| PCIE_RX_P83 | RXS83-DIFF1 | PAIR | 8 | 5.38 | 5 | 10 | 5 | 50 | 6 | 33 | 12 | 12 | 12 | 12 | 6.62 | 85 Ohms | TOP=L2:L3=L2/L4:L6=L5/L7:BOTTOM=L7 |
| PCIE_RX_N84 | RXS84-DIFF1 | PAIR | 1 | 5.38 | 5 | 10 | 5 | 50 | 6 | 33 | 12 | 12 | 12 | 12 | 6.62 | 85 Ohms | TOP=L2:L3=L2/L4:L6=L5/L7:BOTTOM=L7 |
| PCIE_RX_N84 | RXS84-DIFF1 | PAIR | 2 | 5.5 | 5 | 10 | 5 | 50 | 6 | 20 | 12 | 12 | 12 | 12 | 7.5 | 85 Ohms | TOP=L2:L3=L2/L4:L6=L5/L7:BOTTOM=L7 |
| PCIE_RX_N84 | RXS84-DIFF1 | PAIR | 3 | 5.5 | 5 | 10 | 5 | 50 | 6 | 20 | 12 | 12 | 12 | 12 | 7.5 | 85 Ohms | TOP=L2:L3=L2/L4:L6=L5/L7:BOTTOM=L7 |
| PCIE_RX_N84 | RXS84-DIFF1 | PAIR | 4 | 5.5 | 5 | 10 | 5 | 50 | 6 | 20 | 12 | 12 | 12 | 12 | 7.5 | 85 Ohms | TOP=L2:L3=L2/L4:L6=L5/L7:BOTTOM=L7 |
| PCIE_RX_N84 | RXS84-DIFF1 | PAIR | 5 | 5.5 | 5 | 10 | 5 | 50 | 6 | 20 | 12 | 12 | 12 | 12 | 7.5 | 85 Ohms | TOP=L2:L3=L2/L4:L6=L5/L7:BOTTOM=L7 |
| PCIE_RX_N84 | RXS84-DIFF1 | PAIR | 6 | 5.5 | 5 | 10 | 5 | 50 | 6 | 20 | 12 | 12 | 12 | 12 | 7.5 | 85 Ohms | TOP=L2:L3=L2/L4:L6=L5/L7:BOTTOM=L7 |
| PCIE_RX_N84 | RXS84-DIFF1 | PAIR | 7 | 5.5 | 5 | 10 | 5 | 50 | 6 | 20 | 12 | 12 | 12 | 12 | 7.5 | 85 Ohms | TOP=L2:L3=L2/L4:L6=L5/L7:BOTTOM=L7 |
| PCIE_RX_N84 | RXS84-DIFF1 | PAIR | 8 | 5.38 | 5 | 10 | 5 | 50 | 6 | 33 | 12 | 12 | 12 | 12 | 6.62 | 85 Ohms | TOP=L2:L3=L2/L4:L6=L5/L7:BOTTOM=L7 |
| PCIE_RX_P84 | RXS84-DIFF1 | PAIR | 1 | 5.38 | 5 | 10 | 5 | 50 | 6 | 33 | 12 | 12 | 12 | 12 | 6.62 | 85 Ohms | TOP=L2:L3=L2/L4:L6=L5/L7:BOTTOM=L7 |
| PCIE_RX_P84 | RXS84-DIFF1 | PAIR | 2 | 5.5 | 5 | 10 | 5 | 50 | 6 | 20 | 12 | 12 | 12 | 12 | 7.5 | 85 Ohms | TOP=L2:L3=L2/L4:L6=L5/L7:BOTTOM=L7 |
| PCIE_RX_P84 | RXS84-DIFF1 | PAIR | 3 | 5.5 | 5 | 10 | 5 | 50 | 6 | 20 | 12 | 12 | 12 | 12 | 7.5 | 85 Ohms | TOP=L2:L3=L2/L4:L6=L5/L7:BOTTOM=L7 |
| PCIE_RX_P84 | RXS84-DIFF1 | PAIR | 4 | 5.5 | 5 | 10 | 5 | 50 | 6 | 20 | 12 | 12 | 12 | 12 | 7.5 | 85 Ohms | TOP=L2:L3=L2/L4:L6=L5/L7:BOTTOM=L7 |
| PCIE_RX_P84 | RXS84-DIFF1 | PAIR | 5 | 5.5 | 5 | 10 | 5 | 50 | 6 | 20 | 12 | 12 | 12 | 12 | 7.5 | 85 Ohms | TOP=L2:L3=L2/L4:L6=L5/L7:BOTTOM=L7 |
| PCIE_RX_P84 | RXS84-DIFF1 | PAIR | 6 | 5.5 | 5 | 10 | 5 | 50 | 6 | 20 | 12 | 12 | 12 | 12 | 7.5 | 85 Ohms | TOP=L2:L3=L2/L4:L6=L5/L7:BOTTOM=L7 |
| PCIE_RX_P84 | RXS84-DIFF1 | PAIR | 7 | 5.5 | 5 | 10 | 5 | 50 | 6 | 20 | 12 | 12 | 12 | 12 | 7.5 | 85 Ohms | TOP=L2:L3=L2/L4:L6=L5/L7:BOTTOM=L7 |
| PCIE_RX_P84 | RXS84-DIFF1 | PAIR | 8 | 5.38 | 5 | 10 | 5 | 50 | 6 | 33 | 12 | 12 | 12 | 12 | 6.62 | 85 Ohms | TOP=L2:L3=L2/L4:L6=L5/L7:BOTTOM=L7 |
| PCIE_RX_N85 | RXS85-DIFF1 | PAIR | 1 | 5.38 | 5 | 10 | 5 | 50 | 6 | 33 | 12 | 12 | 12 | 12 | 6.62 | 85 Ohms | TOP=L2:L3=L2/L4:L6=L5/L7:BOTTOM=L7 |
| PCIE_RX_N85 | RXS85-DIFF1 | PAIR | 2 | 5.5 | 5 | 10 | 5 | 50 | 6 | 20 | 12 | 12 | 12 | 12 | 7.5 | 85 Ohms | TOP=L2:L3=L2/L4:L6=L5/L7:BOTTOM=L7 |
| PCIE_RX_N85 | RXS85-DIFF1 | PAIR | 3 | 5.5 | 5 | 10 | 5 | 50 | 6 | 20 | 12 | 12 | 12 | 12 | 7.5 | 85 Ohms | TOP=L2:L3=L2/L4:L6=L5/L7:BOTTOM=L7 |
| PCIE_RX_N85 | RXS85-DIFF1 | PAIR | 4 | 5.5 | 5 | 10 | 5 | 50 | 6 | 20 | 12 | 12 | 12 | 12 | 7.5 | 85 Ohms | TOP=L2:L3=L2/L4:L6=L5/L7:BOTTOM=L7 |
| PCIE_RX_N85 | RXS85-DIFF1 | PAIR | 5 | 5.5 | 5 | 10 | 5 | 50 | 6 | 20 | 12 | 12 | 12 | 12 | 7.5 | 85 Ohms | TOP=L2:L3=L2/L4:L6=L5/L7:BOTTOM=L7 |
| PCIE_RX_N85 | RXS85-DIFF1 | PAIR | 6 | 5.5 | 5 | 10 | 5 | 50 | 6 | 20 | 12 | 12 | 12 | 12 | 7.5 | 85 Ohms | TOP=L2:L3=L2/L4:L6=L5/L7:BOTTOM=L7 |
| PCIE_RX_N85 | RXS85-DIFF1 | PAIR | 7 | 5.5 | 5 | 10 | 5 | 50 | 6 | 20 | 12 | 12 | 12 | 12 | 7.5 | 85 Ohms | TOP=L2:L3=L2/L4:L6=L5/L7:BOTTOM=L7 |
| PCIE_RX_N85 | RXS85-DIFF1 | PAIR | 8 | 5.38 | 5 | 10 | 5 | 50 | 6 | 33 | 12 | 12 | 12 | 12 | 6.62 | 85 Ohms | TOP=L2:L3=L2/L4:L6=L5/L7:BOTTOM=L7 |
| PCIE_RX_P85 | RXS85-DIFF1 | PAIR | 1 | 5.38 | 5 | 10 | 5 | 50 | 6 | 33 | 12 | 12 | 12 | 12 | 6.62 | 85 Ohms | TOP=L2:L3=L2/L4:L6=L5/L7:BOTTOM=L7 |
| PCIE_RX_P85 | RXS85-DIFF1 | PAIR | 2 | 5.5 | 5 | 10 | 5 | 50 | 6 | 20 | 12 | 12 | 12 | 12 | 7.5 | 85 Ohms | TOP=L2:L3=L2/L4:L6=L5/L7:BOTTOM=L7 |
| PCIE_RX_P85 | RXS85-DIFF1 | PAIR | 3 | 5.5 | 5 | 10 | 5 | 50 | 6 | 20 | 12 | 12 | 12 | 12 | 7.5 | 85 Ohms | TOP=L2:L3=L2/L4:L6=L5/L7:BOTTOM=L7 |
| PCIE_RX_P85 | RXS85-DIFF1 | PAIR | 4 | 5.5 | 5 | 10 | 5 | 50 | 6 | 20 | 12 | 12 | 12 | 12 | 7.5 | 85 Ohms | TOP=L2:L3=L2/L4:L6=L5/L7:BOTTOM=L7 |
| PCIE_RX_P85 | RXS85-DIFF1 | PAIR | 5 | 5.5 | 5 | 10 | 5 | 50 | 6 | 20 | 12 | 12 | 12 | 12 | 7.5 | 85 Ohms | TOP=L2:L3=L2/L4:L6=L5/L7:BOTTOM=L7 |
| PCIE_RX_P85 | RXS85-DIFF1 | PAIR | 6 | 5.5 | 5 | 10 | 5 | 50 | 6 | 20 | 12 | 12 | 12 | 12 | 7.5 | 85 Ohms | TOP=L2:L3=L2/L4:L6=L5/L7:BOTTOM=L7 |
| PCIE_RX_P85 | RXS85-DIFF1 | PAIR | 7 | 5.5 | 5 | 10 | 5 | 50 | 6 | 20 | 12 | 12 | 12 | 12 | 7.5 | 85 Ohms | TOP=L2:L3=L2/L4:L6=L5/L7:BOTTOM=L7 |
| PCIE_RX_P85 | RXS85-DIFF1 | PAIR | 8 | 5.38 | 5 | 10 | 5 | 50 | 6 | 33 | 12 | 12 | 12 | 12 | 6.62 | 85 Ohms | TOP=L2:L3=L2/L4:L6=L5/L7:BOTTOM=L7 |
| PCIE_RX_N86 | RXS86-DIFF1 | PAIR | 1 | 5.38 | 5 | 10 | 5 | 50 | 6 | 33 | 12 | 12 | 12 | 12 | 6.62 | 85 Ohms | TOP=L2:L3=L2/L4:L6=L5/L7:BOTTOM=L7 |
| PCIE_RX_N86 | RXS86-DIFF1 | PAIR | 2 | 5.5 | 5 | 10 | 5 | 50 | 6 | 20 | 12 | 12 | 12 | 12 | 7.5 | 85 Ohms | TOP=L2:L3=L2/L4:L6=L5/L7:BOTTOM=L7 |
| PCIE_RX_N86 | RXS86-DIFF1 | PAIR | 3 | 5.5 | 5 | 10 | 5 | 50 | 6 | 20 | 12 | 12 | 12 | 12 | 7.5 | 85 Ohms | TOP=L2:L3=L2/L4:L6=L5/L7:BOTTOM=L7 |
| PCIE_RX_N86 | RXS86-DIFF1 | PAIR | 4 | 5.5 | 5 | 10 | 5 | 50 | 6 | 20 | 12 | 12 | 12 | 12 | 7.5 | 85 Ohms | TOP=L2:L3=L2/L4:L6=L5/L7:BOTTOM=L7 |
| PCIE_RX_N86 | RXS86-DIFF1 | PAIR | 5 | 5.5 | 5 | 10 | 5 | 50 | 6 | 20 | 12 | 12 | 12 | 12 | 7.5 | 85 Ohms | TOP=L2:L3=L2/L4:L6=L5/L7:BOTTOM=L7 |
| PCIE_RX_N86 | RXS86-DIFF1 | PAIR | 6 | 5.5 | 5 | 10 | 5 | 50 | 6 | 20 | 12 | 12 | 12 | 12 | 7.5 | 85 Ohms | TOP=L2:L3=L2/L4:L6=L5/L7:BOTTOM=L7 |
| PCIE_RX_N86 | RXS86-DIFF1 | PAIR | 7 | 5.5 | 5 | 10 | 5 | 50 | 6 | 20 | 12 | 12 | 12 | 12 | 7.5 | 85 Ohms | TOP=L2:L3=L2/L4:L6=L5/L7:BOTTOM=L7 |
| PCIE_RX_N86 | RXS86-DIFF1 | PAIR | 8 | 5.38 | 5 | 10 | 5 | 50 | 6 | 33 | 12 | 12 | 12 | 12 | 6.62 | 85 Ohms | TOP=L2:L3=L2/L4:L6=L5/L7:BOTTOM=L7 |
| PCIE_RX_P86 | RXS86-DIFF1 | PAIR | 1 | 5.38 | 5 | 10 | 5 | 50 | 6 | 33 | 12 | 12 | 12 | 12 | 6.62 | 85 Ohms | TOP=L2:L3=L2/L4:L6=L5/L7:BOTTOM=L7 |
| PCIE_RX_P86 | RXS86-DIFF1 | PAIR | 2 | 5.5 | 5 | 10 | 5 | 50 | 6 | 20 | 12 | 12 | 12 | 12 | 7.5 | 85 Ohms | TOP=L2:L3=L2/L4:L6=L5/L7:BOTTOM=L7 |
| PCIE_RX_P86 | RXS86-DIFF1 | PAIR | 3 | 5.5 | 5 | 10 | 5 | 50 | 6 | 20 | 12 | 12 | 12 | 12 | 7.5 | 85 Ohms | TOP=L2:L3=L2/L4:L6=L5/L7:BOTTOM=L7 |
| PCIE_RX_P86 | RXS86-DIFF1 | PAIR | 4 | 5.5 | 5 | 10 | 5 | 50 | 6 | 20 | 12 | 12 | 12 | 12 | 7.5 | 85 Ohms | TOP=L2:L3=L2/L4:L6=L5/L7:BOTTOM=L7 |
| PCIE_RX_P86 | RXS86-DIFF1 | PAIR | 5 | 5.5 | 5 | 10 | 5 | 50 | 6 | 20 | 12 | 12 | 12 | 12 | 7.5 | 85 Ohms | TOP=L2:L3=L2/L4:L6=L5/L7:BOTTOM=L7 |
| PCIE_RX_P86 | RXS86-DIFF1 | PAIR | 6 | 5.5 | 5 | 10 | 5 | 50 | 6 | 20 | 12 | 12 | 12 | 12 | 7.5 | 85 Ohms | TOP=L2:L3=L2/L4:L6=L5/L7:BOTTOM=L7 |
| PCIE_RX_P86 | RXS86-DIFF1 | PAIR | 7 | 5.5 | 5 | 10 | 5 | 50 | 6 | 20 | 12 | 12 | 12 | 12 | 7.5 | 85 Ohms | TOP=L2:L3=L2/L4:L6=L5/L7:BOTTOM=L7 |
| PCIE_RX_P86 | RXS86-DIFF1 | PAIR | 8 | 5.38 | 5 | 10 | 5 | 50 | 6 | 33 | 12 | 12 | 12 | 12 | 6.62 | 85 Ohms | TOP=L2:L3=L2/L4:L6=L5/L7:BOTTOM=L7 |
| PCIE_RX_N87 | RXS87-DIFF1 | PAIR | 1 | 5.38 | 5 | 10 | 5 | 50 | 6 | 33 | 12 | 12 | 12 | 12 | 6.62 | 85 Ohms | TOP=L2:L3=L2/L4:L6=L5/L7:BOTTOM=L7 |
| PCIE_RX_N87 | RXS87-DIFF1 | PAIR | 2 | 5.5 | 5 | 10 | 5 | 50 | 6 | 20 | 12 | 12 | 12 | 12 | 7.5 | 85 Ohms | TOP=L2:L3=L2/L4:L6=L5/L7:BOTTOM=L7 |
| PCIE_RX_N87 | RXS87-DIFF1 | PAIR | 3 | 5.5 | 5 | 10 | 5 | 50 | 6 | 20 | 12 | 12 | 12 | 12 | 7.5 | 85 Ohms | TOP=L2:L3=L2/L4:L6=L5/L7:BOTTOM=L7 |
| PCIE_RX_N87 | RXS87-DIFF1 | PAIR | 4 | 5.5 | 5 | 10 | 5 | 50 | 6 | 20 | 12 | 12 | 12 | 12 | 7.5 | 85 Ohms | TOP=L2:L3=L2/L4:L6=L5/L7:BOTTOM=L7 |
| PCIE_RX_N87 | RXS87-DIFF1 | PAIR | 5 | 5.5 | 5 | 10 | 5 | 50 | 6 | 20 | 12 | 12 | 12 | 12 | 7.5 | 85 Ohms | TOP=L2:L3=L2/L4:L6=L5/L7:BOTTOM=L7 |
| PCIE_RX_N87 | RXS87-DIFF1 | PAIR | 6 | 5.5 | 5 | 10 | 5 | 50 | 6 | 20 | 12 | 12 | 12 | 12 | 7.5 | 85 Ohms | TOP=L2:L3=L2/L4:L6=L5/L7:BOTTOM=L7 |
| PCIE_RX_N87 | RXS87-DIFF1 | PAIR | 7 | 5.5 | 5 | 10 | 5 | 50 | 6 | 20 | 12 | 12 | 12 | 12 | 7.5 | 85 Ohms | TOP=L2:L3=L2/L4:L6=L5/L7:BOTTOM=L7 |
| PCIE_RX_N87 | RXS87-DIFF1 | PAIR | 8 | 5.38 | 5 | 10 | 5 | 50 | 6 | 33 | 12 | 12 | 12 | 12 | 6.62 | 85 Ohms | TOP=L2:L3=L2/L4:L6=L5/L7:BOTTOM=L7 |
| PCIE_RX_P87 | RXS87-DIFF1 | PAIR | 1 | 5.38 | 5 | 10 | 5 | 50 | 6 | 33 | 12 | 12 | 12 | 12 | 6.62 | 85 Ohms | TOP=L2:L3=L2/L4:L6=L5/L7:BOTTOM=L7 |
| PCIE_RX_P87 | RXS87-DIFF1 | PAIR | 2 | 5.5 | 5 | 10 | 5 | 50 | 6 | 20 | 12 | 12 | 12 | 12 | 7.5 | 85 Ohms | TOP=L2:L3=L2/L4:L6=L5/L7:BOTTOM=L7 |
| PCIE_RX_P87 | RXS87-DIFF1 | PAIR | 3 | 5.5 | 5 | 10 | 5 | 50 | 6 | 20 | 12 | 12 | 12 | 12 | 7.5 | 85 Ohms | TOP=L2:L3=L2/L4:L6=L5/L7:BOTTOM=L7 |
| PCIE_RX_P87 | RXS87-DIFF1 | PAIR | 4 | 5.5 | 5 | 10 | 5 | 50 | 6 | 20 | 12 | 12 | 12 | 12 | 7.5 | 85 Ohms | TOP=L2:L3=L2/L4:L6=L5/L7:BOTTOM=L7 |
| PCIE_RX_P87 | RXS87-DIFF1 | PAIR | 5 | 5.5 | 5 | 10 | 5 | 50 | 6 | 20 | 12 | 12 | 12 | 12 | 7.5 | 85 Ohms | TOP=L2:L3=L2/L4:L6=L5/L7:BOTTOM=L7 |
| PCIE_RX_P87 | RXS87-DIFF1 | PAIR | 6 | 5.5 | 5 | 10 | 5 | 50 | 6 | 20 | 12 | 12 | 12 | 12 | 7.5 | 85 Ohms | TOP=L2:L3=L2/L4:L6=L5/L7:BOTTOM=L7 |
| PCIE_RX_P87 | RXS87-DIFF1 | PAIR | 7 | 5.5 | 5 | 10 | 5 | 50 | 6 | 20 | 12 | 12 | 12 | 12 | 7.5 | 85 Ohms | TOP=L2:L3=L2/L4:L6=L5/L7:BOTTOM=L7 |
| PCIE_RX_P87 | RXS87-DIFF1 | PAIR | 8 | 5.38 | 5 | 10 | 5 | 50 | 6 | 33 | 12 | 12 | 12 | 12 | 6.62 | 85 Ohms | TOP=L2:L3=L2/L4:L6=L5/L7:BOTTOM=L7 |
| PCIE_RX_N88 | RXS88-DIFF1 | PAIR | 1 | 5.38 | 5 | 10 | 5 | 50 | 6 | 33 | 12 | 12 | 12 | 12 | 6.62 | 85 Ohms | TOP=L2:L3=L2/L4:L6=L5/L7:BOTTOM=L7 |
| PCIE_RX_N88 | RXS88-DIFF1 | PAIR | 2 | 5.5 | 5 | 10 | 5 | 50 | 6 | 20 | 12 | 12 | 12 | 12 | 7.5 | 85 Ohms | TOP=L2:L3=L2/L4:L6=L5/L7:BOTTOM=L7 |
| PCIE_RX_N88 | RXS88-DIFF1 | PAIR | 3 | 5.5 | 5 | 10 | 5 | 50 | 6 | 20 | 12 | 12 | 12 | 12 | 7.5 | 85 Ohms | TOP=L2:L3=L2/L4:L6=L5/L7:BOTTOM=L7 |
| PCIE_RX_N88 | RXS88-DIFF1 | PAIR | 4 | 5.5 | 5 | 10 | 5 | 50 | 6 | 20 | 12 | 12 | 12 | 12 | 7.5 | 85 Ohms | TOP=L2:L3=L2/L4:L6=L5/L7:BOTTOM=L7 |
| PCIE_RX_N88 | RXS88-DIFF1 | PAIR | 5 | 5.5 | 5 | 10 | 5 | 50 | 6 | 20 | 12 | 12 | 12 | 12 | 7.5 | 85 Ohms | TOP=L2:L3=L2/L4:L6=L5/L7:BOTTOM=L7 |
| PCIE_RX_N88 | RXS88-DIFF1 | PAIR | 6 | 5.5 | 5 | 10 | 5 | 50 | 6 | 20 | 12 | 12 | 12 | 12 | 7.5 | 85 Ohms | TOP=L2:L3=L2/L4:L6=L5/L7:BOTTOM=L7 |
| PCIE_RX_N88 | RXS88-DIFF1 | PAIR | 7 | 5.5 | 5 | 10 | 5 | 50 | 6 | 20 | 12 | 12 | 12 | 12 | 7.5 | 85 Ohms | TOP=L2:L3=L2/L4:L6=L5/L7:BOTTOM=L7 |
| PCIE_RX_N88 | RXS88-DIFF1 | PAIR | 8 | 5.38 | 5 | 10 | 5 | 50 | 6 | 33 | 12 | 12 | 12 | 12 | 6.62 | 85 Ohms | TOP=L2:L3=L2/L4:L6=L5/L7:BOTTOM=L7 |
| PCIE_RX_P88 | RXS88-DIFF1 | PAIR | 1 | 5.38 | 5 | 10 | 5 | 50 | 6 | 33 | 12 | 12 | 12 | 12 | 6.62 | 85 Ohms | TOP=L2:L3=L2/L4:L6=L5/L7:BOTTOM=L7 |
| PCIE_RX_P88 | RXS88-DIFF1 | PAIR | 2 | 5.5 | 5 | 10 | 5 | 50 | 6 | 20 | 12 | 12 | 12 | 12 | 7.5 | 85 Ohms | TOP=L2:L3=L2/L4:L6=L5/L7:BOTTOM=L7 |
| PCIE_RX_P88 | RXS88-DIFF1 | PAIR | 3 | 5.5 | 5 | 10 | 5 | 50 | 6 | 20 | 12 | 12 | 12 | 12 | 7.5 | 85 Ohms | TOP=L2:L3=L2/L4:L6=L5/L7:BOTTOM=L7 |
| PCIE_RX_P88 | RXS88-DIFF1 | PAIR | 4 | 5.5 | 5 | 10 | 5 | 50 | 6 | 20 | 12 | 12 | 12 | 12 | 7.5 | 85 Ohms | TOP=L2:L3=L2/L4:L6=L5/L7:BOTTOM=L7 |
| PCIE_RX_P88 | RXS88-DIFF1 | PAIR | 5 | 5.5 | 5 | 10 | 5 | 50 | 6 | 20 | 12 | 12 | 12 | 12 | 7.5 | 85 Ohms | TOP=L2:L3=L2/L4:L6=L5/L7:BOTTOM=L7 |
| PCIE_RX_P88 | RXS88-DIFF1 | PAIR | 6 | 5.5 | 5 | 10 | 5 | 50 | 6 | 20 | 12 | 12 | 12 | 12 | 7.5 | 85 Ohms | TOP=L2:L3=L2/L4:L6=L5/L7:BOTTOM=L7 |
| PCIE_RX_P88 | RXS88-DIFF1 | PAIR | 7 | 5.5 | 5 | 10 | 5 | 50 | 6 | 20 | 12 | 12 | 12 | 12 | 7.5 | 85 Ohms | TOP=L2:L3=L2/L4:L6=L5/L7:BOTTOM=L7 |
| PCIE_RX_P88 | RXS88-DIFF1 | PAIR | 8 | 5.38 | 5 | 10 | 5 | 50 | 6 | 33 | 12 | 12 | 12 | 12 | 6.62 | 85 Ohms | TOP=L2:L3=L2/L4:L6=L5/L7:BOTTOM=L7 |
| PCIE_RX_N89 | RXS89-DIFF1 | PAIR | 1 | 5.38 | 5 | 10 | 5 | 50 | 6 | 33 | 12 | 12 | 12 | 12 | 6.62 | 85 Ohms | TOP=L2:L3=L2/L4:L6=L5/L7:BOTTOM=L7 |
| PCIE_RX_N89 | RXS89-DIFF1 | PAIR | 2 | 5.5 | 5 | 10 | 5 | 50 | 6 | 20 | 12 | 12 | 12 | 12 | 7.5 | 85 Ohms | TOP=L2:L3=L2/L4:L6=L5/L7:BOTTOM=L7 |
| PCIE_RX_N89 | RXS89-DIFF1 | PAIR | 3 | 5.5 | 5 | 10 | 5 | 50 | 6 | 20 | 12 | 12 | 12 | 12 | 7.5 | 85 Ohms | TOP=L2:L3=L2/L4:L6=L5/L7:BOTTOM=L7 |
| PCIE_RX_N89 | RXS89-DIFF1 | PAIR | 4 | 5.5 | 5 | 10 | 5 | 50 | 6 | 20 | 12 | 12 | 12 | 12 | 7.5 | 85 Ohms | TOP=L2:L3=L2/L4:L6=L5/L7:BOTTOM=L7 |
| PCIE_RX_N89 | RXS89-DIFF1 | PAIR | 5 | 5.5 | 5 | 10 | 5 | 50 | 6 | 20 | 12 | 12 | 12 | 12 | 7.5 | 85 Ohms | TOP=L2:L3=L2/L4:L6=L5/L7:BOTTOM=L7 |
| PCIE_RX_N89 | RXS89-DIFF1 | PAIR | 6 | 5.5 | 5 | 10 | 5 | 50 | 6 | 20 | 12 | 12 | 12 | 12 | 7.5 | 85 Ohms | TOP=L2:L3=L2/L4:L6=L5/L7:BOTTOM=L7 |
| PCIE_RX_N89 | RXS89-DIFF1 | PAIR | 7 | 5.5 | 5 | 10 | 5 | 50 | 6 | 20 | 12 | 12 | 12 | 12 | 7.5 | 85 Ohms | TOP=L2:L3=L2/L4:L6=L5/L7:BOTTOM=L7 |
| PCIE_RX_N89 | RXS89-DIFF1 | PAIR | 8 | 5.38 | 5 | 10 | 5 | 50 | 6 | 33 | 12 | 12 | 12 | 12 | 6.62 | 85 Ohms | TOP=L2:L3=L2/L4:L6=L5/L7:BOTTOM=L7 |
| PCIE_RX_P89 | RXS89-DIFF1 | PAIR | 1 | 5.38 | 5 | 10 | 5 | 50 | 6 | 33 | 12 | 12 | 12 | 12 | 6.62 | 85 Ohms | TOP=L2:L3=L2/L4:L6=L5/L7:BOTTOM=L7 |
| PCIE_RX_P89 | RXS89-DIFF1 | PAIR | 2 | 5.5 | 5 | 10 | 5 | 50 | 6 | 20 | 12 | 12 | 12 | 12 | 7.5 | 85 Ohms | TOP=L2:L3=L2/L4:L6=L5/L7:BOTTOM=L7 |
| PCIE_RX_P89 | RXS89-DIFF1 | PAIR | 3 | 5.5 | 5 | 10 | 5 | 50 | 6 | 20 | 12 | 12 | 12 | 12 | 7.5 | 85 Ohms | TOP=L2:L3=L2/L4:L6=L5/L7:BOTTOM=L7 |
| PCIE_RX_P89 | RXS89-DIFF1 | PAIR | 4 | 5.5 | 5 | 10 | 5 | 50 | 6 | 20 | 12 | 12 | 12 | 12 | 7.5 | 85 Ohms | TOP=L2:L3=L2/L4:L6=L5/L7:BOTTOM=L7 |
| PCIE_RX_P89 | RXS89-DIFF1 | PAIR | 5 | 5.5 | 5 | 10 | 5 | 50 | 6 | 20 | 12 | 12 | 12 | 12 | 7.5 | 85 Ohms | TOP=L2:L3=L2/L4:L6=L5/L7:BOTTOM=L7 |
| PCIE_RX_P89 | RXS89-DIFF1 | PAIR | 6 | 5.5 | 5 | 10 | 5 | 50 | 6 | 20 | 12 | 12 | 12 | 12 | 7.5 | 85 Ohms | TOP=L2:L3=L2/L4:L6=L5/L7:BOTTOM=L7 |
| PCIE_RX_P89 | RXS89-DIFF1 | PAIR | 7 | 5.5 | 5 | 10 | 5 | 50 | 6 | 20 | 12 | 12 | 12 | 12 | 7.5 | 85 Ohms | TOP=L2:L3=L2/L4:L6=L5/L7:BOTTOM=L7 |
| PCIE_RX_P89 | RXS89-DIFF1 | PAIR | 8 | 5.38 | 5 | 10 | 5 | 50 | 6 | 33 | 12 | 12 | 12 | 12 | 6.62 | 85 Ohms | TOP=L2:L3=L2/L4:L6=L5/L7:BOTTOM=L7 |
| PCIE_RX_N8 | RXS8-DIFF1 | PAIR | 1 | 5.38 | 5 | 10 | 5 | 50 | 6 | 33 | 12 | 12 | 12 | 12 | 6.62 | 85 Ohms | TOP=L2:L3=L2/L4:L6=L5/L7:BOTTOM=L7 |
| PCIE_RX_N8 | RXS8-DIFF1 | PAIR | 2 | 5.5 | 5 | 10 | 5 | 50 | 6 | 20 | 12 | 12 | 12 | 12 | 7.5 | 85 Ohms | TOP=L2:L3=L2/L4:L6=L5/L7:BOTTOM=L7 |
| PCIE_RX_N8 | RXS8-DIFF1 | PAIR | 3 | 5.5 | 5 | 10 | 5 | 50 | 6 | 20 | 12 | 12 | 12 | 12 | 7.5 | 85 Ohms | TOP=L2:L3=L2/L4:L6=L5/L7:BOTTOM=L7 |
| PCIE_RX_N8 | RXS8-DIFF1 | PAIR | 4 | 5.5 | 5 | 10 | 5 | 50 | 6 | 20 | 12 | 12 | 12 | 12 | 7.5 | 85 Ohms | TOP=L2:L3=L2/L4:L6=L5/L7:BOTTOM=L7 |
| PCIE_RX_N8 | RXS8-DIFF1 | PAIR | 5 | 5.5 | 5 | 10 | 5 | 50 | 6 | 20 | 12 | 12 | 12 | 12 | 7.5 | 85 Ohms | TOP=L2:L3=L2/L4:L6=L5/L7:BOTTOM=L7 |
| PCIE_RX_N8 | RXS8-DIFF1 | PAIR | 6 | 5.5 | 5 | 10 | 5 | 50 | 6 | 20 | 12 | 12 | 12 | 12 | 7.5 | 85 Ohms | TOP=L2:L3=L2/L4:L6=L5/L7:BOTTOM=L7 |
| PCIE_RX_N8 | RXS8-DIFF1 | PAIR | 7 | 5.5 | 5 | 10 | 5 | 50 | 6 | 20 | 12 | 12 | 12 | 12 | 7.5 | 85 Ohms | TOP=L2:L3=L2/L4:L6=L5/L7:BOTTOM=L7 |
| PCIE_RX_N8 | RXS8-DIFF1 | PAIR | 8 | 5.38 | 5 | 10 | 5 | 50 | 6 | 33 | 12 | 12 | 12 | 12 | 6.62 | 85 Ohms | TOP=L2:L3=L2/L4:L6=L5/L7:BOTTOM=L7 |
| PCIE_RX_P8 | RXS8-DIFF1 | PAIR | 1 | 5.38 | 5 | 10 | 5 | 50 | 6 | 33 | 12 | 12 | 12 | 12 | 6.62 | 85 Ohms | TOP=L2:L3=L2/L4:L6=L5/L7:BOTTOM=L7 |
| PCIE_RX_P8 | RXS8-DIFF1 | PAIR | 2 | 5.5 | 5 | 10 | 5 | 50 | 6 | 20 | 12 | 12 | 12 | 12 | 7.5 | 85 Ohms | TOP=L2:L3=L2/L4:L6=L5/L7:BOTTOM=L7 |
| PCIE_RX_P8 | RXS8-DIFF1 | PAIR | 3 | 5.5 | 5 | 10 | 5 | 50 | 6 | 20 | 12 | 12 | 12 | 12 | 7.5 | 85 Ohms | TOP=L2:L3=L2/L4:L6=L5/L7:BOTTOM=L7 |
| PCIE_RX_P8 | RXS8-DIFF1 | PAIR | 4 | 5.5 | 5 | 10 | 5 | 50 | 6 | 20 | 12 | 12 | 12 | 12 | 7.5 | 85 Ohms | TOP=L2:L3=L2/L4:L6=L5/L7:BOTTOM=L7 |
| PCIE_RX_P8 | RXS8-DIFF1 | PAIR | 5 | 5.5 | 5 | 10 | 5 | 50 | 6 | 20 | 12 | 12 | 12 | 12 | 7.5 | 85 Ohms | TOP=L2:L3=L2/L4:L6=L5/L7:BOTTOM=L7 |
| PCIE_RX_P8 | RXS8-DIFF1 | PAIR | 6 | 5.5 | 5 | 10 | 5 | 50 | 6 | 20 | 12 | 12 | 12 | 12 | 7.5 | 85 Ohms | TOP=L2:L3=L2/L4:L6=L5/L7:BOTTOM=L7 |
| PCIE_RX_P8 | RXS8-DIFF1 | PAIR | 7 | 5.5 | 5 | 10 | 5 | 50 | 6 | 20 | 12 | 12 | 12 | 12 | 7.5 | 85 Ohms | TOP=L2:L3=L2/L4:L6=L5/L7:BOTTOM=L7 |
| PCIE_RX_P8 | RXS8-DIFF1 | PAIR | 8 | 5.38 | 5 | 10 | 5 | 50 | 6 | 33 | 12 | 12 | 12 | 12 | 6.62 | 85 Ohms | TOP=L2:L3=L2/L4:L6=L5/L7:BOTTOM=L7 |
| PCIE_RX_N82 | RXS8-DIFF2 | PAIR | 1 | 5.38 | 5 | 10 | 5 | 50 | 6 | 33 | 12 | 12 | 12 | 12 | 6.62 | 85 Ohms | TOP=L2:L3=L2/L4:L6=L5/L7:BOTTOM=L7 |
| PCIE_RX_N82 | RXS8-DIFF2 | PAIR | 2 | 5.5 | 5 | 10 | 5 | 50 | 6 | 20 | 12 | 12 | 12 | 12 | 7.5 | 85 Ohms | TOP=L2:L3=L2/L4:L6=L5/L7:BOTTOM=L7 |
| PCIE_RX_N82 | RXS8-DIFF2 | PAIR | 3 | 5.5 | 5 | 10 | 5 | 50 | 6 | 20 | 12 | 12 | 12 | 12 | 7.5 | 85 Ohms | TOP=L2:L3=L2/L4:L6=L5/L7:BOTTOM=L7 |
| PCIE_RX_N82 | RXS8-DIFF2 | PAIR | 4 | 5.5 | 5 | 10 | 5 | 50 | 6 | 20 | 12 | 12 | 12 | 12 | 7.5 | 85 Ohms | TOP=L2:L3=L2/L4:L6=L5/L7:BOTTOM=L7 |
| PCIE_RX_N82 | RXS8-DIFF2 | PAIR | 5 | 5.5 | 5 | 10 | 5 | 50 | 6 | 20 | 12 | 12 | 12 | 12 | 7.5 | 85 Ohms | TOP=L2:L3=L2/L4:L6=L5/L7:BOTTOM=L7 |
| PCIE_RX_N82 | RXS8-DIFF2 | PAIR | 6 | 5.5 | 5 | 10 | 5 | 50 | 6 | 20 | 12 | 12 | 12 | 12 | 7.5 | 85 Ohms | TOP=L2:L3=L2/L4:L6=L5/L7:BOTTOM=L7 |
| PCIE_RX_N82 | RXS8-DIFF2 | PAIR | 7 | 5.5 | 5 | 10 | 5 | 50 | 6 | 20 | 12 | 12 | 12 | 12 | 7.5 | 85 Ohms | TOP=L2:L3=L2/L4:L6=L5/L7:BOTTOM=L7 |
| PCIE_RX_N82 | RXS8-DIFF2 | PAIR | 8 | 5.38 | 5 | 10 | 5 | 50 | 6 | 33 | 12 | 12 | 12 | 12 | 6.62 | 85 Ohms | TOP=L2:L3=L2/L4:L6=L5/L7:BOTTOM=L7 |
| PCIE_RX_P82 | RXS8-DIFF2 | PAIR | 1 | 5.38 | 5 | 10 | 5 | 50 | 6 | 33 | 12 | 12 | 12 | 12 | 6.62 | 85 Ohms | TOP=L2:L3=L2/L4:L6=L5/L7:BOTTOM=L7 |
| PCIE_RX_P82 | RXS8-DIFF2 | PAIR | 2 | 5.5 | 5 | 10 | 5 | 50 | 6 | 20 | 12 | 12 | 12 | 12 | 7.5 | 85 Ohms | TOP=L2:L3=L2/L4:L6=L5/L7:BOTTOM=L7 |
| PCIE_RX_P82 | RXS8-DIFF2 | PAIR | 3 | 5.5 | 5 | 10 | 5 | 50 | 6 | 20 | 12 | 12 | 12 | 12 | 7.5 | 85 Ohms | TOP=L2:L3=L2/L4:L6=L5/L7:BOTTOM=L7 |
| PCIE_RX_P82 | RXS8-DIFF2 | PAIR | 4 | 5.5 | 5 | 10 | 5 | 50 | 6 | 20 | 12 | 12 | 12 | 12 | 7.5 | 85 Ohms | TOP=L2:L3=L2/L4:L6=L5/L7:BOTTOM=L7 |
| PCIE_RX_P82 | RXS8-DIFF2 | PAIR | 5 | 5.5 | 5 | 10 | 5 | 50 | 6 | 20 | 12 | 12 | 12 | 12 | 7.5 | 85 Ohms | TOP=L2:L3=L2/L4:L6=L5/L7:BOTTOM=L7 |
| PCIE_RX_P82 | RXS8-DIFF2 | PAIR | 6 | 5.5 | 5 | 10 | 5 | 50 | 6 | 20 | 12 | 12 | 12 | 12 | 7.5 | 85 Ohms | TOP=L2:L3=L2/L4:L6=L5/L7:BOTTOM=L7 |
| PCIE_RX_P82 | RXS8-DIFF2 | PAIR | 7 | 5.5 | 5 | 10 | 5 | 50 | 6 | 20 | 12 | 12 | 12 | 12 | 7.5 | 85 Ohms | TOP=L2:L3=L2/L4:L6=L5/L7:BOTTOM=L7 |
| PCIE_RX_P82 | RXS8-DIFF2 | PAIR | 8 | 5.38 | 5 | 10 | 5 | 50 | 6 | 33 | 12 | 12 | 12 | 12 | 6.62 | 85 Ohms | TOP=L2:L3=L2/L4:L6=L5/L7:BOTTOM=L7 |
| PCIE_RX_N90 | RXS90-DIFF1 | PAIR | 1 | 5.38 | 5 | 10 | 5 | 50 | 6 | 33 | 12 | 12 | 12 | 12 | 6.62 | 85 Ohms | TOP=L2:L3=L2/L4:L6=L5/L7:BOTTOM=L7 |
| PCIE_RX_N90 | RXS90-DIFF1 | PAIR | 2 | 5.5 | 5 | 10 | 5 | 50 | 6 | 20 | 12 | 12 | 12 | 12 | 7.5 | 85 Ohms | TOP=L2:L3=L2/L4:L6=L5/L7:BOTTOM=L7 |
| PCIE_RX_N90 | RXS90-DIFF1 | PAIR | 3 | 5.5 | 5 | 10 | 5 | 50 | 6 | 20 | 12 | 12 | 12 | 12 | 7.5 | 85 Ohms | TOP=L2:L3=L2/L4:L6=L5/L7:BOTTOM=L7 |
| PCIE_RX_N90 | RXS90-DIFF1 | PAIR | 4 | 5.5 | 5 | 10 | 5 | 50 | 6 | 20 | 12 | 12 | 12 | 12 | 7.5 | 85 Ohms | TOP=L2:L3=L2/L4:L6=L5/L7:BOTTOM=L7 |
| PCIE_RX_N90 | RXS90-DIFF1 | PAIR | 5 | 5.5 | 5 | 10 | 5 | 50 | 6 | 20 | 12 | 12 | 12 | 12 | 7.5 | 85 Ohms | TOP=L2:L3=L2/L4:L6=L5/L7:BOTTOM=L7 |
| PCIE_RX_N90 | RXS90-DIFF1 | PAIR | 6 | 5.5 | 5 | 10 | 5 | 50 | 6 | 20 | 12 | 12 | 12 | 12 | 7.5 | 85 Ohms | TOP=L2:L3=L2/L4:L6=L5/L7:BOTTOM=L7 |
| PCIE_RX_N90 | RXS90-DIFF1 | PAIR | 7 | 5.5 | 5 | 10 | 5 | 50 | 6 | 20 | 12 | 12 | 12 | 12 | 7.5 | 85 Ohms | TOP=L2:L3=L2/L4:L6=L5/L7:BOTTOM=L7 |
| PCIE_RX_N90 | RXS90-DIFF1 | PAIR | 8 | 5.38 | 5 | 10 | 5 | 50 | 6 | 33 | 12 | 12 | 12 | 12 | 6.62 | 85 Ohms | TOP=L2:L3=L2/L4:L6=L5/L7:BOTTOM=L7 |
| PCIE_RX_P90 | RXS90-DIFF1 | PAIR | 1 | 5.38 | 5 | 10 | 5 | 50 | 6 | 33 | 12 | 12 | 12 | 12 | 6.62 | 85 Ohms | TOP=L2:L3=L2/L4:L6=L5/L7:BOTTOM=L7 |
| PCIE_RX_P90 | RXS90-DIFF1 | PAIR | 2 | 5.5 | 5 | 10 | 5 | 50 | 6 | 20 | 12 | 12 | 12 | 12 | 7.5 | 85 Ohms | TOP=L2:L3=L2/L4:L6=L5/L7:BOTTOM=L7 |
| PCIE_RX_P90 | RXS90-DIFF1 | PAIR | 3 | 5.5 | 5 | 10 | 5 | 50 | 6 | 20 | 12 | 12 | 12 | 12 | 7.5 | 85 Ohms | TOP=L2:L3=L2/L4:L6=L5/L7:BOTTOM=L7 |
| PCIE_RX_P90 | RXS90-DIFF1 | PAIR | 4 | 5.5 | 5 | 10 | 5 | 50 | 6 | 20 | 12 | 12 | 12 | 12 | 7.5 | 85 Ohms | TOP=L2:L3=L2/L4:L6=L5/L7:BOTTOM=L7 |
| PCIE_RX_P90 | RXS90-DIFF1 | PAIR | 5 | 5.5 | 5 | 10 | 5 | 50 | 6 | 20 | 12 | 12 | 12 | 12 | 7.5 | 85 Ohms | TOP=L2:L3=L2/L4:L6=L5/L7:BOTTOM=L7 |
| PCIE_RX_P90 | RXS90-DIFF1 | PAIR | 6 | 5.5 | 5 | 10 | 5 | 50 | 6 | 20 | 12 | 12 | 12 | 12 | 7.5 | 85 Ohms | TOP=L2:L3=L2/L4:L6=L5/L7:BOTTOM=L7 |
| PCIE_RX_P90 | RXS90-DIFF1 | PAIR | 7 | 5.5 | 5 | 10 | 5 | 50 | 6 | 20 | 12 | 12 | 12 | 12 | 7.5 | 85 Ohms | TOP=L2:L3=L2/L4:L6=L5/L7:BOTTOM=L7 |
| PCIE_RX_P90 | RXS90-DIFF1 | PAIR | 8 | 5.38 | 5 | 10 | 5 | 50 | 6 | 33 | 12 | 12 | 12 | 12 | 6.62 | 85 Ohms | TOP=L2:L3=L2/L4:L6=L5/L7:BOTTOM=L7 |
| PCIE_RX_N91 | RXS91-DIFF1 | PAIR | 1 | 5.38 | 5 | 10 | 5 | 50 | 6 | 33 | 12 | 12 | 12 | 12 | 6.62 | 85 Ohms | TOP=L2:L3=L2/L4:L6=L5/L7:BOTTOM=L7 |
| PCIE_RX_N91 | RXS91-DIFF1 | PAIR | 2 | 5.5 | 5 | 10 | 5 | 50 | 6 | 20 | 12 | 12 | 12 | 12 | 7.5 | 85 Ohms | TOP=L2:L3=L2/L4:L6=L5/L7:BOTTOM=L7 |
| PCIE_RX_N91 | RXS91-DIFF1 | PAIR | 3 | 5.5 | 5 | 10 | 5 | 50 | 6 | 20 | 12 | 12 | 12 | 12 | 7.5 | 85 Ohms | TOP=L2:L3=L2/L4:L6=L5/L7:BOTTOM=L7 |
| PCIE_RX_N91 | RXS91-DIFF1 | PAIR | 4 | 5.5 | 5 | 10 | 5 | 50 | 6 | 20 | 12 | 12 | 12 | 12 | 7.5 | 85 Ohms | TOP=L2:L3=L2/L4:L6=L5/L7:BOTTOM=L7 |
| PCIE_RX_N91 | RXS91-DIFF1 | PAIR | 5 | 5.5 | 5 | 10 | 5 | 50 | 6 | 20 | 12 | 12 | 12 | 12 | 7.5 | 85 Ohms | TOP=L2:L3=L2/L4:L6=L5/L7:BOTTOM=L7 |
| PCIE_RX_N91 | RXS91-DIFF1 | PAIR | 6 | 5.5 | 5 | 10 | 5 | 50 | 6 | 20 | 12 | 12 | 12 | 12 | 7.5 | 85 Ohms | TOP=L2:L3=L2/L4:L6=L5/L7:BOTTOM=L7 |
| PCIE_RX_N91 | RXS91-DIFF1 | PAIR | 7 | 5.5 | 5 | 10 | 5 | 50 | 6 | 20 | 12 | 12 | 12 | 12 | 7.5 | 85 Ohms | TOP=L2:L3=L2/L4:L6=L5/L7:BOTTOM=L7 |
| PCIE_RX_N91 | RXS91-DIFF1 | PAIR | 8 | 5.38 | 5 | 10 | 5 | 50 | 6 | 33 | 12 | 12 | 12 | 12 | 6.62 | 85 Ohms | TOP=L2:L3=L2/L4:L6=L5/L7:BOTTOM=L7 |
| PCIE_RX_P91 | RXS91-DIFF1 | PAIR | 1 | 5.38 | 5 | 10 | 5 | 50 | 6 | 33 | 12 | 12 | 12 | 12 | 6.62 | 85 Ohms | TOP=L2:L3=L2/L4:L6=L5/L7:BOTTOM=L7 |
| PCIE_RX_P91 | RXS91-DIFF1 | PAIR | 2 | 5.5 | 5 | 10 | 5 | 50 | 6 | 20 | 12 | 12 | 12 | 12 | 7.5 | 85 Ohms | TOP=L2:L3=L2/L4:L6=L5/L7:BOTTOM=L7 |
| PCIE_RX_P91 | RXS91-DIFF1 | PAIR | 3 | 5.5 | 5 | 10 | 5 | 50 | 6 | 20 | 12 | 12 | 12 | 12 | 7.5 | 85 Ohms | TOP=L2:L3=L2/L4:L6=L5/L7:BOTTOM=L7 |
| PCIE_RX_P91 | RXS91-DIFF1 | PAIR | 4 | 5.5 | 5 | 10 | 5 | 50 | 6 | 20 | 12 | 12 | 12 | 12 | 7.5 | 85 Ohms | TOP=L2:L3=L2/L4:L6=L5/L7:BOTTOM=L7 |
| PCIE_RX_P91 | RXS91-DIFF1 | PAIR | 5 | 5.5 | 5 | 10 | 5 | 50 | 6 | 20 | 12 | 12 | 12 | 12 | 7.5 | 85 Ohms | TOP=L2:L3=L2/L4:L6=L5/L7:BOTTOM=L7 |
| PCIE_RX_P91 | RXS91-DIFF1 | PAIR | 6 | 5.5 | 5 | 10 | 5 | 50 | 6 | 20 | 12 | 12 | 12 | 12 | 7.5 | 85 Ohms | TOP=L2:L3=L2/L4:L6=L5/L7:BOTTOM=L7 |
| PCIE_RX_P91 | RXS91-DIFF1 | PAIR | 7 | 5.5 | 5 | 10 | 5 | 50 | 6 | 20 | 12 | 12 | 12 | 12 | 7.5 | 85 Ohms | TOP=L2:L3=L2/L4:L6=L5/L7:BOTTOM=L7 |
| PCIE_RX_P91 | RXS91-DIFF1 | PAIR | 8 | 5.38 | 5 | 10 | 5 | 50 | 6 | 33 | 12 | 12 | 12 | 12 | 6.62 | 85 Ohms | TOP=L2:L3=L2/L4:L6=L5/L7:BOTTOM=L7 |
| PCIE_RX_N92 | RXS92-DIFF1 | PAIR | 1 | 5.38 | 5 | 10 | 5 | 50 | 6 | 33 | 12 | 12 | 12 | 12 | 6.62 | 85 Ohms | TOP=L2:L3=L2/L4:L6=L5/L7:BOTTOM=L7 |
| PCIE_RX_N92 | RXS92-DIFF1 | PAIR | 2 | 5.5 | 5 | 10 | 5 | 50 | 6 | 20 | 12 | 12 | 12 | 12 | 7.5 | 85 Ohms | TOP=L2:L3=L2/L4:L6=L5/L7:BOTTOM=L7 |
| PCIE_RX_N92 | RXS92-DIFF1 | PAIR | 3 | 5.5 | 5 | 10 | 5 | 50 | 6 | 20 | 12 | 12 | 12 | 12 | 7.5 | 85 Ohms | TOP=L2:L3=L2/L4:L6=L5/L7:BOTTOM=L7 |
| PCIE_RX_N92 | RXS92-DIFF1 | PAIR | 4 | 5.5 | 5 | 10 | 5 | 50 | 6 | 20 | 12 | 12 | 12 | 12 | 7.5 | 85 Ohms | TOP=L2:L3=L2/L4:L6=L5/L7:BOTTOM=L7 |
| PCIE_RX_N92 | RXS92-DIFF1 | PAIR | 5 | 5.5 | 5 | 10 | 5 | 50 | 6 | 20 | 12 | 12 | 12 | 12 | 7.5 | 85 Ohms | TOP=L2:L3=L2/L4:L6=L5/L7:BOTTOM=L7 |
| PCIE_RX_N92 | RXS92-DIFF1 | PAIR | 6 | 5.5 | 5 | 10 | 5 | 50 | 6 | 20 | 12 | 12 | 12 | 12 | 7.5 | 85 Ohms | TOP=L2:L3=L2/L4:L6=L5/L7:BOTTOM=L7 |
| PCIE_RX_N92 | RXS92-DIFF1 | PAIR | 7 | 5.5 | 5 | 10 | 5 | 50 | 6 | 20 | 12 | 12 | 12 | 12 | 7.5 | 85 Ohms | TOP=L2:L3=L2/L4:L6=L5/L7:BOTTOM=L7 |
| PCIE_RX_N92 | RXS92-DIFF1 | PAIR | 8 | 5.38 | 5 | 10 | 5 | 50 | 6 | 33 | 12 | 12 | 12 | 12 | 6.62 | 85 Ohms | TOP=L2:L3=L2/L4:L6=L5/L7:BOTTOM=L7 |
| PCIE_RX_P92 | RXS92-DIFF1 | PAIR | 1 | 5.38 | 5 | 10 | 5 | 50 | 6 | 33 | 12 | 12 | 12 | 12 | 6.62 | 85 Ohms | TOP=L2:L3=L2/L4:L6=L5/L7:BOTTOM=L7 |
| PCIE_RX_P92 | RXS92-DIFF1 | PAIR | 2 | 5.5 | 5 | 10 | 5 | 50 | 6 | 20 | 12 | 12 | 12 | 12 | 7.5 | 85 Ohms | TOP=L2:L3=L2/L4:L6=L5/L7:BOTTOM=L7 |
| PCIE_RX_P92 | RXS92-DIFF1 | PAIR | 3 | 5.5 | 5 | 10 | 5 | 50 | 6 | 20 | 12 | 12 | 12 | 12 | 7.5 | 85 Ohms | TOP=L2:L3=L2/L4:L6=L5/L7:BOTTOM=L7 |
| PCIE_RX_P92 | RXS92-DIFF1 | PAIR | 4 | 5.5 | 5 | 10 | 5 | 50 | 6 | 20 | 12 | 12 | 12 | 12 | 7.5 | 85 Ohms | TOP=L2:L3=L2/L4:L6=L5/L7:BOTTOM=L7 |
| PCIE_RX_P92 | RXS92-DIFF1 | PAIR | 5 | 5.5 | 5 | 10 | 5 | 50 | 6 | 20 | 12 | 12 | 12 | 12 | 7.5 | 85 Ohms | TOP=L2:L3=L2/L4:L6=L5/L7:BOTTOM=L7 |
| PCIE_RX_P92 | RXS92-DIFF1 | PAIR | 6 | 5.5 | 5 | 10 | 5 | 50 | 6 | 20 | 12 | 12 | 12 | 12 | 7.5 | 85 Ohms | TOP=L2:L3=L2/L4:L6=L5/L7:BOTTOM=L7 |
| PCIE_RX_P92 | RXS92-DIFF1 | PAIR | 7 | 5.5 | 5 | 10 | 5 | 50 | 6 | 20 | 12 | 12 | 12 | 12 | 7.5 | 85 Ohms | TOP=L2:L3=L2/L4:L6=L5/L7:BOTTOM=L7 |
| PCIE_RX_P92 | RXS92-DIFF1 | PAIR | 8 | 5.38 | 5 | 10 | 5 | 50 | 6 | 33 | 12 | 12 | 12 | 12 | 6.62 | 85 Ohms | TOP=L2:L3=L2/L4:L6=L5/L7:BOTTOM=L7 |
| PCIE_RX_N93 | RXS93-DIFF1 | PAIR | 1 | 5.38 | 5 | 10 | 5 | 50 | 6 | 33 | 12 | 12 | 12 | 12 | 6.62 | 85 Ohms | TOP=L2:L3=L2/L4:L6=L5/L7:BOTTOM=L7 |
| PCIE_RX_N93 | RXS93-DIFF1 | PAIR | 2 | 5.5 | 5 | 10 | 5 | 50 | 6 | 20 | 12 | 12 | 12 | 12 | 7.5 | 85 Ohms | TOP=L2:L3=L2/L4:L6=L5/L7:BOTTOM=L7 |
| PCIE_RX_N93 | RXS93-DIFF1 | PAIR | 3 | 5.5 | 5 | 10 | 5 | 50 | 6 | 20 | 12 | 12 | 12 | 12 | 7.5 | 85 Ohms | TOP=L2:L3=L2/L4:L6=L5/L7:BOTTOM=L7 |
| PCIE_RX_N93 | RXS93-DIFF1 | PAIR | 4 | 5.5 | 5 | 10 | 5 | 50 | 6 | 20 | 12 | 12 | 12 | 12 | 7.5 | 85 Ohms | TOP=L2:L3=L2/L4:L6=L5/L7:BOTTOM=L7 |
| PCIE_RX_N93 | RXS93-DIFF1 | PAIR | 5 | 5.5 | 5 | 10 | 5 | 50 | 6 | 20 | 12 | 12 | 12 | 12 | 7.5 | 85 Ohms | TOP=L2:L3=L2/L4:L6=L5/L7:BOTTOM=L7 |
| PCIE_RX_N93 | RXS93-DIFF1 | PAIR | 6 | 5.5 | 5 | 10 | 5 | 50 | 6 | 20 | 12 | 12 | 12 | 12 | 7.5 | 85 Ohms | TOP=L2:L3=L2/L4:L6=L5/L7:BOTTOM=L7 |
| PCIE_RX_N93 | RXS93-DIFF1 | PAIR | 7 | 5.5 | 5 | 10 | 5 | 50 | 6 | 20 | 12 | 12 | 12 | 12 | 7.5 | 85 Ohms | TOP=L2:L3=L2/L4:L6=L5/L7:BOTTOM=L7 |
| PCIE_RX_N93 | RXS93-DIFF1 | PAIR | 8 | 5.38 | 5 | 10 | 5 | 50 | 6 | 33 | 12 | 12 | 12 | 12 | 6.62 | 85 Ohms | TOP=L2:L3=L2/L4:L6=L5/L7:BOTTOM=L7 |
| PCIE_RX_P93 | RXS93-DIFF1 | PAIR | 1 | 5.38 | 5 | 10 | 5 | 50 | 6 | 33 | 12 | 12 | 12 | 12 | 6.62 | 85 Ohms | TOP=L2:L3=L2/L4:L6=L5/L7:BOTTOM=L7 |
| PCIE_RX_P93 | RXS93-DIFF1 | PAIR | 2 | 5.5 | 5 | 10 | 5 | 50 | 6 | 20 | 12 | 12 | 12 | 12 | 7.5 | 85 Ohms | TOP=L2:L3=L2/L4:L6=L5/L7:BOTTOM=L7 |
| PCIE_RX_P93 | RXS93-DIFF1 | PAIR | 3 | 5.5 | 5 | 10 | 5 | 50 | 6 | 20 | 12 | 12 | 12 | 12 | 7.5 | 85 Ohms | TOP=L2:L3=L2/L4:L6=L5/L7:BOTTOM=L7 |
| PCIE_RX_P93 | RXS93-DIFF1 | PAIR | 4 | 5.5 | 5 | 10 | 5 | 50 | 6 | 20 | 12 | 12 | 12 | 12 | 7.5 | 85 Ohms | TOP=L2:L3=L2/L4:L6=L5/L7:BOTTOM=L7 |
| PCIE_RX_P93 | RXS93-DIFF1 | PAIR | 5 | 5.5 | 5 | 10 | 5 | 50 | 6 | 20 | 12 | 12 | 12 | 12 | 7.5 | 85 Ohms | TOP=L2:L3=L2/L4:L6=L5/L7:BOTTOM=L7 |
| PCIE_RX_P93 | RXS93-DIFF1 | PAIR | 6 | 5.5 | 5 | 10 | 5 | 50 | 6 | 20 | 12 | 12 | 12 | 12 | 7.5 | 85 Ohms | TOP=L2:L3=L2/L4:L6=L5/L7:BOTTOM=L7 |
| PCIE_RX_P93 | RXS93-DIFF1 | PAIR | 7 | 5.5 | 5 | 10 | 5 | 50 | 6 | 20 | 12 | 12 | 12 | 12 | 7.5 | 85 Ohms | TOP=L2:L3=L2/L4:L6=L5/L7:BOTTOM=L7 |
| PCIE_RX_P93 | RXS93-DIFF1 | PAIR | 8 | 5.38 | 5 | 10 | 5 | 50 | 6 | 33 | 12 | 12 | 12 | 12 | 6.62 | 85 Ohms | TOP=L2:L3=L2/L4:L6=L5/L7:BOTTOM=L7 |
| PCIE_RX_N94 | RXS94-DIFF1 | PAIR | 1 | 5.38 | 5 | 10 | 5 | 50 | 6 | 33 | 12 | 12 | 12 | 12 | 6.62 | 85 Ohms | TOP=L2:L3=L2/L4:L6=L5/L7:BOTTOM=L7 |
| PCIE_RX_N94 | RXS94-DIFF1 | PAIR | 2 | 5.5 | 5 | 10 | 5 | 50 | 6 | 20 | 12 | 12 | 12 | 12 | 7.5 | 85 Ohms | TOP=L2:L3=L2/L4:L6=L5/L7:BOTTOM=L7 |
| PCIE_RX_N94 | RXS94-DIFF1 | PAIR | 3 | 5.5 | 5 | 10 | 5 | 50 | 6 | 20 | 12 | 12 | 12 | 12 | 7.5 | 85 Ohms | TOP=L2:L3=L2/L4:L6=L5/L7:BOTTOM=L7 |
| PCIE_RX_N94 | RXS94-DIFF1 | PAIR | 4 | 5.5 | 5 | 10 | 5 | 50 | 6 | 20 | 12 | 12 | 12 | 12 | 7.5 | 85 Ohms | TOP=L2:L3=L2/L4:L6=L5/L7:BOTTOM=L7 |
| PCIE_RX_N94 | RXS94-DIFF1 | PAIR | 5 | 5.5 | 5 | 10 | 5 | 50 | 6 | 20 | 12 | 12 | 12 | 12 | 7.5 | 85 Ohms | TOP=L2:L3=L2/L4:L6=L5/L7:BOTTOM=L7 |
| PCIE_RX_N94 | RXS94-DIFF1 | PAIR | 6 | 5.5 | 5 | 10 | 5 | 50 | 6 | 20 | 12 | 12 | 12 | 12 | 7.5 | 85 Ohms | TOP=L2:L3=L2/L4:L6=L5/L7:BOTTOM=L7 |
| PCIE_RX_N94 | RXS94-DIFF1 | PAIR | 7 | 5.5 | 5 | 10 | 5 | 50 | 6 | 20 | 12 | 12 | 12 | 12 | 7.5 | 85 Ohms | TOP=L2:L3=L2/L4:L6=L5/L7:BOTTOM=L7 |
| PCIE_RX_N94 | RXS94-DIFF1 | PAIR | 8 | 5.38 | 5 | 10 | 5 | 50 | 6 | 33 | 12 | 12 | 12 | 12 | 6.62 | 85 Ohms | TOP=L2:L3=L2/L4:L6=L5/L7:BOTTOM=L7 |
| PCIE_RX_P94 | RXS94-DIFF1 | PAIR | 1 | 5.38 | 5 | 10 | 5 | 50 | 6 | 33 | 12 | 12 | 12 | 12 | 6.62 | 85 Ohms | TOP=L2:L3=L2/L4:L6=L5/L7:BOTTOM=L7 |
| PCIE_RX_P94 | RXS94-DIFF1 | PAIR | 2 | 5.5 | 5 | 10 | 5 | 50 | 6 | 20 | 12 | 12 | 12 | 12 | 7.5 | 85 Ohms | TOP=L2:L3=L2/L4:L6=L5/L7:BOTTOM=L7 |
| PCIE_RX_P94 | RXS94-DIFF1 | PAIR | 3 | 5.5 | 5 | 10 | 5 | 50 | 6 | 20 | 12 | 12 | 12 | 12 | 7.5 | 85 Ohms | TOP=L2:L3=L2/L4:L6=L5/L7:BOTTOM=L7 |
| PCIE_RX_P94 | RXS94-DIFF1 | PAIR | 4 | 5.5 | 5 | 10 | 5 | 50 | 6 | 20 | 12 | 12 | 12 | 12 | 7.5 | 85 Ohms | TOP=L2:L3=L2/L4:L6=L5/L7:BOTTOM=L7 |
| PCIE_RX_P94 | RXS94-DIFF1 | PAIR | 5 | 5.5 | 5 | 10 | 5 | 50 | 6 | 20 | 12 | 12 | 12 | 12 | 7.5 | 85 Ohms | TOP=L2:L3=L2/L4:L6=L5/L7:BOTTOM=L7 |
| PCIE_RX_P94 | RXS94-DIFF1 | PAIR | 6 | 5.5 | 5 | 10 | 5 | 50 | 6 | 20 | 12 | 12 | 12 | 12 | 7.5 | 85 Ohms | TOP=L2:L3=L2/L4:L6=L5/L7:BOTTOM=L7 |
| PCIE_RX_P94 | RXS94-DIFF1 | PAIR | 7 | 5.5 | 5 | 10 | 5 | 50 | 6 | 20 | 12 | 12 | 12 | 12 | 7.5 | 85 Ohms | TOP=L2:L3=L2/L4:L6=L5/L7:BOTTOM=L7 |
| PCIE_RX_P94 | RXS94-DIFF1 | PAIR | 8 | 5.38 | 5 | 10 | 5 | 50 | 6 | 33 | 12 | 12 | 12 | 12 | 6.62 | 85 Ohms | TOP=L2:L3=L2/L4:L6=L5/L7:BOTTOM=L7 |
| PCIE_RX_N95 | RXS95-DIFF1 | PAIR | 1 | 5.38 | 5 | 10 | 5 | 50 | 6 | 33 | 12 | 12 | 12 | 12 | 6.62 | 85 Ohms | TOP=L2:L3=L2/L4:L6=L5/L7:BOTTOM=L7 |
| PCIE_RX_N95 | RXS95-DIFF1 | PAIR | 2 | 5.5 | 5 | 10 | 5 | 50 | 6 | 20 | 12 | 12 | 12 | 12 | 7.5 | 85 Ohms | TOP=L2:L3=L2/L4:L6=L5/L7:BOTTOM=L7 |
| PCIE_RX_N95 | RXS95-DIFF1 | PAIR | 3 | 5.5 | 5 | 10 | 5 | 50 | 6 | 20 | 12 | 12 | 12 | 12 | 7.5 | 85 Ohms | TOP=L2:L3=L2/L4:L6=L5/L7:BOTTOM=L7 |
| PCIE_RX_N95 | RXS95-DIFF1 | PAIR | 4 | 5.5 | 5 | 10 | 5 | 50 | 6 | 20 | 12 | 12 | 12 | 12 | 7.5 | 85 Ohms | TOP=L2:L3=L2/L4:L6=L5/L7:BOTTOM=L7 |
| PCIE_RX_N95 | RXS95-DIFF1 | PAIR | 5 | 5.5 | 5 | 10 | 5 | 50 | 6 | 20 | 12 | 12 | 12 | 12 | 7.5 | 85 Ohms | TOP=L2:L3=L2/L4:L6=L5/L7:BOTTOM=L7 |
| PCIE_RX_N95 | RXS95-DIFF1 | PAIR | 6 | 5.5 | 5 | 10 | 5 | 50 | 6 | 20 | 12 | 12 | 12 | 12 | 7.5 | 85 Ohms | TOP=L2:L3=L2/L4:L6=L5/L7:BOTTOM=L7 |
| PCIE_RX_N95 | RXS95-DIFF1 | PAIR | 7 | 5.5 | 5 | 10 | 5 | 50 | 6 | 20 | 12 | 12 | 12 | 12 | 7.5 | 85 Ohms | TOP=L2:L3=L2/L4:L6=L5/L7:BOTTOM=L7 |
| PCIE_RX_N95 | RXS95-DIFF1 | PAIR | 8 | 5.38 | 5 | 10 | 5 | 50 | 6 | 33 | 12 | 12 | 12 | 12 | 6.62 | 85 Ohms | TOP=L2:L3=L2/L4:L6=L5/L7:BOTTOM=L7 |
| PCIE_RX_P95 | RXS95-DIFF1 | PAIR | 1 | 5.38 | 5 | 10 | 5 | 50 | 6 | 33 | 12 | 12 | 12 | 12 | 6.62 | 85 Ohms | TOP=L2:L3=L2/L4:L6=L5/L7:BOTTOM=L7 |
| PCIE_RX_P95 | RXS95-DIFF1 | PAIR | 2 | 5.5 | 5 | 10 | 5 | 50 | 6 | 20 | 12 | 12 | 12 | 12 | 7.5 | 85 Ohms | TOP=L2:L3=L2/L4:L6=L5/L7:BOTTOM=L7 |
| PCIE_RX_P95 | RXS95-DIFF1 | PAIR | 3 | 5.5 | 5 | 10 | 5 | 50 | 6 | 20 | 12 | 12 | 12 | 12 | 7.5 | 85 Ohms | TOP=L2:L3=L2/L4:L6=L5/L7:BOTTOM=L7 |
| PCIE_RX_P95 | RXS95-DIFF1 | PAIR | 4 | 5.5 | 5 | 10 | 5 | 50 | 6 | 20 | 12 | 12 | 12 | 12 | 7.5 | 85 Ohms | TOP=L2:L3=L2/L4:L6=L5/L7:BOTTOM=L7 |
| PCIE_RX_P95 | RXS95-DIFF1 | PAIR | 5 | 5.5 | 5 | 10 | 5 | 50 | 6 | 20 | 12 | 12 | 12 | 12 | 7.5 | 85 Ohms | TOP=L2:L3=L2/L4:L6=L5/L7:BOTTOM=L7 |
| PCIE_RX_P95 | RXS95-DIFF1 | PAIR | 6 | 5.5 | 5 | 10 | 5 | 50 | 6 | 20 | 12 | 12 | 12 | 12 | 7.5 | 85 Ohms | TOP=L2:L3=L2/L4:L6=L5/L7:BOTTOM=L7 |
| PCIE_RX_P95 | RXS95-DIFF1 | PAIR | 7 | 5.5 | 5 | 10 | 5 | 50 | 6 | 20 | 12 | 12 | 12 | 12 | 7.5 | 85 Ohms | TOP=L2:L3=L2/L4:L6=L5/L7:BOTTOM=L7 |
| PCIE_RX_P95 | RXS95-DIFF1 | PAIR | 8 | 5.38 | 5 | 10 | 5 | 50 | 6 | 33 | 12 | 12 | 12 | 12 | 6.62 | 85 Ohms | TOP=L2:L3=L2/L4:L6=L5/L7:BOTTOM=L7 |
| PCIE_RX_N9 | RXS9-DIFF1 | PAIR | 1 | 5.38 | 5 | 10 | 5 | 50 | 6 | 33 | 12 | 12 | 12 | 12 | 6.62 | 85 Ohms | TOP=L2:L3=L2/L4:L6=L5/L7:BOTTOM=L7 |
| PCIE_RX_N9 | RXS9-DIFF1 | PAIR | 2 | 5.5 | 5 | 10 | 5 | 50 | 6 | 20 | 12 | 12 | 12 | 12 | 7.5 | 85 Ohms | TOP=L2:L3=L2/L4:L6=L5/L7:BOTTOM=L7 |
| PCIE_RX_N9 | RXS9-DIFF1 | PAIR | 3 | 5.5 | 5 | 10 | 5 | 50 | 6 | 20 | 12 | 12 | 12 | 12 | 7.5 | 85 Ohms | TOP=L2:L3=L2/L4:L6=L5/L7:BOTTOM=L7 |
| PCIE_RX_N9 | RXS9-DIFF1 | PAIR | 4 | 5.5 | 5 | 10 | 5 | 50 | 6 | 20 | 12 | 12 | 12 | 12 | 7.5 | 85 Ohms | TOP=L2:L3=L2/L4:L6=L5/L7:BOTTOM=L7 |
| PCIE_RX_N9 | RXS9-DIFF1 | PAIR | 5 | 5.5 | 5 | 10 | 5 | 50 | 6 | 20 | 12 | 12 | 12 | 12 | 7.5 | 85 Ohms | TOP=L2:L3=L2/L4:L6=L5/L7:BOTTOM=L7 |
| PCIE_RX_N9 | RXS9-DIFF1 | PAIR | 6 | 5.5 | 5 | 10 | 5 | 50 | 6 | 20 | 12 | 12 | 12 | 12 | 7.5 | 85 Ohms | TOP=L2:L3=L2/L4:L6=L5/L7:BOTTOM=L7 |
| PCIE_RX_N9 | RXS9-DIFF1 | PAIR | 7 | 5.5 | 5 | 10 | 5 | 50 | 6 | 20 | 12 | 12 | 12 | 12 | 7.5 | 85 Ohms | TOP=L2:L3=L2/L4:L6=L5/L7:BOTTOM=L7 |
| PCIE_RX_N9 | RXS9-DIFF1 | PAIR | 8 | 5.38 | 5 | 10 | 5 | 50 | 6 | 33 | 12 | 12 | 12 | 12 | 6.62 | 85 Ohms | TOP=L2:L3=L2/L4:L6=L5/L7:BOTTOM=L7 |
| PCIE_RX_P9 | RXS9-DIFF1 | PAIR | 1 | 5.38 | 5 | 10 | 5 | 50 | 6 | 33 | 12 | 12 | 12 | 12 | 6.62 | 85 Ohms | TOP=L2:L3=L2/L4:L6=L5/L7:BOTTOM=L7 |
| PCIE_RX_P9 | RXS9-DIFF1 | PAIR | 2 | 5.5 | 5 | 10 | 5 | 50 | 6 | 20 | 12 | 12 | 12 | 12 | 7.5 | 85 Ohms | TOP=L2:L3=L2/L4:L6=L5/L7:BOTTOM=L7 |
| PCIE_RX_P9 | RXS9-DIFF1 | PAIR | 3 | 5.5 | 5 | 10 | 5 | 50 | 6 | 20 | 12 | 12 | 12 | 12 | 7.5 | 85 Ohms | TOP=L2:L3=L2/L4:L6=L5/L7:BOTTOM=L7 |
| PCIE_RX_P9 | RXS9-DIFF1 | PAIR | 4 | 5.5 | 5 | 10 | 5 | 50 | 6 | 20 | 12 | 12 | 12 | 12 | 7.5 | 85 Ohms | TOP=L2:L3=L2/L4:L6=L5/L7:BOTTOM=L7 |
| PCIE_RX_P9 | RXS9-DIFF1 | PAIR | 5 | 5.5 | 5 | 10 | 5 | 50 | 6 | 20 | 12 | 12 | 12 | 12 | 7.5 | 85 Ohms | TOP=L2:L3=L2/L4:L6=L5/L7:BOTTOM=L7 |
| PCIE_RX_P9 | RXS9-DIFF1 | PAIR | 6 | 5.5 | 5 | 10 | 5 | 50 | 6 | 20 | 12 | 12 | 12 | 12 | 7.5 | 85 Ohms | TOP=L2:L3=L2/L4:L6=L5/L7:BOTTOM=L7 |
| PCIE_RX_P9 | RXS9-DIFF1 | PAIR | 7 | 5.5 | 5 | 10 | 5 | 50 | 6 | 20 | 12 | 12 | 12 | 12 | 7.5 | 85 Ohms | TOP=L2:L3=L2/L4:L6=L5/L7:BOTTOM=L7 |
| PCIE_RX_P9 | RXS9-DIFF1 | PAIR | 8 | 5.38 | 5 | 10 | 5 | 50 | 6 | 33 | 12 | 12 | 12 | 12 | 6.62 | 85 Ohms | TOP=L2:L3=L2/L4:L6=L5/L7:BOTTOM=L7 |
| PCIE_TX_N0 | TX0-DIFF1 | PAIR | 1 | 5.38 | 5 | 10 | 5 | 50 | 6 | 33 | 12 | 12 | 12 | 12 | 6.62 | 85 Ohms | TOP=L2:L3=L2/L4:L6=L5/L7:BOTTOM=L7 |
| PCIE_TX_N0 | TX0-DIFF1 | PAIR | 2 | 5.5 | 5 | 10 | 5 | 50 | 6 | 20 | 12 | 12 | 12 | 12 | 7.5 | 85 Ohms | TOP=L2:L3=L2/L4:L6=L5/L7:BOTTOM=L7 |
| PCIE_TX_N0 | TX0-DIFF1 | PAIR | 3 | 5.5 | 5 | 10 | 5 | 50 | 6 | 20 | 12 | 12 | 12 | 12 | 7.5 | 85 Ohms | TOP=L2:L3=L2/L4:L6=L5/L7:BOTTOM=L7 |
| PCIE_TX_N0 | TX0-DIFF1 | PAIR | 4 | 5.5 | 5 | 10 | 5 | 50 | 6 | 20 | 12 | 12 | 12 | 12 | 7.5 | 85 Ohms | TOP=L2:L3=L2/L4:L6=L5/L7:BOTTOM=L7 |
| PCIE_TX_N0 | TX0-DIFF1 | PAIR | 5 | 5.5 | 5 | 10 | 5 | 50 | 6 | 20 | 12 | 12 | 12 | 12 | 7.5 | 85 Ohms | TOP=L2:L3=L2/L4:L6=L5/L7:BOTTOM=L7 |
| PCIE_TX_N0 | TX0-DIFF1 | PAIR | 6 | 5.5 | 5 | 10 | 5 | 50 | 6 | 20 | 12 | 12 | 12 | 12 | 7.5 | 85 Ohms | TOP=L2:L3=L2/L4:L6=L5/L7:BOTTOM=L7 |
| PCIE_TX_N0 | TX0-DIFF1 | PAIR | 7 | 5.5 | 5 | 10 | 5 | 50 | 6 | 20 | 12 | 12 | 12 | 12 | 7.5 | 85 Ohms | TOP=L2:L3=L2/L4:L6=L5/L7:BOTTOM=L7 |
| PCIE_TX_N0 | TX0-DIFF1 | PAIR | 8 | 5.38 | 5 | 10 | 5 | 50 | 6 | 33 | 12 | 12 | 12 | 12 | 6.62 | 85 Ohms | TOP=L2:L3=L2/L4:L6=L5/L7:BOTTOM=L7 |
| PCIE_TX_P0 | TX0-DIFF1 | PAIR | 1 | 5.38 | 5 | 10 | 5 | 50 | 6 | 33 | 12 | 12 | 12 | 12 | 6.62 | 85 Ohms | TOP=L2:L3=L2/L4:L6=L5/L7:BOTTOM=L7 |
| PCIE_TX_P0 | TX0-DIFF1 | PAIR | 2 | 5.5 | 5 | 10 | 5 | 50 | 6 | 20 | 12 | 12 | 12 | 12 | 7.5 | 85 Ohms | TOP=L2:L3=L2/L4:L6=L5/L7:BOTTOM=L7 |
| PCIE_TX_P0 | TX0-DIFF1 | PAIR | 3 | 5.5 | 5 | 10 | 5 | 50 | 6 | 20 | 12 | 12 | 12 | 12 | 7.5 | 85 Ohms | TOP=L2:L3=L2/L4:L6=L5/L7:BOTTOM=L7 |
| PCIE_TX_P0 | TX0-DIFF1 | PAIR | 4 | 5.5 | 5 | 10 | 5 | 50 | 6 | 20 | 12 | 12 | 12 | 12 | 7.5 | 85 Ohms | TOP=L2:L3=L2/L4:L6=L5/L7:BOTTOM=L7 |
| PCIE_TX_P0 | TX0-DIFF1 | PAIR | 5 | 5.5 | 5 | 10 | 5 | 50 | 6 | 20 | 12 | 12 | 12 | 12 | 7.5 | 85 Ohms | TOP=L2:L3=L2/L4:L6=L5/L7:BOTTOM=L7 |
| PCIE_TX_P0 | TX0-DIFF1 | PAIR | 6 | 5.5 | 5 | 10 | 5 | 50 | 6 | 20 | 12 | 12 | 12 | 12 | 7.5 | 85 Ohms | TOP=L2:L3=L2/L4:L6=L5/L7:BOTTOM=L7 |
| PCIE_TX_P0 | TX0-DIFF1 | PAIR | 7 | 5.5 | 5 | 10 | 5 | 50 | 6 | 20 | 12 | 12 | 12 | 12 | 7.5 | 85 Ohms | TOP=L2:L3=L2/L4:L6=L5/L7:BOTTOM=L7 |
| PCIE_TX_P0 | TX0-DIFF1 | PAIR | 8 | 5.38 | 5 | 10 | 5 | 50 | 6 | 33 | 12 | 12 | 12 | 12 | 6.62 | 85 Ohms | TOP=L2:L3=L2/L4:L6=L5/L7:BOTTOM=L7 |
| PCIE_TX_N10 | TX10-DIFF1 | PAIR | 1 | 5.38 | 5 | 10 | 5 | 50 | 6 | 33 | 12 | 12 | 12 | 12 | 6.62 | 85 Ohms | TOP=L2:L3=L2/L4:L6=L5/L7:BOTTOM=L7 |
| PCIE_TX_N10 | TX10-DIFF1 | PAIR | 2 | 5.5 | 5 | 10 | 5 | 50 | 6 | 20 | 12 | 12 | 12 | 12 | 7.5 | 85 Ohms | TOP=L2:L3=L2/L4:L6=L5/L7:BOTTOM=L7 |
| PCIE_TX_N10 | TX10-DIFF1 | PAIR | 3 | 5.5 | 5 | 10 | 5 | 50 | 6 | 20 | 12 | 12 | 12 | 12 | 7.5 | 85 Ohms | TOP=L2:L3=L2/L4:L6=L5/L7:BOTTOM=L7 |
| PCIE_TX_N10 | TX10-DIFF1 | PAIR | 4 | 5.5 | 5 | 10 | 5 | 50 | 6 | 20 | 12 | 12 | 12 | 12 | 7.5 | 85 Ohms | TOP=L2:L3=L2/L4:L6=L5/L7:BOTTOM=L7 |
| PCIE_TX_N10 | TX10-DIFF1 | PAIR | 5 | 5.5 | 5 | 10 | 5 | 50 | 6 | 20 | 12 | 12 | 12 | 12 | 7.5 | 85 Ohms | TOP=L2:L3=L2/L4:L6=L5/L7:BOTTOM=L7 |
| PCIE_TX_N10 | TX10-DIFF1 | PAIR | 6 | 5.5 | 5 | 10 | 5 | 50 | 6 | 20 | 12 | 12 | 12 | 12 | 7.5 | 85 Ohms | TOP=L2:L3=L2/L4:L6=L5/L7:BOTTOM=L7 |
| PCIE_TX_N10 | TX10-DIFF1 | PAIR | 7 | 5.5 | 5 | 10 | 5 | 50 | 6 | 20 | 12 | 12 | 12 | 12 | 7.5 | 85 Ohms | TOP=L2:L3=L2/L4:L6=L5/L7:BOTTOM=L7 |
| PCIE_TX_N10 | TX10-DIFF1 | PAIR | 8 | 5.38 | 5 | 10 | 5 | 50 | 6 | 33 | 12 | 12 | 12 | 12 | 6.62 | 85 Ohms | TOP=L2:L3=L2/L4:L6=L5/L7:BOTTOM=L7 |
| PCIE_TX_P10 | TX10-DIFF1 | PAIR | 1 | 5.38 | 5 | 10 | 5 | 50 | 6 | 33 | 12 | 12 | 12 | 12 | 6.62 | 85 Ohms | TOP=L2:L3=L2/L4:L6=L5/L7:BOTTOM=L7 |
| PCIE_TX_P10 | TX10-DIFF1 | PAIR | 2 | 5.5 | 5 | 10 | 5 | 50 | 6 | 20 | 12 | 12 | 12 | 12 | 7.5 | 85 Ohms | TOP=L2:L3=L2/L4:L6=L5/L7:BOTTOM=L7 |
| PCIE_TX_P10 | TX10-DIFF1 | PAIR | 3 | 5.5 | 5 | 10 | 5 | 50 | 6 | 20 | 12 | 12 | 12 | 12 | 7.5 | 85 Ohms | TOP=L2:L3=L2/L4:L6=L5/L7:BOTTOM=L7 |
| PCIE_TX_P10 | TX10-DIFF1 | PAIR | 4 | 5.5 | 5 | 10 | 5 | 50 | 6 | 20 | 12 | 12 | 12 | 12 | 7.5 | 85 Ohms | TOP=L2:L3=L2/L4:L6=L5/L7:BOTTOM=L7 |
| PCIE_TX_P10 | TX10-DIFF1 | PAIR | 5 | 5.5 | 5 | 10 | 5 | 50 | 6 | 20 | 12 | 12 | 12 | 12 | 7.5 | 85 Ohms | TOP=L2:L3=L2/L4:L6=L5/L7:BOTTOM=L7 |
| PCIE_TX_P10 | TX10-DIFF1 | PAIR | 6 | 5.5 | 5 | 10 | 5 | 50 | 6 | 20 | 12 | 12 | 12 | 12 | 7.5 | 85 Ohms | TOP=L2:L3=L2/L4:L6=L5/L7:BOTTOM=L7 |
| PCIE_TX_P10 | TX10-DIFF1 | PAIR | 7 | 5.5 | 5 | 10 | 5 | 50 | 6 | 20 | 12 | 12 | 12 | 12 | 7.5 | 85 Ohms | TOP=L2:L3=L2/L4:L6=L5/L7:BOTTOM=L7 |
| PCIE_TX_P10 | TX10-DIFF1 | PAIR | 8 | 5.38 | 5 | 10 | 5 | 50 | 6 | 33 | 12 | 12 | 12 | 12 | 6.62 | 85 Ohms | TOP=L2:L3=L2/L4:L6=L5/L7:BOTTOM=L7 |
| PCIE_TX_N11 | TX11-DIFF1 | PAIR | 1 | 5.38 | 5 | 10 | 5 | 50 | 6 | 33 | 12 | 12 | 12 | 12 | 6.62 | 85 Ohms | TOP=L2:L3=L2/L4:L6=L5/L7:BOTTOM=L7 |
| PCIE_TX_N11 | TX11-DIFF1 | PAIR | 2 | 5.5 | 5 | 10 | 5 | 50 | 6 | 20 | 12 | 12 | 12 | 12 | 7.5 | 85 Ohms | TOP=L2:L3=L2/L4:L6=L5/L7:BOTTOM=L7 |
| PCIE_TX_N11 | TX11-DIFF1 | PAIR | 3 | 5.5 | 5 | 10 | 5 | 50 | 6 | 20 | 12 | 12 | 12 | 12 | 7.5 | 85 Ohms | TOP=L2:L3=L2/L4:L6=L5/L7:BOTTOM=L7 |
| PCIE_TX_N11 | TX11-DIFF1 | PAIR | 4 | 5.5 | 5 | 10 | 5 | 50 | 6 | 20 | 12 | 12 | 12 | 12 | 7.5 | 85 Ohms | TOP=L2:L3=L2/L4:L6=L5/L7:BOTTOM=L7 |
| PCIE_TX_N11 | TX11-DIFF1 | PAIR | 5 | 5.5 | 5 | 10 | 5 | 50 | 6 | 20 | 12 | 12 | 12 | 12 | 7.5 | 85 Ohms | TOP=L2:L3=L2/L4:L6=L5/L7:BOTTOM=L7 |
| PCIE_TX_N11 | TX11-DIFF1 | PAIR | 6 | 5.5 | 5 | 10 | 5 | 50 | 6 | 20 | 12 | 12 | 12 | 12 | 7.5 | 85 Ohms | TOP=L2:L3=L2/L4:L6=L5/L7:BOTTOM=L7 |
| PCIE_TX_N11 | TX11-DIFF1 | PAIR | 7 | 5.5 | 5 | 10 | 5 | 50 | 6 | 20 | 12 | 12 | 12 | 12 | 7.5 | 85 Ohms | TOP=L2:L3=L2/L4:L6=L5/L7:BOTTOM=L7 |
| PCIE_TX_N11 | TX11-DIFF1 | PAIR | 8 | 5.38 | 5 | 10 | 5 | 50 | 6 | 33 | 12 | 12 | 12 | 12 | 6.62 | 85 Ohms | TOP=L2:L3=L2/L4:L6=L5/L7:BOTTOM=L7 |
| PCIE_TX_P11 | TX11-DIFF1 | PAIR | 1 | 5.38 | 5 | 10 | 5 | 50 | 6 | 33 | 12 | 12 | 12 | 12 | 6.62 | 85 Ohms | TOP=L2:L3=L2/L4:L6=L5/L7:BOTTOM=L7 |
| PCIE_TX_P11 | TX11-DIFF1 | PAIR | 2 | 5.5 | 5 | 10 | 5 | 50 | 6 | 20 | 12 | 12 | 12 | 12 | 7.5 | 85 Ohms | TOP=L2:L3=L2/L4:L6=L5/L7:BOTTOM=L7 |
| PCIE_TX_P11 | TX11-DIFF1 | PAIR | 3 | 5.5 | 5 | 10 | 5 | 50 | 6 | 20 | 12 | 12 | 12 | 12 | 7.5 | 85 Ohms | TOP=L2:L3=L2/L4:L6=L5/L7:BOTTOM=L7 |
| PCIE_TX_P11 | TX11-DIFF1 | PAIR | 4 | 5.5 | 5 | 10 | 5 | 50 | 6 | 20 | 12 | 12 | 12 | 12 | 7.5 | 85 Ohms | TOP=L2:L3=L2/L4:L6=L5/L7:BOTTOM=L7 |
| PCIE_TX_P11 | TX11-DIFF1 | PAIR | 5 | 5.5 | 5 | 10 | 5 | 50 | 6 | 20 | 12 | 12 | 12 | 12 | 7.5 | 85 Ohms | TOP=L2:L3=L2/L4:L6=L5/L7:BOTTOM=L7 |
| PCIE_TX_P11 | TX11-DIFF1 | PAIR | 6 | 5.5 | 5 | 10 | 5 | 50 | 6 | 20 | 12 | 12 | 12 | 12 | 7.5 | 85 Ohms | TOP=L2:L3=L2/L4:L6=L5/L7:BOTTOM=L7 |
| PCIE_TX_P11 | TX11-DIFF1 | PAIR | 7 | 5.5 | 5 | 10 | 5 | 50 | 6 | 20 | 12 | 12 | 12 | 12 | 7.5 | 85 Ohms | TOP=L2:L3=L2/L4:L6=L5/L7:BOTTOM=L7 |
| PCIE_TX_P11 | TX11-DIFF1 | PAIR | 8 | 5.38 | 5 | 10 | 5 | 50 | 6 | 33 | 12 | 12 | 12 | 12 | 6.62 | 85 Ohms | TOP=L2:L3=L2/L4:L6=L5/L7:BOTTOM=L7 |
| PCIE_TX_N12 | TX12-DIFF1 | PAIR | 1 | 5.38 | 5 | 10 | 5 | 50 | 6 | 33 | 12 | 12 | 12 | 12 | 6.62 | 85 Ohms | TOP=L2:L3=L2/L4:L6=L5/L7:BOTTOM=L7 |
| PCIE_TX_N12 | TX12-DIFF1 | PAIR | 2 | 5.5 | 5 | 10 | 5 | 50 | 6 | 20 | 12 | 12 | 12 | 12 | 7.5 | 85 Ohms | TOP=L2:L3=L2/L4:L6=L5/L7:BOTTOM=L7 |
| PCIE_TX_N12 | TX12-DIFF1 | PAIR | 3 | 5.5 | 5 | 10 | 5 | 50 | 6 | 20 | 12 | 12 | 12 | 12 | 7.5 | 85 Ohms | TOP=L2:L3=L2/L4:L6=L5/L7:BOTTOM=L7 |
| PCIE_TX_N12 | TX12-DIFF1 | PAIR | 4 | 5.5 | 5 | 10 | 5 | 50 | 6 | 20 | 12 | 12 | 12 | 12 | 7.5 | 85 Ohms | TOP=L2:L3=L2/L4:L6=L5/L7:BOTTOM=L7 |
| PCIE_TX_N12 | TX12-DIFF1 | PAIR | 5 | 5.5 | 5 | 10 | 5 | 50 | 6 | 20 | 12 | 12 | 12 | 12 | 7.5 | 85 Ohms | TOP=L2:L3=L2/L4:L6=L5/L7:BOTTOM=L7 |
| PCIE_TX_N12 | TX12-DIFF1 | PAIR | 6 | 5.5 | 5 | 10 | 5 | 50 | 6 | 20 | 12 | 12 | 12 | 12 | 7.5 | 85 Ohms | TOP=L2:L3=L2/L4:L6=L5/L7:BOTTOM=L7 |
| PCIE_TX_N12 | TX12-DIFF1 | PAIR | 7 | 5.5 | 5 | 10 | 5 | 50 | 6 | 20 | 12 | 12 | 12 | 12 | 7.5 | 85 Ohms | TOP=L2:L3=L2/L4:L6=L5/L7:BOTTOM=L7 |
| PCIE_TX_N12 | TX12-DIFF1 | PAIR | 8 | 5.38 | 5 | 10 | 5 | 50 | 6 | 33 | 12 | 12 | 12 | 12 | 6.62 | 85 Ohms | TOP=L2:L3=L2/L4:L6=L5/L7:BOTTOM=L7 |
| PCIE_TX_P12 | TX12-DIFF1 | PAIR | 1 | 5.38 | 5 | 10 | 5 | 50 | 6 | 33 | 12 | 12 | 12 | 12 | 6.62 | 85 Ohms | TOP=L2:L3=L2/L4:L6=L5/L7:BOTTOM=L7 |
| PCIE_TX_P12 | TX12-DIFF1 | PAIR | 2 | 5.5 | 5 | 10 | 5 | 50 | 6 | 20 | 12 | 12 | 12 | 12 | 7.5 | 85 Ohms | TOP=L2:L3=L2/L4:L6=L5/L7:BOTTOM=L7 |
| PCIE_TX_P12 | TX12-DIFF1 | PAIR | 3 | 5.5 | 5 | 10 | 5 | 50 | 6 | 20 | 12 | 12 | 12 | 12 | 7.5 | 85 Ohms | TOP=L2:L3=L2/L4:L6=L5/L7:BOTTOM=L7 |
| PCIE_TX_P12 | TX12-DIFF1 | PAIR | 4 | 5.5 | 5 | 10 | 5 | 50 | 6 | 20 | 12 | 12 | 12 | 12 | 7.5 | 85 Ohms | TOP=L2:L3=L2/L4:L6=L5/L7:BOTTOM=L7 |
| PCIE_TX_P12 | TX12-DIFF1 | PAIR | 5 | 5.5 | 5 | 10 | 5 | 50 | 6 | 20 | 12 | 12 | 12 | 12 | 7.5 | 85 Ohms | TOP=L2:L3=L2/L4:L6=L5/L7:BOTTOM=L7 |
| PCIE_TX_P12 | TX12-DIFF1 | PAIR | 6 | 5.5 | 5 | 10 | 5 | 50 | 6 | 20 | 12 | 12 | 12 | 12 | 7.5 | 85 Ohms | TOP=L2:L3=L2/L4:L6=L5/L7:BOTTOM=L7 |
| PCIE_TX_P12 | TX12-DIFF1 | PAIR | 7 | 5.5 | 5 | 10 | 5 | 50 | 6 | 20 | 12 | 12 | 12 | 12 | 7.5 | 85 Ohms | TOP=L2:L3=L2/L4:L6=L5/L7:BOTTOM=L7 |
| PCIE_TX_P12 | TX12-DIFF1 | PAIR | 8 | 5.38 | 5 | 10 | 5 | 50 | 6 | 33 | 12 | 12 | 12 | 12 | 6.62 | 85 Ohms | TOP=L2:L3=L2/L4:L6=L5/L7:BOTTOM=L7 |
| PCIE_TX_N13 | TX13-DIFF1 | PAIR | 1 | 5.38 | 5 | 10 | 5 | 50 | 6 | 33 | 12 | 12 | 12 | 12 | 6.62 | 85 Ohms | TOP=L2:L3=L2/L4:L6=L5/L7:BOTTOM=L7 |
| PCIE_TX_N13 | TX13-DIFF1 | PAIR | 2 | 5.5 | 5 | 10 | 5 | 50 | 6 | 20 | 12 | 12 | 12 | 12 | 7.5 | 85 Ohms | TOP=L2:L3=L2/L4:L6=L5/L7:BOTTOM=L7 |
| PCIE_TX_N13 | TX13-DIFF1 | PAIR | 3 | 5.5 | 5 | 10 | 5 | 50 | 6 | 20 | 12 | 12 | 12 | 12 | 7.5 | 85 Ohms | TOP=L2:L3=L2/L4:L6=L5/L7:BOTTOM=L7 |
| PCIE_TX_N13 | TX13-DIFF1 | PAIR | 4 | 5.5 | 5 | 10 | 5 | 50 | 6 | 20 | 12 | 12 | 12 | 12 | 7.5 | 85 Ohms | TOP=L2:L3=L2/L4:L6=L5/L7:BOTTOM=L7 |
| PCIE_TX_N13 | TX13-DIFF1 | PAIR | 5 | 5.5 | 5 | 10 | 5 | 50 | 6 | 20 | 12 | 12 | 12 | 12 | 7.5 | 85 Ohms | TOP=L2:L3=L2/L4:L6=L5/L7:BOTTOM=L7 |
| PCIE_TX_N13 | TX13-DIFF1 | PAIR | 6 | 5.5 | 5 | 10 | 5 | 50 | 6 | 20 | 12 | 12 | 12 | 12 | 7.5 | 85 Ohms | TOP=L2:L3=L2/L4:L6=L5/L7:BOTTOM=L7 |
| PCIE_TX_N13 | TX13-DIFF1 | PAIR | 7 | 5.5 | 5 | 10 | 5 | 50 | 6 | 20 | 12 | 12 | 12 | 12 | 7.5 | 85 Ohms | TOP=L2:L3=L2/L4:L6=L5/L7:BOTTOM=L7 |
| PCIE_TX_N13 | TX13-DIFF1 | PAIR | 8 | 5.38 | 5 | 10 | 5 | 50 | 6 | 33 | 12 | 12 | 12 | 12 | 6.62 | 85 Ohms | TOP=L2:L3=L2/L4:L6=L5/L7:BOTTOM=L7 |
| PCIE_TX_P13 | TX13-DIFF1 | PAIR | 1 | 5.38 | 5 | 10 | 5 | 50 | 6 | 33 | 12 | 12 | 12 | 12 | 6.62 | 85 Ohms | TOP=L2:L3=L2/L4:L6=L5/L7:BOTTOM=L7 |
| PCIE_TX_P13 | TX13-DIFF1 | PAIR | 2 | 5.5 | 5 | 10 | 5 | 50 | 6 | 20 | 12 | 12 | 12 | 12 | 7.5 | 85 Ohms | TOP=L2:L3=L2/L4:L6=L5/L7:BOTTOM=L7 |
| PCIE_TX_P13 | TX13-DIFF1 | PAIR | 3 | 5.5 | 5 | 10 | 5 | 50 | 6 | 20 | 12 | 12 | 12 | 12 | 7.5 | 85 Ohms | TOP=L2:L3=L2/L4:L6=L5/L7:BOTTOM=L7 |
| PCIE_TX_P13 | TX13-DIFF1 | PAIR | 4 | 5.5 | 5 | 10 | 5 | 50 | 6 | 20 | 12 | 12 | 12 | 12 | 7.5 | 85 Ohms | TOP=L2:L3=L2/L4:L6=L5/L7:BOTTOM=L7 |
| PCIE_TX_P13 | TX13-DIFF1 | PAIR | 5 | 5.5 | 5 | 10 | 5 | 50 | 6 | 20 | 12 | 12 | 12 | 12 | 7.5 | 85 Ohms | TOP=L2:L3=L2/L4:L6=L5/L7:BOTTOM=L7 |
| PCIE_TX_P13 | TX13-DIFF1 | PAIR | 6 | 5.5 | 5 | 10 | 5 | 50 | 6 | 20 | 12 | 12 | 12 | 12 | 7.5 | 85 Ohms | TOP=L2:L3=L2/L4:L6=L5/L7:BOTTOM=L7 |
| PCIE_TX_P13 | TX13-DIFF1 | PAIR | 7 | 5.5 | 5 | 10 | 5 | 50 | 6 | 20 | 12 | 12 | 12 | 12 | 7.5 | 85 Ohms | TOP=L2:L3=L2/L4:L6=L5/L7:BOTTOM=L7 |
| PCIE_TX_P13 | TX13-DIFF1 | PAIR | 8 | 5.38 | 5 | 10 | 5 | 50 | 6 | 33 | 12 | 12 | 12 | 12 | 6.62 | 85 Ohms | TOP=L2:L3=L2/L4:L6=L5/L7:BOTTOM=L7 |
| PCIE_TX_N14 | TX14-DIFF1 | PAIR | 1 | 5.38 | 5 | 10 | 5 | 50 | 6 | 33 | 12 | 12 | 12 | 12 | 6.62 | 85 Ohms | TOP=L2:L3=L2/L4:L6=L5/L7:BOTTOM=L7 |
| PCIE_TX_N14 | TX14-DIFF1 | PAIR | 2 | 5.5 | 5 | 10 | 5 | 50 | 6 | 20 | 12 | 12 | 12 | 12 | 7.5 | 85 Ohms | TOP=L2:L3=L2/L4:L6=L5/L7:BOTTOM=L7 |
| PCIE_TX_N14 | TX14-DIFF1 | PAIR | 3 | 5.5 | 5 | 10 | 5 | 50 | 6 | 20 | 12 | 12 | 12 | 12 | 7.5 | 85 Ohms | TOP=L2:L3=L2/L4:L6=L5/L7:BOTTOM=L7 |
| PCIE_TX_N14 | TX14-DIFF1 | PAIR | 4 | 5.5 | 5 | 10 | 5 | 50 | 6 | 20 | 12 | 12 | 12 | 12 | 7.5 | 85 Ohms | TOP=L2:L3=L2/L4:L6=L5/L7:BOTTOM=L7 |
| PCIE_TX_N14 | TX14-DIFF1 | PAIR | 5 | 5.5 | 5 | 10 | 5 | 50 | 6 | 20 | 12 | 12 | 12 | 12 | 7.5 | 85 Ohms | TOP=L2:L3=L2/L4:L6=L5/L7:BOTTOM=L7 |
| PCIE_TX_N14 | TX14-DIFF1 | PAIR | 6 | 5.5 | 5 | 10 | 5 | 50 | 6 | 20 | 12 | 12 | 12 | 12 | 7.5 | 85 Ohms | TOP=L2:L3=L2/L4:L6=L5/L7:BOTTOM=L7 |
| PCIE_TX_N14 | TX14-DIFF1 | PAIR | 7 | 5.5 | 5 | 10 | 5 | 50 | 6 | 20 | 12 | 12 | 12 | 12 | 7.5 | 85 Ohms | TOP=L2:L3=L2/L4:L6=L5/L7:BOTTOM=L7 |
| PCIE_TX_N14 | TX14-DIFF1 | PAIR | 8 | 5.38 | 5 | 10 | 5 | 50 | 6 | 33 | 12 | 12 | 12 | 12 | 6.62 | 85 Ohms | TOP=L2:L3=L2/L4:L6=L5/L7:BOTTOM=L7 |
| PCIE_TX_P14 | TX14-DIFF1 | PAIR | 1 | 5.38 | 5 | 10 | 5 | 50 | 6 | 33 | 12 | 12 | 12 | 12 | 6.62 | 85 Ohms | TOP=L2:L3=L2/L4:L6=L5/L7:BOTTOM=L7 |
| PCIE_TX_P14 | TX14-DIFF1 | PAIR | 2 | 5.5 | 5 | 10 | 5 | 50 | 6 | 20 | 12 | 12 | 12 | 12 | 7.5 | 85 Ohms | TOP=L2:L3=L2/L4:L6=L5/L7:BOTTOM=L7 |
| PCIE_TX_P14 | TX14-DIFF1 | PAIR | 3 | 5.5 | 5 | 10 | 5 | 50 | 6 | 20 | 12 | 12 | 12 | 12 | 7.5 | 85 Ohms | TOP=L2:L3=L2/L4:L6=L5/L7:BOTTOM=L7 |
| PCIE_TX_P14 | TX14-DIFF1 | PAIR | 4 | 5.5 | 5 | 10 | 5 | 50 | 6 | 20 | 12 | 12 | 12 | 12 | 7.5 | 85 Ohms | TOP=L2:L3=L2/L4:L6=L5/L7:BOTTOM=L7 |
| PCIE_TX_P14 | TX14-DIFF1 | PAIR | 5 | 5.5 | 5 | 10 | 5 | 50 | 6 | 20 | 12 | 12 | 12 | 12 | 7.5 | 85 Ohms | TOP=L2:L3=L2/L4:L6=L5/L7:BOTTOM=L7 |
| PCIE_TX_P14 | TX14-DIFF1 | PAIR | 6 | 5.5 | 5 | 10 | 5 | 50 | 6 | 20 | 12 | 12 | 12 | 12 | 7.5 | 85 Ohms | TOP=L2:L3=L2/L4:L6=L5/L7:BOTTOM=L7 |
| PCIE_TX_P14 | TX14-DIFF1 | PAIR | 7 | 5.5 | 5 | 10 | 5 | 50 | 6 | 20 | 12 | 12 | 12 | 12 | 7.5 | 85 Ohms | TOP=L2:L3=L2/L4:L6=L5/L7:BOTTOM=L7 |
| PCIE_TX_P14 | TX14-DIFF1 | PAIR | 8 | 5.38 | 5 | 10 | 5 | 50 | 6 | 33 | 12 | 12 | 12 | 12 | 6.62 | 85 Ohms | TOP=L2:L3=L2/L4:L6=L5/L7:BOTTOM=L7 |
| PCIE_TX_N15 | TX15-DIFF1 | PAIR | 1 | 5.38 | 5 | 10 | 5 | 50 | 6 | 33 | 12 | 12 | 12 | 12 | 6.62 | 85 Ohms | TOP=L2:L3=L2/L4:L6=L5/L7:BOTTOM=L7 |
| PCIE_TX_N15 | TX15-DIFF1 | PAIR | 2 | 5.5 | 5 | 10 | 5 | 50 | 6 | 20 | 12 | 12 | 12 | 12 | 7.5 | 85 Ohms | TOP=L2:L3=L2/L4:L6=L5/L7:BOTTOM=L7 |
| PCIE_TX_N15 | TX15-DIFF1 | PAIR | 3 | 5.5 | 5 | 10 | 5 | 50 | 6 | 20 | 12 | 12 | 12 | 12 | 7.5 | 85 Ohms | TOP=L2:L3=L2/L4:L6=L5/L7:BOTTOM=L7 |
| PCIE_TX_N15 | TX15-DIFF1 | PAIR | 4 | 5.5 | 5 | 10 | 5 | 50 | 6 | 20 | 12 | 12 | 12 | 12 | 7.5 | 85 Ohms | TOP=L2:L3=L2/L4:L6=L5/L7:BOTTOM=L7 |
| PCIE_TX_N15 | TX15-DIFF1 | PAIR | 5 | 5.5 | 5 | 10 | 5 | 50 | 6 | 20 | 12 | 12 | 12 | 12 | 7.5 | 85 Ohms | TOP=L2:L3=L2/L4:L6=L5/L7:BOTTOM=L7 |
| PCIE_TX_N15 | TX15-DIFF1 | PAIR | 6 | 5.5 | 5 | 10 | 5 | 50 | 6 | 20 | 12 | 12 | 12 | 12 | 7.5 | 85 Ohms | TOP=L2:L3=L2/L4:L6=L5/L7:BOTTOM=L7 |
| PCIE_TX_N15 | TX15-DIFF1 | PAIR | 7 | 5.5 | 5 | 10 | 5 | 50 | 6 | 20 | 12 | 12 | 12 | 12 | 7.5 | 85 Ohms | TOP=L2:L3=L2/L4:L6=L5/L7:BOTTOM=L7 |
| PCIE_TX_N15 | TX15-DIFF1 | PAIR | 8 | 5.38 | 5 | 10 | 5 | 50 | 6 | 33 | 12 | 12 | 12 | 12 | 6.62 | 85 Ohms | TOP=L2:L3=L2/L4:L6=L5/L7:BOTTOM=L7 |
| PCIE_TX_P15 | TX15-DIFF1 | PAIR | 1 | 5.38 | 5 | 10 | 5 | 50 | 6 | 33 | 12 | 12 | 12 | 12 | 6.62 | 85 Ohms | TOP=L2:L3=L2/L4:L6=L5/L7:BOTTOM=L7 |
| PCIE_TX_P15 | TX15-DIFF1 | PAIR | 2 | 5.5 | 5 | 10 | 5 | 50 | 6 | 20 | 12 | 12 | 12 | 12 | 7.5 | 85 Ohms | TOP=L2:L3=L2/L4:L6=L5/L7:BOTTOM=L7 |
| PCIE_TX_P15 | TX15-DIFF1 | PAIR | 3 | 5.5 | 5 | 10 | 5 | 50 | 6 | 20 | 12 | 12 | 12 | 12 | 7.5 | 85 Ohms | TOP=L2:L3=L2/L4:L6=L5/L7:BOTTOM=L7 |
| PCIE_TX_P15 | TX15-DIFF1 | PAIR | 4 | 5.5 | 5 | 10 | 5 | 50 | 6 | 20 | 12 | 12 | 12 | 12 | 7.5 | 85 Ohms | TOP=L2:L3=L2/L4:L6=L5/L7:BOTTOM=L7 |
| PCIE_TX_P15 | TX15-DIFF1 | PAIR | 5 | 5.5 | 5 | 10 | 5 | 50 | 6 | 20 | 12 | 12 | 12 | 12 | 7.5 | 85 Ohms | TOP=L2:L3=L2/L4:L6=L5/L7:BOTTOM=L7 |
| PCIE_TX_P15 | TX15-DIFF1 | PAIR | 6 | 5.5 | 5 | 10 | 5 | 50 | 6 | 20 | 12 | 12 | 12 | 12 | 7.5 | 85 Ohms | TOP=L2:L3=L2/L4:L6=L5/L7:BOTTOM=L7 |
| PCIE_TX_P15 | TX15-DIFF1 | PAIR | 7 | 5.5 | 5 | 10 | 5 | 50 | 6 | 20 | 12 | 12 | 12 | 12 | 7.5 | 85 Ohms | TOP=L2:L3=L2/L4:L6=L5/L7:BOTTOM=L7 |
| PCIE_TX_P15 | TX15-DIFF1 | PAIR | 8 | 5.38 | 5 | 10 | 5 | 50 | 6 | 33 | 12 | 12 | 12 | 12 | 6.62 | 85 Ohms | TOP=L2:L3=L2/L4:L6=L5/L7:BOTTOM=L7 |
| PCIE_TX_N16 | TX16-DIFF1 | PAIR | 1 | 5.38 | 5 | 10 | 5 | 50 | 6 | 33 | 12 | 12 | 12 | 12 | 6.62 | 85 Ohms | TOP=L2:L3=L2/L4:L6=L5/L7:BOTTOM=L7 |
| PCIE_TX_N16 | TX16-DIFF1 | PAIR | 2 | 5.5 | 5 | 10 | 5 | 50 | 6 | 20 | 12 | 12 | 12 | 12 | 7.5 | 85 Ohms | TOP=L2:L3=L2/L4:L6=L5/L7:BOTTOM=L7 |
| PCIE_TX_N16 | TX16-DIFF1 | PAIR | 3 | 5.5 | 5 | 10 | 5 | 50 | 6 | 20 | 12 | 12 | 12 | 12 | 7.5 | 85 Ohms | TOP=L2:L3=L2/L4:L6=L5/L7:BOTTOM=L7 |
| PCIE_TX_N16 | TX16-DIFF1 | PAIR | 4 | 5.5 | 5 | 10 | 5 | 50 | 6 | 20 | 12 | 12 | 12 | 12 | 7.5 | 85 Ohms | TOP=L2:L3=L2/L4:L6=L5/L7:BOTTOM=L7 |
| PCIE_TX_N16 | TX16-DIFF1 | PAIR | 5 | 5.5 | 5 | 10 | 5 | 50 | 6 | 20 | 12 | 12 | 12 | 12 | 7.5 | 85 Ohms | TOP=L2:L3=L2/L4:L6=L5/L7:BOTTOM=L7 |
| PCIE_TX_N16 | TX16-DIFF1 | PAIR | 6 | 5.5 | 5 | 10 | 5 | 50 | 6 | 20 | 12 | 12 | 12 | 12 | 7.5 | 85 Ohms | TOP=L2:L3=L2/L4:L6=L5/L7:BOTTOM=L7 |
| PCIE_TX_N16 | TX16-DIFF1 | PAIR | 7 | 5.5 | 5 | 10 | 5 | 50 | 6 | 20 | 12 | 12 | 12 | 12 | 7.5 | 85 Ohms | TOP=L2:L3=L2/L4:L6=L5/L7:BOTTOM=L7 |
| PCIE_TX_N16 | TX16-DIFF1 | PAIR | 8 | 5.38 | 5 | 10 | 5 | 50 | 6 | 33 | 12 | 12 | 12 | 12 | 6.62 | 85 Ohms | TOP=L2:L3=L2/L4:L6=L5/L7:BOTTOM=L7 |
| PCIE_TX_P16 | TX16-DIFF1 | PAIR | 1 | 5.38 | 5 | 10 | 5 | 50 | 6 | 33 | 12 | 12 | 12 | 12 | 6.62 | 85 Ohms | TOP=L2:L3=L2/L4:L6=L5/L7:BOTTOM=L7 |
| PCIE_TX_P16 | TX16-DIFF1 | PAIR | 2 | 5.5 | 5 | 10 | 5 | 50 | 6 | 20 | 12 | 12 | 12 | 12 | 7.5 | 85 Ohms | TOP=L2:L3=L2/L4:L6=L5/L7:BOTTOM=L7 |
| PCIE_TX_P16 | TX16-DIFF1 | PAIR | 3 | 5.5 | 5 | 10 | 5 | 50 | 6 | 20 | 12 | 12 | 12 | 12 | 7.5 | 85 Ohms | TOP=L2:L3=L2/L4:L6=L5/L7:BOTTOM=L7 |
| PCIE_TX_P16 | TX16-DIFF1 | PAIR | 4 | 5.5 | 5 | 10 | 5 | 50 | 6 | 20 | 12 | 12 | 12 | 12 | 7.5 | 85 Ohms | TOP=L2:L3=L2/L4:L6=L5/L7:BOTTOM=L7 |
| PCIE_TX_P16 | TX16-DIFF1 | PAIR | 5 | 5.5 | 5 | 10 | 5 | 50 | 6 | 20 | 12 | 12 | 12 | 12 | 7.5 | 85 Ohms | TOP=L2:L3=L2/L4:L6=L5/L7:BOTTOM=L7 |
| PCIE_TX_P16 | TX16-DIFF1 | PAIR | 6 | 5.5 | 5 | 10 | 5 | 50 | 6 | 20 | 12 | 12 | 12 | 12 | 7.5 | 85 Ohms | TOP=L2:L3=L2/L4:L6=L5/L7:BOTTOM=L7 |
| PCIE_TX_P16 | TX16-DIFF1 | PAIR | 7 | 5.5 | 5 | 10 | 5 | 50 | 6 | 20 | 12 | 12 | 12 | 12 | 7.5 | 85 Ohms | TOP=L2:L3=L2/L4:L6=L5/L7:BOTTOM=L7 |
| PCIE_TX_P16 | TX16-DIFF1 | PAIR | 8 | 5.38 | 5 | 10 | 5 | 50 | 6 | 33 | 12 | 12 | 12 | 12 | 6.62 | 85 Ohms | TOP=L2:L3=L2/L4:L6=L5/L7:BOTTOM=L7 |
| PCIE_TX_N17 | TX17-DIFF1 | PAIR | 1 | 5.38 | 5 | 10 | 5 | 50 | 6 | 33 | 12 | 12 | 12 | 12 | 6.62 | 85 Ohms | TOP=L2:L3=L2/L4:L6=L5/L7:BOTTOM=L7 |
| PCIE_TX_N17 | TX17-DIFF1 | PAIR | 2 | 5.5 | 5 | 10 | 5 | 50 | 6 | 20 | 12 | 12 | 12 | 12 | 7.5 | 85 Ohms | TOP=L2:L3=L2/L4:L6=L5/L7:BOTTOM=L7 |
| PCIE_TX_N17 | TX17-DIFF1 | PAIR | 3 | 5.5 | 5 | 10 | 5 | 50 | 6 | 20 | 12 | 12 | 12 | 12 | 7.5 | 85 Ohms | TOP=L2:L3=L2/L4:L6=L5/L7:BOTTOM=L7 |
| PCIE_TX_N17 | TX17-DIFF1 | PAIR | 4 | 5.5 | 5 | 10 | 5 | 50 | 6 | 20 | 12 | 12 | 12 | 12 | 7.5 | 85 Ohms | TOP=L2:L3=L2/L4:L6=L5/L7:BOTTOM=L7 |
| PCIE_TX_N17 | TX17-DIFF1 | PAIR | 5 | 5.5 | 5 | 10 | 5 | 50 | 6 | 20 | 12 | 12 | 12 | 12 | 7.5 | 85 Ohms | TOP=L2:L3=L2/L4:L6=L5/L7:BOTTOM=L7 |
| PCIE_TX_N17 | TX17-DIFF1 | PAIR | 6 | 5.5 | 5 | 10 | 5 | 50 | 6 | 20 | 12 | 12 | 12 | 12 | 7.5 | 85 Ohms | TOP=L2:L3=L2/L4:L6=L5/L7:BOTTOM=L7 |
| PCIE_TX_N17 | TX17-DIFF1 | PAIR | 7 | 5.5 | 5 | 10 | 5 | 50 | 6 | 20 | 12 | 12 | 12 | 12 | 7.5 | 85 Ohms | TOP=L2:L3=L2/L4:L6=L5/L7:BOTTOM=L7 |
| PCIE_TX_N17 | TX17-DIFF1 | PAIR | 8 | 5.38 | 5 | 10 | 5 | 50 | 6 | 33 | 12 | 12 | 12 | 12 | 6.62 | 85 Ohms | TOP=L2:L3=L2/L4:L6=L5/L7:BOTTOM=L7 |
| PCIE_TX_P17 | TX17-DIFF1 | PAIR | 1 | 5.38 | 5 | 10 | 5 | 50 | 6 | 33 | 12 | 12 | 12 | 12 | 6.62 | 85 Ohms | TOP=L2:L3=L2/L4:L6=L5/L7:BOTTOM=L7 |
| PCIE_TX_P17 | TX17-DIFF1 | PAIR | 2 | 5.5 | 5 | 10 | 5 | 50 | 6 | 20 | 12 | 12 | 12 | 12 | 7.5 | 85 Ohms | TOP=L2:L3=L2/L4:L6=L5/L7:BOTTOM=L7 |
| PCIE_TX_P17 | TX17-DIFF1 | PAIR | 3 | 5.5 | 5 | 10 | 5 | 50 | 6 | 20 | 12 | 12 | 12 | 12 | 7.5 | 85 Ohms | TOP=L2:L3=L2/L4:L6=L5/L7:BOTTOM=L7 |
| PCIE_TX_P17 | TX17-DIFF1 | PAIR | 4 | 5.5 | 5 | 10 | 5 | 50 | 6 | 20 | 12 | 12 | 12 | 12 | 7.5 | 85 Ohms | TOP=L2:L3=L2/L4:L6=L5/L7:BOTTOM=L7 |
| PCIE_TX_P17 | TX17-DIFF1 | PAIR | 5 | 5.5 | 5 | 10 | 5 | 50 | 6 | 20 | 12 | 12 | 12 | 12 | 7.5 | 85 Ohms | TOP=L2:L3=L2/L4:L6=L5/L7:BOTTOM=L7 |
| PCIE_TX_P17 | TX17-DIFF1 | PAIR | 6 | 5.5 | 5 | 10 | 5 | 50 | 6 | 20 | 12 | 12 | 12 | 12 | 7.5 | 85 Ohms | TOP=L2:L3=L2/L4:L6=L5/L7:BOTTOM=L7 |
| PCIE_TX_P17 | TX17-DIFF1 | PAIR | 7 | 5.5 | 5 | 10 | 5 | 50 | 6 | 20 | 12 | 12 | 12 | 12 | 7.5 | 85 Ohms | TOP=L2:L3=L2/L4:L6=L5/L7:BOTTOM=L7 |
| PCIE_TX_P17 | TX17-DIFF1 | PAIR | 8 | 5.38 | 5 | 10 | 5 | 50 | 6 | 33 | 12 | 12 | 12 | 12 | 6.62 | 85 Ohms | TOP=L2:L3=L2/L4:L6=L5/L7:BOTTOM=L7 |
| PCIE_TX_N18 | TX18-DIFF1 | PAIR | 1 | 5.38 | 5 | 10 | 5 | 50 | 6 | 33 | 12 | 12 | 12 | 12 | 6.62 | 85 Ohms | TOP=L2:L3=L2/L4:L6=L5/L7:BOTTOM=L7 |
| PCIE_TX_N18 | TX18-DIFF1 | PAIR | 2 | 5.5 | 5 | 10 | 5 | 50 | 6 | 20 | 12 | 12 | 12 | 12 | 7.5 | 85 Ohms | TOP=L2:L3=L2/L4:L6=L5/L7:BOTTOM=L7 |
| PCIE_TX_N18 | TX18-DIFF1 | PAIR | 3 | 5.5 | 5 | 10 | 5 | 50 | 6 | 20 | 12 | 12 | 12 | 12 | 7.5 | 85 Ohms | TOP=L2:L3=L2/L4:L6=L5/L7:BOTTOM=L7 |
| PCIE_TX_N18 | TX18-DIFF1 | PAIR | 4 | 5.5 | 5 | 10 | 5 | 50 | 6 | 20 | 12 | 12 | 12 | 12 | 7.5 | 85 Ohms | TOP=L2:L3=L2/L4:L6=L5/L7:BOTTOM=L7 |
| PCIE_TX_N18 | TX18-DIFF1 | PAIR | 5 | 5.5 | 5 | 10 | 5 | 50 | 6 | 20 | 12 | 12 | 12 | 12 | 7.5 | 85 Ohms | TOP=L2:L3=L2/L4:L6=L5/L7:BOTTOM=L7 |
| PCIE_TX_N18 | TX18-DIFF1 | PAIR | 6 | 5.5 | 5 | 10 | 5 | 50 | 6 | 20 | 12 | 12 | 12 | 12 | 7.5 | 85 Ohms | TOP=L2:L3=L2/L4:L6=L5/L7:BOTTOM=L7 |
| PCIE_TX_N18 | TX18-DIFF1 | PAIR | 7 | 5.5 | 5 | 10 | 5 | 50 | 6 | 20 | 12 | 12 | 12 | 12 | 7.5 | 85 Ohms | TOP=L2:L3=L2/L4:L6=L5/L7:BOTTOM=L7 |
| PCIE_TX_N18 | TX18-DIFF1 | PAIR | 8 | 5.38 | 5 | 10 | 5 | 50 | 6 | 33 | 12 | 12 | 12 | 12 | 6.62 | 85 Ohms | TOP=L2:L3=L2/L4:L6=L5/L7:BOTTOM=L7 |
| PCIE_TX_P18 | TX18-DIFF1 | PAIR | 1 | 5.38 | 5 | 10 | 5 | 50 | 6 | 33 | 12 | 12 | 12 | 12 | 6.62 | 85 Ohms | TOP=L2:L3=L2/L4:L6=L5/L7:BOTTOM=L7 |
| PCIE_TX_P18 | TX18-DIFF1 | PAIR | 2 | 5.5 | 5 | 10 | 5 | 50 | 6 | 20 | 12 | 12 | 12 | 12 | 7.5 | 85 Ohms | TOP=L2:L3=L2/L4:L6=L5/L7:BOTTOM=L7 |
| PCIE_TX_P18 | TX18-DIFF1 | PAIR | 3 | 5.5 | 5 | 10 | 5 | 50 | 6 | 20 | 12 | 12 | 12 | 12 | 7.5 | 85 Ohms | TOP=L2:L3=L2/L4:L6=L5/L7:BOTTOM=L7 |
| PCIE_TX_P18 | TX18-DIFF1 | PAIR | 4 | 5.5 | 5 | 10 | 5 | 50 | 6 | 20 | 12 | 12 | 12 | 12 | 7.5 | 85 Ohms | TOP=L2:L3=L2/L4:L6=L5/L7:BOTTOM=L7 |
| PCIE_TX_P18 | TX18-DIFF1 | PAIR | 5 | 5.5 | 5 | 10 | 5 | 50 | 6 | 20 | 12 | 12 | 12 | 12 | 7.5 | 85 Ohms | TOP=L2:L3=L2/L4:L6=L5/L7:BOTTOM=L7 |
| PCIE_TX_P18 | TX18-DIFF1 | PAIR | 6 | 5.5 | 5 | 10 | 5 | 50 | 6 | 20 | 12 | 12 | 12 | 12 | 7.5 | 85 Ohms | TOP=L2:L3=L2/L4:L6=L5/L7:BOTTOM=L7 |
| PCIE_TX_P18 | TX18-DIFF1 | PAIR | 7 | 5.5 | 5 | 10 | 5 | 50 | 6 | 20 | 12 | 12 | 12 | 12 | 7.5 | 85 Ohms | TOP=L2:L3=L2/L4:L6=L5/L7:BOTTOM=L7 |
| PCIE_TX_P18 | TX18-DIFF1 | PAIR | 8 | 5.38 | 5 | 10 | 5 | 50 | 6 | 33 | 12 | 12 | 12 | 12 | 6.62 | 85 Ohms | TOP=L2:L3=L2/L4:L6=L5/L7:BOTTOM=L7 |
| PCIE_TX_N19 | TX19-DIFF1 | PAIR | 1 | 5.38 | 5 | 10 | 5 | 50 | 6 | 33 | 12 | 12 | 12 | 12 | 6.62 | 85 Ohms | TOP=L2:L3=L2/L4:L6=L5/L7:BOTTOM=L7 |
| PCIE_TX_N19 | TX19-DIFF1 | PAIR | 2 | 5.5 | 5 | 10 | 5 | 50 | 6 | 20 | 12 | 12 | 12 | 12 | 7.5 | 85 Ohms | TOP=L2:L3=L2/L4:L6=L5/L7:BOTTOM=L7 |
| PCIE_TX_N19 | TX19-DIFF1 | PAIR | 3 | 5.5 | 5 | 10 | 5 | 50 | 6 | 20 | 12 | 12 | 12 | 12 | 7.5 | 85 Ohms | TOP=L2:L3=L2/L4:L6=L5/L7:BOTTOM=L7 |
| PCIE_TX_N19 | TX19-DIFF1 | PAIR | 4 | 5.5 | 5 | 10 | 5 | 50 | 6 | 20 | 12 | 12 | 12 | 12 | 7.5 | 85 Ohms | TOP=L2:L3=L2/L4:L6=L5/L7:BOTTOM=L7 |
| PCIE_TX_N19 | TX19-DIFF1 | PAIR | 5 | 5.5 | 5 | 10 | 5 | 50 | 6 | 20 | 12 | 12 | 12 | 12 | 7.5 | 85 Ohms | TOP=L2:L3=L2/L4:L6=L5/L7:BOTTOM=L7 |
| PCIE_TX_N19 | TX19-DIFF1 | PAIR | 6 | 5.5 | 5 | 10 | 5 | 50 | 6 | 20 | 12 | 12 | 12 | 12 | 7.5 | 85 Ohms | TOP=L2:L3=L2/L4:L6=L5/L7:BOTTOM=L7 |
| PCIE_TX_N19 | TX19-DIFF1 | PAIR | 7 | 5.5 | 5 | 10 | 5 | 50 | 6 | 20 | 12 | 12 | 12 | 12 | 7.5 | 85 Ohms | TOP=L2:L3=L2/L4:L6=L5/L7:BOTTOM=L7 |
| PCIE_TX_N19 | TX19-DIFF1 | PAIR | 8 | 5.38 | 5 | 10 | 5 | 50 | 6 | 33 | 12 | 12 | 12 | 12 | 6.62 | 85 Ohms | TOP=L2:L3=L2/L4:L6=L5/L7:BOTTOM=L7 |
| PCIE_TX_P19 | TX19-DIFF1 | PAIR | 1 | 5.38 | 5 | 10 | 5 | 50 | 6 | 33 | 12 | 12 | 12 | 12 | 6.62 | 85 Ohms | TOP=L2:L3=L2/L4:L6=L5/L7:BOTTOM=L7 |
| PCIE_TX_P19 | TX19-DIFF1 | PAIR | 2 | 5.5 | 5 | 10 | 5 | 50 | 6 | 20 | 12 | 12 | 12 | 12 | 7.5 | 85 Ohms | TOP=L2:L3=L2/L4:L6=L5/L7:BOTTOM=L7 |
| PCIE_TX_P19 | TX19-DIFF1 | PAIR | 3 | 5.5 | 5 | 10 | 5 | 50 | 6 | 20 | 12 | 12 | 12 | 12 | 7.5 | 85 Ohms | TOP=L2:L3=L2/L4:L6=L5/L7:BOTTOM=L7 |
| PCIE_TX_P19 | TX19-DIFF1 | PAIR | 4 | 5.5 | 5 | 10 | 5 | 50 | 6 | 20 | 12 | 12 | 12 | 12 | 7.5 | 85 Ohms | TOP=L2:L3=L2/L4:L6=L5/L7:BOTTOM=L7 |
| PCIE_TX_P19 | TX19-DIFF1 | PAIR | 5 | 5.5 | 5 | 10 | 5 | 50 | 6 | 20 | 12 | 12 | 12 | 12 | 7.5 | 85 Ohms | TOP=L2:L3=L2/L4:L6=L5/L7:BOTTOM=L7 |
| PCIE_TX_P19 | TX19-DIFF1 | PAIR | 6 | 5.5 | 5 | 10 | 5 | 50 | 6 | 20 | 12 | 12 | 12 | 12 | 7.5 | 85 Ohms | TOP=L2:L3=L2/L4:L6=L5/L7:BOTTOM=L7 |
| PCIE_TX_P19 | TX19-DIFF1 | PAIR | 7 | 5.5 | 5 | 10 | 5 | 50 | 6 | 20 | 12 | 12 | 12 | 12 | 7.5 | 85 Ohms | TOP=L2:L3=L2/L4:L6=L5/L7:BOTTOM=L7 |
| PCIE_TX_P19 | TX19-DIFF1 | PAIR | 8 | 5.38 | 5 | 10 | 5 | 50 | 6 | 33 | 12 | 12 | 12 | 12 | 6.62 | 85 Ohms | TOP=L2:L3=L2/L4:L6=L5/L7:BOTTOM=L7 |
| PCIE_TX_N1 | TX1-DIFF1 | PAIR | 1 | 5.38 | 5 | 10 | 5 | 50 | 6 | 33 | 12 | 12 | 12 | 12 | 6.62 | 85 Ohms | TOP=L2:L3=L2/L4:L6=L5/L7:BOTTOM=L7 |
| PCIE_TX_N1 | TX1-DIFF1 | PAIR | 2 | 5.5 | 5 | 10 | 5 | 50 | 6 | 20 | 12 | 12 | 12 | 12 | 7.5 | 85 Ohms | TOP=L2:L3=L2/L4:L6=L5/L7:BOTTOM=L7 |
| PCIE_TX_N1 | TX1-DIFF1 | PAIR | 3 | 5.5 | 5 | 10 | 5 | 50 | 6 | 20 | 12 | 12 | 12 | 12 | 7.5 | 85 Ohms | TOP=L2:L3=L2/L4:L6=L5/L7:BOTTOM=L7 |
| PCIE_TX_N1 | TX1-DIFF1 | PAIR | 4 | 5.5 | 5 | 10 | 5 | 50 | 6 | 20 | 12 | 12 | 12 | 12 | 7.5 | 85 Ohms | TOP=L2:L3=L2/L4:L6=L5/L7:BOTTOM=L7 |
| PCIE_TX_N1 | TX1-DIFF1 | PAIR | 5 | 5.5 | 5 | 10 | 5 | 50 | 6 | 20 | 12 | 12 | 12 | 12 | 7.5 | 85 Ohms | TOP=L2:L3=L2/L4:L6=L5/L7:BOTTOM=L7 |
| PCIE_TX_N1 | TX1-DIFF1 | PAIR | 6 | 5.5 | 5 | 10 | 5 | 50 | 6 | 20 | 12 | 12 | 12 | 12 | 7.5 | 85 Ohms | TOP=L2:L3=L2/L4:L6=L5/L7:BOTTOM=L7 |
| PCIE_TX_N1 | TX1-DIFF1 | PAIR | 7 | 5.5 | 5 | 10 | 5 | 50 | 6 | 20 | 12 | 12 | 12 | 12 | 7.5 | 85 Ohms | TOP=L2:L3=L2/L4:L6=L5/L7:BOTTOM=L7 |
| PCIE_TX_N1 | TX1-DIFF1 | PAIR | 8 | 5.38 | 5 | 10 | 5 | 50 | 6 | 33 | 12 | 12 | 12 | 12 | 6.62 | 85 Ohms | TOP=L2:L3=L2/L4:L6=L5/L7:BOTTOM=L7 |
| PCIE_TX_P1 | TX1-DIFF1 | PAIR | 1 | 5.38 | 5 | 10 | 5 | 50 | 6 | 33 | 12 | 12 | 12 | 12 | 6.62 | 85 Ohms | TOP=L2:L3=L2/L4:L6=L5/L7:BOTTOM=L7 |
| PCIE_TX_P1 | TX1-DIFF1 | PAIR | 2 | 5.5 | 5 | 10 | 5 | 50 | 6 | 20 | 12 | 12 | 12 | 12 | 7.5 | 85 Ohms | TOP=L2:L3=L2/L4:L6=L5/L7:BOTTOM=L7 |
| PCIE_TX_P1 | TX1-DIFF1 | PAIR | 3 | 5.5 | 5 | 10 | 5 | 50 | 6 | 20 | 12 | 12 | 12 | 12 | 7.5 | 85 Ohms | TOP=L2:L3=L2/L4:L6=L5/L7:BOTTOM=L7 |
| PCIE_TX_P1 | TX1-DIFF1 | PAIR | 4 | 5.5 | 5 | 10 | 5 | 50 | 6 | 20 | 12 | 12 | 12 | 12 | 7.5 | 85 Ohms | TOP=L2:L3=L2/L4:L6=L5/L7:BOTTOM=L7 |
| PCIE_TX_P1 | TX1-DIFF1 | PAIR | 5 | 5.5 | 5 | 10 | 5 | 50 | 6 | 20 | 12 | 12 | 12 | 12 | 7.5 | 85 Ohms | TOP=L2:L3=L2/L4:L6=L5/L7:BOTTOM=L7 |
| PCIE_TX_P1 | TX1-DIFF1 | PAIR | 6 | 5.5 | 5 | 10 | 5 | 50 | 6 | 20 | 12 | 12 | 12 | 12 | 7.5 | 85 Ohms | TOP=L2:L3=L2/L4:L6=L5/L7:BOTTOM=L7 |
| PCIE_TX_P1 | TX1-DIFF1 | PAIR | 7 | 5.5 | 5 | 10 | 5 | 50 | 6 | 20 | 12 | 12 | 12 | 12 | 7.5 | 85 Ohms | TOP=L2:L3=L2/L4:L6=L5/L7:BOTTOM=L7 |
| PCIE_TX_P1 | TX1-DIFF1 | PAIR | 8 | 5.38 | 5 | 10 | 5 | 50 | 6 | 33 | 12 | 12 | 12 | 12 | 6.62 | 85 Ohms | TOP=L2:L3=L2/L4:L6=L5/L7:BOTTOM=L7 |
| PCIE_TX_N20 | TX20-DIFF1 | PAIR | 1 | 5.38 | 5 | 10 | 5 | 50 | 6 | 33 | 12 | 12 | 12 | 12 | 6.62 | 85 Ohms | TOP=L2:L3=L2/L4:L6=L5/L7:BOTTOM=L7 |
| PCIE_TX_N20 | TX20-DIFF1 | PAIR | 2 | 5.5 | 5 | 10 | 5 | 50 | 6 | 20 | 12 | 12 | 12 | 12 | 7.5 | 85 Ohms | TOP=L2:L3=L2/L4:L6=L5/L7:BOTTOM=L7 |
| PCIE_TX_N20 | TX20-DIFF1 | PAIR | 3 | 5.5 | 5 | 10 | 5 | 50 | 6 | 20 | 12 | 12 | 12 | 12 | 7.5 | 85 Ohms | TOP=L2:L3=L2/L4:L6=L5/L7:BOTTOM=L7 |
| PCIE_TX_N20 | TX20-DIFF1 | PAIR | 4 | 5.5 | 5 | 10 | 5 | 50 | 6 | 20 | 12 | 12 | 12 | 12 | 7.5 | 85 Ohms | TOP=L2:L3=L2/L4:L6=L5/L7:BOTTOM=L7 |
| PCIE_TX_N20 | TX20-DIFF1 | PAIR | 5 | 5.5 | 5 | 10 | 5 | 50 | 6 | 20 | 12 | 12 | 12 | 12 | 7.5 | 85 Ohms | TOP=L2:L3=L2/L4:L6=L5/L7:BOTTOM=L7 |
| PCIE_TX_N20 | TX20-DIFF1 | PAIR | 6 | 5.5 | 5 | 10 | 5 | 50 | 6 | 20 | 12 | 12 | 12 | 12 | 7.5 | 85 Ohms | TOP=L2:L3=L2/L4:L6=L5/L7:BOTTOM=L7 |
| PCIE_TX_N20 | TX20-DIFF1 | PAIR | 7 | 5.5 | 5 | 10 | 5 | 50 | 6 | 20 | 12 | 12 | 12 | 12 | 7.5 | 85 Ohms | TOP=L2:L3=L2/L4:L6=L5/L7:BOTTOM=L7 |
| PCIE_TX_N20 | TX20-DIFF1 | PAIR | 8 | 5.38 | 5 | 10 | 5 | 50 | 6 | 33 | 12 | 12 | 12 | 12 | 6.62 | 85 Ohms | TOP=L2:L3=L2/L4:L6=L5/L7:BOTTOM=L7 |
| PCIE_TX_P20 | TX20-DIFF1 | PAIR | 1 | 5.38 | 5 | 10 | 5 | 50 | 6 | 33 | 12 | 12 | 12 | 12 | 6.62 | 85 Ohms | TOP=L2:L3=L2/L4:L6=L5/L7:BOTTOM=L7 |
| PCIE_TX_P20 | TX20-DIFF1 | PAIR | 2 | 5.5 | 5 | 10 | 5 | 50 | 6 | 20 | 12 | 12 | 12 | 12 | 7.5 | 85 Ohms | TOP=L2:L3=L2/L4:L6=L5/L7:BOTTOM=L7 |
| PCIE_TX_P20 | TX20-DIFF1 | PAIR | 3 | 5.5 | 5 | 10 | 5 | 50 | 6 | 20 | 12 | 12 | 12 | 12 | 7.5 | 85 Ohms | TOP=L2:L3=L2/L4:L6=L5/L7:BOTTOM=L7 |
| PCIE_TX_P20 | TX20-DIFF1 | PAIR | 4 | 5.5 | 5 | 10 | 5 | 50 | 6 | 20 | 12 | 12 | 12 | 12 | 7.5 | 85 Ohms | TOP=L2:L3=L2/L4:L6=L5/L7:BOTTOM=L7 |
| PCIE_TX_P20 | TX20-DIFF1 | PAIR | 5 | 5.5 | 5 | 10 | 5 | 50 | 6 | 20 | 12 | 12 | 12 | 12 | 7.5 | 85 Ohms | TOP=L2:L3=L2/L4:L6=L5/L7:BOTTOM=L7 |
| PCIE_TX_P20 | TX20-DIFF1 | PAIR | 6 | 5.5 | 5 | 10 | 5 | 50 | 6 | 20 | 12 | 12 | 12 | 12 | 7.5 | 85 Ohms | TOP=L2:L3=L2/L4:L6=L5/L7:BOTTOM=L7 |
| PCIE_TX_P20 | TX20-DIFF1 | PAIR | 7 | 5.5 | 5 | 10 | 5 | 50 | 6 | 20 | 12 | 12 | 12 | 12 | 7.5 | 85 Ohms | TOP=L2:L3=L2/L4:L6=L5/L7:BOTTOM=L7 |
| PCIE_TX_P20 | TX20-DIFF1 | PAIR | 8 | 5.38 | 5 | 10 | 5 | 50 | 6 | 33 | 12 | 12 | 12 | 12 | 6.62 | 85 Ohms | TOP=L2:L3=L2/L4:L6=L5/L7:BOTTOM=L7 |
| PCIE_TX_N21 | TX21-DIFF1 | PAIR | 1 | 5.38 | 5 | 10 | 5 | 50 | 6 | 33 | 12 | 12 | 12 | 12 | 6.62 | 85 Ohms | TOP=L2:L3=L2/L4:L6=L5/L7:BOTTOM=L7 |
| PCIE_TX_N21 | TX21-DIFF1 | PAIR | 2 | 5.5 | 5 | 10 | 5 | 50 | 6 | 20 | 12 | 12 | 12 | 12 | 7.5 | 85 Ohms | TOP=L2:L3=L2/L4:L6=L5/L7:BOTTOM=L7 |
| PCIE_TX_N21 | TX21-DIFF1 | PAIR | 3 | 5.5 | 5 | 10 | 5 | 50 | 6 | 20 | 12 | 12 | 12 | 12 | 7.5 | 85 Ohms | TOP=L2:L3=L2/L4:L6=L5/L7:BOTTOM=L7 |
| PCIE_TX_N21 | TX21-DIFF1 | PAIR | 4 | 5.5 | 5 | 10 | 5 | 50 | 6 | 20 | 12 | 12 | 12 | 12 | 7.5 | 85 Ohms | TOP=L2:L3=L2/L4:L6=L5/L7:BOTTOM=L7 |
| PCIE_TX_N21 | TX21-DIFF1 | PAIR | 5 | 5.5 | 5 | 10 | 5 | 50 | 6 | 20 | 12 | 12 | 12 | 12 | 7.5 | 85 Ohms | TOP=L2:L3=L2/L4:L6=L5/L7:BOTTOM=L7 |
| PCIE_TX_N21 | TX21-DIFF1 | PAIR | 6 | 5.5 | 5 | 10 | 5 | 50 | 6 | 20 | 12 | 12 | 12 | 12 | 7.5 | 85 Ohms | TOP=L2:L3=L2/L4:L6=L5/L7:BOTTOM=L7 |
| PCIE_TX_N21 | TX21-DIFF1 | PAIR | 7 | 5.5 | 5 | 10 | 5 | 50 | 6 | 20 | 12 | 12 | 12 | 12 | 7.5 | 85 Ohms | TOP=L2:L3=L2/L4:L6=L5/L7:BOTTOM=L7 |
| PCIE_TX_N21 | TX21-DIFF1 | PAIR | 8 | 5.38 | 5 | 10 | 5 | 50 | 6 | 33 | 12 | 12 | 12 | 12 | 6.62 | 85 Ohms | TOP=L2:L3=L2/L4:L6=L5/L7:BOTTOM=L7 |
| PCIE_TX_P21 | TX21-DIFF1 | PAIR | 1 | 5.38 | 5 | 10 | 5 | 50 | 6 | 33 | 12 | 12 | 12 | 12 | 6.62 | 85 Ohms | TOP=L2:L3=L2/L4:L6=L5/L7:BOTTOM=L7 |
| PCIE_TX_P21 | TX21-DIFF1 | PAIR | 2 | 5.5 | 5 | 10 | 5 | 50 | 6 | 20 | 12 | 12 | 12 | 12 | 7.5 | 85 Ohms | TOP=L2:L3=L2/L4:L6=L5/L7:BOTTOM=L7 |
| PCIE_TX_P21 | TX21-DIFF1 | PAIR | 3 | 5.5 | 5 | 10 | 5 | 50 | 6 | 20 | 12 | 12 | 12 | 12 | 7.5 | 85 Ohms | TOP=L2:L3=L2/L4:L6=L5/L7:BOTTOM=L7 |
| PCIE_TX_P21 | TX21-DIFF1 | PAIR | 4 | 5.5 | 5 | 10 | 5 | 50 | 6 | 20 | 12 | 12 | 12 | 12 | 7.5 | 85 Ohms | TOP=L2:L3=L2/L4:L6=L5/L7:BOTTOM=L7 |
| PCIE_TX_P21 | TX21-DIFF1 | PAIR | 5 | 5.5 | 5 | 10 | 5 | 50 | 6 | 20 | 12 | 12 | 12 | 12 | 7.5 | 85 Ohms | TOP=L2:L3=L2/L4:L6=L5/L7:BOTTOM=L7 |
| PCIE_TX_P21 | TX21-DIFF1 | PAIR | 6 | 5.5 | 5 | 10 | 5 | 50 | 6 | 20 | 12 | 12 | 12 | 12 | 7.5 | 85 Ohms | TOP=L2:L3=L2/L4:L6=L5/L7:BOTTOM=L7 |
| PCIE_TX_P21 | TX21-DIFF1 | PAIR | 7 | 5.5 | 5 | 10 | 5 | 50 | 6 | 20 | 12 | 12 | 12 | 12 | 7.5 | 85 Ohms | TOP=L2:L3=L2/L4:L6=L5/L7:BOTTOM=L7 |
| PCIE_TX_P21 | TX21-DIFF1 | PAIR | 8 | 5.38 | 5 | 10 | 5 | 50 | 6 | 33 | 12 | 12 | 12 | 12 | 6.62 | 85 Ohms | TOP=L2:L3=L2/L4:L6=L5/L7:BOTTOM=L7 |
| PCIE_TX_N22 | TX22-DIFF1 | PAIR | 1 | 5.38 | 5 | 10 | 5 | 50 | 6 | 33 | 12 | 12 | 12 | 12 | 6.62 | 85 Ohms | TOP=L2:L3=L2/L4:L6=L5/L7:BOTTOM=L7 |
| PCIE_TX_N22 | TX22-DIFF1 | PAIR | 2 | 5.5 | 5 | 10 | 5 | 50 | 6 | 20 | 12 | 12 | 12 | 12 | 7.5 | 85 Ohms | TOP=L2:L3=L2/L4:L6=L5/L7:BOTTOM=L7 |
| PCIE_TX_N22 | TX22-DIFF1 | PAIR | 3 | 5.5 | 5 | 10 | 5 | 50 | 6 | 20 | 12 | 12 | 12 | 12 | 7.5 | 85 Ohms | TOP=L2:L3=L2/L4:L6=L5/L7:BOTTOM=L7 |
| PCIE_TX_N22 | TX22-DIFF1 | PAIR | 4 | 5.5 | 5 | 10 | 5 | 50 | 6 | 20 | 12 | 12 | 12 | 12 | 7.5 | 85 Ohms | TOP=L2:L3=L2/L4:L6=L5/L7:BOTTOM=L7 |
| PCIE_TX_N22 | TX22-DIFF1 | PAIR | 5 | 5.5 | 5 | 10 | 5 | 50 | 6 | 20 | 12 | 12 | 12 | 12 | 7.5 | 85 Ohms | TOP=L2:L3=L2/L4:L6=L5/L7:BOTTOM=L7 |
| PCIE_TX_N22 | TX22-DIFF1 | PAIR | 6 | 5.5 | 5 | 10 | 5 | 50 | 6 | 20 | 12 | 12 | 12 | 12 | 7.5 | 85 Ohms | TOP=L2:L3=L2/L4:L6=L5/L7:BOTTOM=L7 |
| PCIE_TX_N22 | TX22-DIFF1 | PAIR | 7 | 5.5 | 5 | 10 | 5 | 50 | 6 | 20 | 12 | 12 | 12 | 12 | 7.5 | 85 Ohms | TOP=L2:L3=L2/L4:L6=L5/L7:BOTTOM=L7 |
| PCIE_TX_N22 | TX22-DIFF1 | PAIR | 8 | 5.38 | 5 | 10 | 5 | 50 | 6 | 33 | 12 | 12 | 12 | 12 | 6.62 | 85 Ohms | TOP=L2:L3=L2/L4:L6=L5/L7:BOTTOM=L7 |
| PCIE_TX_P22 | TX22-DIFF1 | PAIR | 1 | 5.38 | 5 | 10 | 5 | 50 | 6 | 33 | 12 | 12 | 12 | 12 | 6.62 | 85 Ohms | TOP=L2:L3=L2/L4:L6=L5/L7:BOTTOM=L7 |
| PCIE_TX_P22 | TX22-DIFF1 | PAIR | 2 | 5.5 | 5 | 10 | 5 | 50 | 6 | 20 | 12 | 12 | 12 | 12 | 7.5 | 85 Ohms | TOP=L2:L3=L2/L4:L6=L5/L7:BOTTOM=L7 |
| PCIE_TX_P22 | TX22-DIFF1 | PAIR | 3 | 5.5 | 5 | 10 | 5 | 50 | 6 | 20 | 12 | 12 | 12 | 12 | 7.5 | 85 Ohms | TOP=L2:L3=L2/L4:L6=L5/L7:BOTTOM=L7 |
| PCIE_TX_P22 | TX22-DIFF1 | PAIR | 4 | 5.5 | 5 | 10 | 5 | 50 | 6 | 20 | 12 | 12 | 12 | 12 | 7.5 | 85 Ohms | TOP=L2:L3=L2/L4:L6=L5/L7:BOTTOM=L7 |
| PCIE_TX_P22 | TX22-DIFF1 | PAIR | 5 | 5.5 | 5 | 10 | 5 | 50 | 6 | 20 | 12 | 12 | 12 | 12 | 7.5 | 85 Ohms | TOP=L2:L3=L2/L4:L6=L5/L7:BOTTOM=L7 |
| PCIE_TX_P22 | TX22-DIFF1 | PAIR | 6 | 5.5 | 5 | 10 | 5 | 50 | 6 | 20 | 12 | 12 | 12 | 12 | 7.5 | 85 Ohms | TOP=L2:L3=L2/L4:L6=L5/L7:BOTTOM=L7 |
| PCIE_TX_P22 | TX22-DIFF1 | PAIR | 7 | 5.5 | 5 | 10 | 5 | 50 | 6 | 20 | 12 | 12 | 12 | 12 | 7.5 | 85 Ohms | TOP=L2:L3=L2/L4:L6=L5/L7:BOTTOM=L7 |
| PCIE_TX_P22 | TX22-DIFF1 | PAIR | 8 | 5.38 | 5 | 10 | 5 | 50 | 6 | 33 | 12 | 12 | 12 | 12 | 6.62 | 85 Ohms | TOP=L2:L3=L2/L4:L6=L5/L7:BOTTOM=L7 |
| PCIE_TX_N23 | TX23-DIFF1 | PAIR | 1 | 5.38 | 5 | 10 | 5 | 50 | 6 | 33 | 12 | 12 | 12 | 12 | 6.62 | 85 Ohms | TOP=L2:L3=L2/L4:L6=L5/L7:BOTTOM=L7 |
| PCIE_TX_N23 | TX23-DIFF1 | PAIR | 2 | 5.5 | 5 | 10 | 5 | 50 | 6 | 20 | 12 | 12 | 12 | 12 | 7.5 | 85 Ohms | TOP=L2:L3=L2/L4:L6=L5/L7:BOTTOM=L7 |
| PCIE_TX_N23 | TX23-DIFF1 | PAIR | 3 | 5.5 | 5 | 10 | 5 | 50 | 6 | 20 | 12 | 12 | 12 | 12 | 7.5 | 85 Ohms | TOP=L2:L3=L2/L4:L6=L5/L7:BOTTOM=L7 |
| PCIE_TX_N23 | TX23-DIFF1 | PAIR | 4 | 5.5 | 5 | 10 | 5 | 50 | 6 | 20 | 12 | 12 | 12 | 12 | 7.5 | 85 Ohms | TOP=L2:L3=L2/L4:L6=L5/L7:BOTTOM=L7 |
| PCIE_TX_N23 | TX23-DIFF1 | PAIR | 5 | 5.5 | 5 | 10 | 5 | 50 | 6 | 20 | 12 | 12 | 12 | 12 | 7.5 | 85 Ohms | TOP=L2:L3=L2/L4:L6=L5/L7:BOTTOM=L7 |
| PCIE_TX_N23 | TX23-DIFF1 | PAIR | 6 | 5.5 | 5 | 10 | 5 | 50 | 6 | 20 | 12 | 12 | 12 | 12 | 7.5 | 85 Ohms | TOP=L2:L3=L2/L4:L6=L5/L7:BOTTOM=L7 |
| PCIE_TX_N23 | TX23-DIFF1 | PAIR | 7 | 5.5 | 5 | 10 | 5 | 50 | 6 | 20 | 12 | 12 | 12 | 12 | 7.5 | 85 Ohms | TOP=L2:L3=L2/L4:L6=L5/L7:BOTTOM=L7 |
| PCIE_TX_N23 | TX23-DIFF1 | PAIR | 8 | 5.38 | 5 | 10 | 5 | 50 | 6 | 33 | 12 | 12 | 12 | 12 | 6.62 | 85 Ohms | TOP=L2:L3=L2/L4:L6=L5/L7:BOTTOM=L7 |
| PCIE_TX_P23 | TX23-DIFF1 | PAIR | 1 | 5.38 | 5 | 10 | 5 | 50 | 6 | 33 | 12 | 12 | 12 | 12 | 6.62 | 85 Ohms | TOP=L2:L3=L2/L4:L6=L5/L7:BOTTOM=L7 |
| PCIE_TX_P23 | TX23-DIFF1 | PAIR | 2 | 5.5 | 5 | 10 | 5 | 50 | 6 | 20 | 12 | 12 | 12 | 12 | 7.5 | 85 Ohms | TOP=L2:L3=L2/L4:L6=L5/L7:BOTTOM=L7 |
| PCIE_TX_P23 | TX23-DIFF1 | PAIR | 3 | 5.5 | 5 | 10 | 5 | 50 | 6 | 20 | 12 | 12 | 12 | 12 | 7.5 | 85 Ohms | TOP=L2:L3=L2/L4:L6=L5/L7:BOTTOM=L7 |
| PCIE_TX_P23 | TX23-DIFF1 | PAIR | 4 | 5.5 | 5 | 10 | 5 | 50 | 6 | 20 | 12 | 12 | 12 | 12 | 7.5 | 85 Ohms | TOP=L2:L3=L2/L4:L6=L5/L7:BOTTOM=L7 |
| PCIE_TX_P23 | TX23-DIFF1 | PAIR | 5 | 5.5 | 5 | 10 | 5 | 50 | 6 | 20 | 12 | 12 | 12 | 12 | 7.5 | 85 Ohms | TOP=L2:L3=L2/L4:L6=L5/L7:BOTTOM=L7 |
| PCIE_TX_P23 | TX23-DIFF1 | PAIR | 6 | 5.5 | 5 | 10 | 5 | 50 | 6 | 20 | 12 | 12 | 12 | 12 | 7.5 | 85 Ohms | TOP=L2:L3=L2/L4:L6=L5/L7:BOTTOM=L7 |
| PCIE_TX_P23 | TX23-DIFF1 | PAIR | 7 | 5.5 | 5 | 10 | 5 | 50 | 6 | 20 | 12 | 12 | 12 | 12 | 7.5 | 85 Ohms | TOP=L2:L3=L2/L4:L6=L5/L7:BOTTOM=L7 |
| PCIE_TX_P23 | TX23-DIFF1 | PAIR | 8 | 5.38 | 5 | 10 | 5 | 50 | 6 | 33 | 12 | 12 | 12 | 12 | 6.62 | 85 Ohms | TOP=L2:L3=L2/L4:L6=L5/L7:BOTTOM=L7 |
| PCIE_TX_N24 | TX24-DIFF1 | PAIR | 1 | 5.38 | 5 | 10 | 5 | 50 | 6 | 33 | 12 | 12 | 12 | 12 | 6.62 | 85 Ohms | TOP=L2:L3=L2/L4:L6=L5/L7:BOTTOM=L7 |
| PCIE_TX_N24 | TX24-DIFF1 | PAIR | 2 | 5.5 | 5 | 10 | 5 | 50 | 6 | 20 | 12 | 12 | 12 | 12 | 7.5 | 85 Ohms | TOP=L2:L3=L2/L4:L6=L5/L7:BOTTOM=L7 |
| PCIE_TX_N24 | TX24-DIFF1 | PAIR | 3 | 5.5 | 5 | 10 | 5 | 50 | 6 | 20 | 12 | 12 | 12 | 12 | 7.5 | 85 Ohms | TOP=L2:L3=L2/L4:L6=L5/L7:BOTTOM=L7 |
| PCIE_TX_N24 | TX24-DIFF1 | PAIR | 4 | 5.5 | 5 | 10 | 5 | 50 | 6 | 20 | 12 | 12 | 12 | 12 | 7.5 | 85 Ohms | TOP=L2:L3=L2/L4:L6=L5/L7:BOTTOM=L7 |
| PCIE_TX_N24 | TX24-DIFF1 | PAIR | 5 | 5.5 | 5 | 10 | 5 | 50 | 6 | 20 | 12 | 12 | 12 | 12 | 7.5 | 85 Ohms | TOP=L2:L3=L2/L4:L6=L5/L7:BOTTOM=L7 |
| PCIE_TX_N24 | TX24-DIFF1 | PAIR | 6 | 5.5 | 5 | 10 | 5 | 50 | 6 | 20 | 12 | 12 | 12 | 12 | 7.5 | 85 Ohms | TOP=L2:L3=L2/L4:L6=L5/L7:BOTTOM=L7 |
| PCIE_TX_N24 | TX24-DIFF1 | PAIR | 7 | 5.5 | 5 | 10 | 5 | 50 | 6 | 20 | 12 | 12 | 12 | 12 | 7.5 | 85 Ohms | TOP=L2:L3=L2/L4:L6=L5/L7:BOTTOM=L7 |
| PCIE_TX_N24 | TX24-DIFF1 | PAIR | 8 | 5.38 | 5 | 10 | 5 | 50 | 6 | 33 | 12 | 12 | 12 | 12 | 6.62 | 85 Ohms | TOP=L2:L3=L2/L4:L6=L5/L7:BOTTOM=L7 |
| PCIE_TX_P24 | TX24-DIFF1 | PAIR | 1 | 5.38 | 5 | 10 | 5 | 50 | 6 | 33 | 12 | 12 | 12 | 12 | 6.62 | 85 Ohms | TOP=L2:L3=L2/L4:L6=L5/L7:BOTTOM=L7 |
| PCIE_TX_P24 | TX24-DIFF1 | PAIR | 2 | 5.5 | 5 | 10 | 5 | 50 | 6 | 20 | 12 | 12 | 12 | 12 | 7.5 | 85 Ohms | TOP=L2:L3=L2/L4:L6=L5/L7:BOTTOM=L7 |
| PCIE_TX_P24 | TX24-DIFF1 | PAIR | 3 | 5.5 | 5 | 10 | 5 | 50 | 6 | 20 | 12 | 12 | 12 | 12 | 7.5 | 85 Ohms | TOP=L2:L3=L2/L4:L6=L5/L7:BOTTOM=L7 |
| PCIE_TX_P24 | TX24-DIFF1 | PAIR | 4 | 5.5 | 5 | 10 | 5 | 50 | 6 | 20 | 12 | 12 | 12 | 12 | 7.5 | 85 Ohms | TOP=L2:L3=L2/L4:L6=L5/L7:BOTTOM=L7 |
| PCIE_TX_P24 | TX24-DIFF1 | PAIR | 5 | 5.5 | 5 | 10 | 5 | 50 | 6 | 20 | 12 | 12 | 12 | 12 | 7.5 | 85 Ohms | TOP=L2:L3=L2/L4:L6=L5/L7:BOTTOM=L7 |
| PCIE_TX_P24 | TX24-DIFF1 | PAIR | 6 | 5.5 | 5 | 10 | 5 | 50 | 6 | 20 | 12 | 12 | 12 | 12 | 7.5 | 85 Ohms | TOP=L2:L3=L2/L4:L6=L5/L7:BOTTOM=L7 |
| PCIE_TX_P24 | TX24-DIFF1 | PAIR | 7 | 5.5 | 5 | 10 | 5 | 50 | 6 | 20 | 12 | 12 | 12 | 12 | 7.5 | 85 Ohms | TOP=L2:L3=L2/L4:L6=L5/L7:BOTTOM=L7 |
| PCIE_TX_P24 | TX24-DIFF1 | PAIR | 8 | 5.38 | 5 | 10 | 5 | 50 | 6 | 33 | 12 | 12 | 12 | 12 | 6.62 | 85 Ohms | TOP=L2:L3=L2/L4:L6=L5/L7:BOTTOM=L7 |
| PCIE_TX_N25 | TX25-DIFF1 | PAIR | 1 | 5.38 | 5 | 10 | 5 | 50 | 6 | 33 | 12 | 12 | 12 | 12 | 6.62 | 85 Ohms | TOP=L2:L3=L2/L4:L6=L5/L7:BOTTOM=L7 |
| PCIE_TX_N25 | TX25-DIFF1 | PAIR | 2 | 5.5 | 5 | 10 | 5 | 50 | 6 | 20 | 12 | 12 | 12 | 12 | 7.5 | 85 Ohms | TOP=L2:L3=L2/L4:L6=L5/L7:BOTTOM=L7 |
| PCIE_TX_N25 | TX25-DIFF1 | PAIR | 3 | 5.5 | 5 | 10 | 5 | 50 | 6 | 20 | 12 | 12 | 12 | 12 | 7.5 | 85 Ohms | TOP=L2:L3=L2/L4:L6=L5/L7:BOTTOM=L7 |
| PCIE_TX_N25 | TX25-DIFF1 | PAIR | 4 | 5.5 | 5 | 10 | 5 | 50 | 6 | 20 | 12 | 12 | 12 | 12 | 7.5 | 85 Ohms | TOP=L2:L3=L2/L4:L6=L5/L7:BOTTOM=L7 |
| PCIE_TX_N25 | TX25-DIFF1 | PAIR | 5 | 5.5 | 5 | 10 | 5 | 50 | 6 | 20 | 12 | 12 | 12 | 12 | 7.5 | 85 Ohms | TOP=L2:L3=L2/L4:L6=L5/L7:BOTTOM=L7 |
| PCIE_TX_N25 | TX25-DIFF1 | PAIR | 6 | 5.5 | 5 | 10 | 5 | 50 | 6 | 20 | 12 | 12 | 12 | 12 | 7.5 | 85 Ohms | TOP=L2:L3=L2/L4:L6=L5/L7:BOTTOM=L7 |
| PCIE_TX_N25 | TX25-DIFF1 | PAIR | 7 | 5.5 | 5 | 10 | 5 | 50 | 6 | 20 | 12 | 12 | 12 | 12 | 7.5 | 85 Ohms | TOP=L2:L3=L2/L4:L6=L5/L7:BOTTOM=L7 |
| PCIE_TX_N25 | TX25-DIFF1 | PAIR | 8 | 5.38 | 5 | 10 | 5 | 50 | 6 | 33 | 12 | 12 | 12 | 12 | 6.62 | 85 Ohms | TOP=L2:L3=L2/L4:L6=L5/L7:BOTTOM=L7 |
| PCIE_TX_P25 | TX25-DIFF1 | PAIR | 1 | 5.38 | 5 | 10 | 5 | 50 | 6 | 33 | 12 | 12 | 12 | 12 | 6.62 | 85 Ohms | TOP=L2:L3=L2/L4:L6=L5/L7:BOTTOM=L7 |
| PCIE_TX_P25 | TX25-DIFF1 | PAIR | 2 | 5.5 | 5 | 10 | 5 | 50 | 6 | 20 | 12 | 12 | 12 | 12 | 7.5 | 85 Ohms | TOP=L2:L3=L2/L4:L6=L5/L7:BOTTOM=L7 |
| PCIE_TX_P25 | TX25-DIFF1 | PAIR | 3 | 5.5 | 5 | 10 | 5 | 50 | 6 | 20 | 12 | 12 | 12 | 12 | 7.5 | 85 Ohms | TOP=L2:L3=L2/L4:L6=L5/L7:BOTTOM=L7 |
| PCIE_TX_P25 | TX25-DIFF1 | PAIR | 4 | 5.5 | 5 | 10 | 5 | 50 | 6 | 20 | 12 | 12 | 12 | 12 | 7.5 | 85 Ohms | TOP=L2:L3=L2/L4:L6=L5/L7:BOTTOM=L7 |
| PCIE_TX_P25 | TX25-DIFF1 | PAIR | 5 | 5.5 | 5 | 10 | 5 | 50 | 6 | 20 | 12 | 12 | 12 | 12 | 7.5 | 85 Ohms | TOP=L2:L3=L2/L4:L6=L5/L7:BOTTOM=L7 |
| PCIE_TX_P25 | TX25-DIFF1 | PAIR | 6 | 5.5 | 5 | 10 | 5 | 50 | 6 | 20 | 12 | 12 | 12 | 12 | 7.5 | 85 Ohms | TOP=L2:L3=L2/L4:L6=L5/L7:BOTTOM=L7 |
| PCIE_TX_P25 | TX25-DIFF1 | PAIR | 7 | 5.5 | 5 | 10 | 5 | 50 | 6 | 20 | 12 | 12 | 12 | 12 | 7.5 | 85 Ohms | TOP=L2:L3=L2/L4:L6=L5/L7:BOTTOM=L7 |
| PCIE_TX_P25 | TX25-DIFF1 | PAIR | 8 | 5.38 | 5 | 10 | 5 | 50 | 6 | 33 | 12 | 12 | 12 | 12 | 6.62 | 85 Ohms | TOP=L2:L3=L2/L4:L6=L5/L7:BOTTOM=L7 |
| PCIE_TX_N26 | TX26-DIFF1 | PAIR | 1 | 5.38 | 5 | 10 | 5 | 50 | 6 | 33 | 12 | 12 | 12 | 12 | 6.62 | 85 Ohms | TOP=L2:L3=L2/L4:L6=L5/L7:BOTTOM=L7 |
| PCIE_TX_N26 | TX26-DIFF1 | PAIR | 2 | 5.5 | 5 | 10 | 5 | 50 | 6 | 20 | 12 | 12 | 12 | 12 | 7.5 | 85 Ohms | TOP=L2:L3=L2/L4:L6=L5/L7:BOTTOM=L7 |
| PCIE_TX_N26 | TX26-DIFF1 | PAIR | 3 | 5.5 | 5 | 10 | 5 | 50 | 6 | 20 | 12 | 12 | 12 | 12 | 7.5 | 85 Ohms | TOP=L2:L3=L2/L4:L6=L5/L7:BOTTOM=L7 |
| PCIE_TX_N26 | TX26-DIFF1 | PAIR | 4 | 5.5 | 5 | 10 | 5 | 50 | 6 | 20 | 12 | 12 | 12 | 12 | 7.5 | 85 Ohms | TOP=L2:L3=L2/L4:L6=L5/L7:BOTTOM=L7 |
| PCIE_TX_N26 | TX26-DIFF1 | PAIR | 5 | 5.5 | 5 | 10 | 5 | 50 | 6 | 20 | 12 | 12 | 12 | 12 | 7.5 | 85 Ohms | TOP=L2:L3=L2/L4:L6=L5/L7:BOTTOM=L7 |
| PCIE_TX_N26 | TX26-DIFF1 | PAIR | 6 | 5.5 | 5 | 10 | 5 | 50 | 6 | 20 | 12 | 12 | 12 | 12 | 7.5 | 85 Ohms | TOP=L2:L3=L2/L4:L6=L5/L7:BOTTOM=L7 |
| PCIE_TX_N26 | TX26-DIFF1 | PAIR | 7 | 5.5 | 5 | 10 | 5 | 50 | 6 | 20 | 12 | 12 | 12 | 12 | 7.5 | 85 Ohms | TOP=L2:L3=L2/L4:L6=L5/L7:BOTTOM=L7 |
| PCIE_TX_N26 | TX26-DIFF1 | PAIR | 8 | 5.38 | 5 | 10 | 5 | 50 | 6 | 33 | 12 | 12 | 12 | 12 | 6.62 | 85 Ohms | TOP=L2:L3=L2/L4:L6=L5/L7:BOTTOM=L7 |
| PCIE_TX_P26 | TX26-DIFF1 | PAIR | 1 | 5.38 | 5 | 10 | 5 | 50 | 6 | 33 | 12 | 12 | 12 | 12 | 6.62 | 85 Ohms | TOP=L2:L3=L2/L4:L6=L5/L7:BOTTOM=L7 |
| PCIE_TX_P26 | TX26-DIFF1 | PAIR | 2 | 5.5 | 5 | 10 | 5 | 50 | 6 | 20 | 12 | 12 | 12 | 12 | 7.5 | 85 Ohms | TOP=L2:L3=L2/L4:L6=L5/L7:BOTTOM=L7 |
| PCIE_TX_P26 | TX26-DIFF1 | PAIR | 3 | 5.5 | 5 | 10 | 5 | 50 | 6 | 20 | 12 | 12 | 12 | 12 | 7.5 | 85 Ohms | TOP=L2:L3=L2/L4:L6=L5/L7:BOTTOM=L7 |
| PCIE_TX_P26 | TX26-DIFF1 | PAIR | 4 | 5.5 | 5 | 10 | 5 | 50 | 6 | 20 | 12 | 12 | 12 | 12 | 7.5 | 85 Ohms | TOP=L2:L3=L2/L4:L6=L5/L7:BOTTOM=L7 |
| PCIE_TX_P26 | TX26-DIFF1 | PAIR | 5 | 5.5 | 5 | 10 | 5 | 50 | 6 | 20 | 12 | 12 | 12 | 12 | 7.5 | 85 Ohms | TOP=L2:L3=L2/L4:L6=L5/L7:BOTTOM=L7 |
| PCIE_TX_P26 | TX26-DIFF1 | PAIR | 6 | 5.5 | 5 | 10 | 5 | 50 | 6 | 20 | 12 | 12 | 12 | 12 | 7.5 | 85 Ohms | TOP=L2:L3=L2/L4:L6=L5/L7:BOTTOM=L7 |
| PCIE_TX_P26 | TX26-DIFF1 | PAIR | 7 | 5.5 | 5 | 10 | 5 | 50 | 6 | 20 | 12 | 12 | 12 | 12 | 7.5 | 85 Ohms | TOP=L2:L3=L2/L4:L6=L5/L7:BOTTOM=L7 |
| PCIE_TX_P26 | TX26-DIFF1 | PAIR | 8 | 5.38 | 5 | 10 | 5 | 50 | 6 | 33 | 12 | 12 | 12 | 12 | 6.62 | 85 Ohms | TOP=L2:L3=L2/L4:L6=L5/L7:BOTTOM=L7 |
| PCIE_TX_N27 | TX27-DIFF1 | PAIR | 1 | 5.38 | 5 | 10 | 5 | 50 | 6 | 33 | 12 | 12 | 12 | 12 | 6.62 | 85 Ohms | TOP=L2:L3=L2/L4:L6=L5/L7:BOTTOM=L7 |
| PCIE_TX_N27 | TX27-DIFF1 | PAIR | 2 | 5.5 | 5 | 10 | 5 | 50 | 6 | 20 | 12 | 12 | 12 | 12 | 7.5 | 85 Ohms | TOP=L2:L3=L2/L4:L6=L5/L7:BOTTOM=L7 |
| PCIE_TX_N27 | TX27-DIFF1 | PAIR | 3 | 5.5 | 5 | 10 | 5 | 50 | 6 | 20 | 12 | 12 | 12 | 12 | 7.5 | 85 Ohms | TOP=L2:L3=L2/L4:L6=L5/L7:BOTTOM=L7 |
| PCIE_TX_N27 | TX27-DIFF1 | PAIR | 4 | 5.5 | 5 | 10 | 5 | 50 | 6 | 20 | 12 | 12 | 12 | 12 | 7.5 | 85 Ohms | TOP=L2:L3=L2/L4:L6=L5/L7:BOTTOM=L7 |
| PCIE_TX_N27 | TX27-DIFF1 | PAIR | 5 | 5.5 | 5 | 10 | 5 | 50 | 6 | 20 | 12 | 12 | 12 | 12 | 7.5 | 85 Ohms | TOP=L2:L3=L2/L4:L6=L5/L7:BOTTOM=L7 |
| PCIE_TX_N27 | TX27-DIFF1 | PAIR | 6 | 5.5 | 5 | 10 | 5 | 50 | 6 | 20 | 12 | 12 | 12 | 12 | 7.5 | 85 Ohms | TOP=L2:L3=L2/L4:L6=L5/L7:BOTTOM=L7 |
| PCIE_TX_N27 | TX27-DIFF1 | PAIR | 7 | 5.5 | 5 | 10 | 5 | 50 | 6 | 20 | 12 | 12 | 12 | 12 | 7.5 | 85 Ohms | TOP=L2:L3=L2/L4:L6=L5/L7:BOTTOM=L7 |
| PCIE_TX_N27 | TX27-DIFF1 | PAIR | 8 | 5.38 | 5 | 10 | 5 | 50 | 6 | 33 | 12 | 12 | 12 | 12 | 6.62 | 85 Ohms | TOP=L2:L3=L2/L4:L6=L5/L7:BOTTOM=L7 |
| PCIE_TX_P27 | TX27-DIFF1 | PAIR | 1 | 5.38 | 5 | 10 | 5 | 50 | 6 | 33 | 12 | 12 | 12 | 12 | 6.62 | 85 Ohms | TOP=L2:L3=L2/L4:L6=L5/L7:BOTTOM=L7 |
| PCIE_TX_P27 | TX27-DIFF1 | PAIR | 2 | 5.5 | 5 | 10 | 5 | 50 | 6 | 20 | 12 | 12 | 12 | 12 | 7.5 | 85 Ohms | TOP=L2:L3=L2/L4:L6=L5/L7:BOTTOM=L7 |
| PCIE_TX_P27 | TX27-DIFF1 | PAIR | 3 | 5.5 | 5 | 10 | 5 | 50 | 6 | 20 | 12 | 12 | 12 | 12 | 7.5 | 85 Ohms | TOP=L2:L3=L2/L4:L6=L5/L7:BOTTOM=L7 |
| PCIE_TX_P27 | TX27-DIFF1 | PAIR | 4 | 5.5 | 5 | 10 | 5 | 50 | 6 | 20 | 12 | 12 | 12 | 12 | 7.5 | 85 Ohms | TOP=L2:L3=L2/L4:L6=L5/L7:BOTTOM=L7 |
| PCIE_TX_P27 | TX27-DIFF1 | PAIR | 5 | 5.5 | 5 | 10 | 5 | 50 | 6 | 20 | 12 | 12 | 12 | 12 | 7.5 | 85 Ohms | TOP=L2:L3=L2/L4:L6=L5/L7:BOTTOM=L7 |
| PCIE_TX_P27 | TX27-DIFF1 | PAIR | 6 | 5.5 | 5 | 10 | 5 | 50 | 6 | 20 | 12 | 12 | 12 | 12 | 7.5 | 85 Ohms | TOP=L2:L3=L2/L4:L6=L5/L7:BOTTOM=L7 |
| PCIE_TX_P27 | TX27-DIFF1 | PAIR | 7 | 5.5 | 5 | 10 | 5 | 50 | 6 | 20 | 12 | 12 | 12 | 12 | 7.5 | 85 Ohms | TOP=L2:L3=L2/L4:L6=L5/L7:BOTTOM=L7 |
| PCIE_TX_P27 | TX27-DIFF1 | PAIR | 8 | 5.38 | 5 | 10 | 5 | 50 | 6 | 33 | 12 | 12 | 12 | 12 | 6.62 | 85 Ohms | TOP=L2:L3=L2/L4:L6=L5/L7:BOTTOM=L7 |
| PCIE_TX_N28 | TX28-DIFF1 | PAIR | 1 | 5.38 | 5 | 10 | 5 | 50 | 6 | 33 | 12 | 12 | 12 | 12 | 6.62 | 85 Ohms | TOP=L2:L3=L2/L4:L6=L5/L7:BOTTOM=L7 |
| PCIE_TX_N28 | TX28-DIFF1 | PAIR | 2 | 5.5 | 5 | 10 | 5 | 50 | 6 | 20 | 12 | 12 | 12 | 12 | 7.5 | 85 Ohms | TOP=L2:L3=L2/L4:L6=L5/L7:BOTTOM=L7 |
| PCIE_TX_N28 | TX28-DIFF1 | PAIR | 3 | 5.5 | 5 | 10 | 5 | 50 | 6 | 20 | 12 | 12 | 12 | 12 | 7.5 | 85 Ohms | TOP=L2:L3=L2/L4:L6=L5/L7:BOTTOM=L7 |
| PCIE_TX_N28 | TX28-DIFF1 | PAIR | 4 | 5.5 | 5 | 10 | 5 | 50 | 6 | 20 | 12 | 12 | 12 | 12 | 7.5 | 85 Ohms | TOP=L2:L3=L2/L4:L6=L5/L7:BOTTOM=L7 |
| PCIE_TX_N28 | TX28-DIFF1 | PAIR | 5 | 5.5 | 5 | 10 | 5 | 50 | 6 | 20 | 12 | 12 | 12 | 12 | 7.5 | 85 Ohms | TOP=L2:L3=L2/L4:L6=L5/L7:BOTTOM=L7 |
| PCIE_TX_N28 | TX28-DIFF1 | PAIR | 6 | 5.5 | 5 | 10 | 5 | 50 | 6 | 20 | 12 | 12 | 12 | 12 | 7.5 | 85 Ohms | TOP=L2:L3=L2/L4:L6=L5/L7:BOTTOM=L7 |
| PCIE_TX_N28 | TX28-DIFF1 | PAIR | 7 | 5.5 | 5 | 10 | 5 | 50 | 6 | 20 | 12 | 12 | 12 | 12 | 7.5 | 85 Ohms | TOP=L2:L3=L2/L4:L6=L5/L7:BOTTOM=L7 |
| PCIE_TX_N28 | TX28-DIFF1 | PAIR | 8 | 5.38 | 5 | 10 | 5 | 50 | 6 | 33 | 12 | 12 | 12 | 12 | 6.62 | 85 Ohms | TOP=L2:L3=L2/L4:L6=L5/L7:BOTTOM=L7 |
| PCIE_TX_P28 | TX28-DIFF1 | PAIR | 1 | 5.38 | 5 | 10 | 5 | 50 | 6 | 33 | 12 | 12 | 12 | 12 | 6.62 | 85 Ohms | TOP=L2:L3=L2/L4:L6=L5/L7:BOTTOM=L7 |
| PCIE_TX_P28 | TX28-DIFF1 | PAIR | 2 | 5.5 | 5 | 10 | 5 | 50 | 6 | 20 | 12 | 12 | 12 | 12 | 7.5 | 85 Ohms | TOP=L2:L3=L2/L4:L6=L5/L7:BOTTOM=L7 |
| PCIE_TX_P28 | TX28-DIFF1 | PAIR | 3 | 5.5 | 5 | 10 | 5 | 50 | 6 | 20 | 12 | 12 | 12 | 12 | 7.5 | 85 Ohms | TOP=L2:L3=L2/L4:L6=L5/L7:BOTTOM=L7 |
| PCIE_TX_P28 | TX28-DIFF1 | PAIR | 4 | 5.5 | 5 | 10 | 5 | 50 | 6 | 20 | 12 | 12 | 12 | 12 | 7.5 | 85 Ohms | TOP=L2:L3=L2/L4:L6=L5/L7:BOTTOM=L7 |
| PCIE_TX_P28 | TX28-DIFF1 | PAIR | 5 | 5.5 | 5 | 10 | 5 | 50 | 6 | 20 | 12 | 12 | 12 | 12 | 7.5 | 85 Ohms | TOP=L2:L3=L2/L4:L6=L5/L7:BOTTOM=L7 |
| PCIE_TX_P28 | TX28-DIFF1 | PAIR | 6 | 5.5 | 5 | 10 | 5 | 50 | 6 | 20 | 12 | 12 | 12 | 12 | 7.5 | 85 Ohms | TOP=L2:L3=L2/L4:L6=L5/L7:BOTTOM=L7 |
| PCIE_TX_P28 | TX28-DIFF1 | PAIR | 7 | 5.5 | 5 | 10 | 5 | 50 | 6 | 20 | 12 | 12 | 12 | 12 | 7.5 | 85 Ohms | TOP=L2:L3=L2/L4:L6=L5/L7:BOTTOM=L7 |
| PCIE_TX_P28 | TX28-DIFF1 | PAIR | 8 | 5.38 | 5 | 10 | 5 | 50 | 6 | 33 | 12 | 12 | 12 | 12 | 6.62 | 85 Ohms | TOP=L2:L3=L2/L4:L6=L5/L7:BOTTOM=L7 |
| PCIE_TX_N29 | TX29-DIFF1 | PAIR | 1 | 5.38 | 5 | 10 | 5 | 50 | 6 | 33 | 12 | 12 | 12 | 12 | 6.62 | 85 Ohms | TOP=L2:L3=L2/L4:L6=L5/L7:BOTTOM=L7 |
| PCIE_TX_N29 | TX29-DIFF1 | PAIR | 2 | 5.5 | 5 | 10 | 5 | 50 | 6 | 20 | 12 | 12 | 12 | 12 | 7.5 | 85 Ohms | TOP=L2:L3=L2/L4:L6=L5/L7:BOTTOM=L7 |
| PCIE_TX_N29 | TX29-DIFF1 | PAIR | 3 | 5.5 | 5 | 10 | 5 | 50 | 6 | 20 | 12 | 12 | 12 | 12 | 7.5 | 85 Ohms | TOP=L2:L3=L2/L4:L6=L5/L7:BOTTOM=L7 |
| PCIE_TX_N29 | TX29-DIFF1 | PAIR | 4 | 5.5 | 5 | 10 | 5 | 50 | 6 | 20 | 12 | 12 | 12 | 12 | 7.5 | 85 Ohms | TOP=L2:L3=L2/L4:L6=L5/L7:BOTTOM=L7 |
| PCIE_TX_N29 | TX29-DIFF1 | PAIR | 5 | 5.5 | 5 | 10 | 5 | 50 | 6 | 20 | 12 | 12 | 12 | 12 | 7.5 | 85 Ohms | TOP=L2:L3=L2/L4:L6=L5/L7:BOTTOM=L7 |
| PCIE_TX_N29 | TX29-DIFF1 | PAIR | 6 | 5.5 | 5 | 10 | 5 | 50 | 6 | 20 | 12 | 12 | 12 | 12 | 7.5 | 85 Ohms | TOP=L2:L3=L2/L4:L6=L5/L7:BOTTOM=L7 |
| PCIE_TX_N29 | TX29-DIFF1 | PAIR | 7 | 5.5 | 5 | 10 | 5 | 50 | 6 | 20 | 12 | 12 | 12 | 12 | 7.5 | 85 Ohms | TOP=L2:L3=L2/L4:L6=L5/L7:BOTTOM=L7 |
| PCIE_TX_N29 | TX29-DIFF1 | PAIR | 8 | 5.38 | 5 | 10 | 5 | 50 | 6 | 33 | 12 | 12 | 12 | 12 | 6.62 | 85 Ohms | TOP=L2:L3=L2/L4:L6=L5/L7:BOTTOM=L7 |
| PCIE_TX_P29 | TX29-DIFF1 | PAIR | 1 | 5.38 | 5 | 10 | 5 | 50 | 6 | 33 | 12 | 12 | 12 | 12 | 6.62 | 85 Ohms | TOP=L2:L3=L2/L4:L6=L5/L7:BOTTOM=L7 |
| PCIE_TX_P29 | TX29-DIFF1 | PAIR | 2 | 5.5 | 5 | 10 | 5 | 50 | 6 | 20 | 12 | 12 | 12 | 12 | 7.5 | 85 Ohms | TOP=L2:L3=L2/L4:L6=L5/L7:BOTTOM=L7 |
| PCIE_TX_P29 | TX29-DIFF1 | PAIR | 3 | 5.5 | 5 | 10 | 5 | 50 | 6 | 20 | 12 | 12 | 12 | 12 | 7.5 | 85 Ohms | TOP=L2:L3=L2/L4:L6=L5/L7:BOTTOM=L7 |
| PCIE_TX_P29 | TX29-DIFF1 | PAIR | 4 | 5.5 | 5 | 10 | 5 | 50 | 6 | 20 | 12 | 12 | 12 | 12 | 7.5 | 85 Ohms | TOP=L2:L3=L2/L4:L6=L5/L7:BOTTOM=L7 |
| PCIE_TX_P29 | TX29-DIFF1 | PAIR | 5 | 5.5 | 5 | 10 | 5 | 50 | 6 | 20 | 12 | 12 | 12 | 12 | 7.5 | 85 Ohms | TOP=L2:L3=L2/L4:L6=L5/L7:BOTTOM=L7 |
| PCIE_TX_P29 | TX29-DIFF1 | PAIR | 6 | 5.5 | 5 | 10 | 5 | 50 | 6 | 20 | 12 | 12 | 12 | 12 | 7.5 | 85 Ohms | TOP=L2:L3=L2/L4:L6=L5/L7:BOTTOM=L7 |
| PCIE_TX_P29 | TX29-DIFF1 | PAIR | 7 | 5.5 | 5 | 10 | 5 | 50 | 6 | 20 | 12 | 12 | 12 | 12 | 7.5 | 85 Ohms | TOP=L2:L3=L2/L4:L6=L5/L7:BOTTOM=L7 |
| PCIE_TX_P29 | TX29-DIFF1 | PAIR | 8 | 5.38 | 5 | 10 | 5 | 50 | 6 | 33 | 12 | 12 | 12 | 12 | 6.62 | 85 Ohms | TOP=L2:L3=L2/L4:L6=L5/L7:BOTTOM=L7 |
| PCIE_TX_N2 | TX2-DIFF1 | PAIR | 1 | 5.38 | 5 | 10 | 5 | 50 | 6 | 33 | 12 | 12 | 12 | 12 | 6.62 | 85 Ohms | TOP=L2:L3=L2/L4:L6=L5/L7:BOTTOM=L7 |
| PCIE_TX_N2 | TX2-DIFF1 | PAIR | 2 | 5.5 | 5 | 10 | 5 | 50 | 6 | 20 | 12 | 12 | 12 | 12 | 7.5 | 85 Ohms | TOP=L2:L3=L2/L4:L6=L5/L7:BOTTOM=L7 |
| PCIE_TX_N2 | TX2-DIFF1 | PAIR | 3 | 5.5 | 5 | 10 | 5 | 50 | 6 | 20 | 12 | 12 | 12 | 12 | 7.5 | 85 Ohms | TOP=L2:L3=L2/L4:L6=L5/L7:BOTTOM=L7 |
| PCIE_TX_N2 | TX2-DIFF1 | PAIR | 4 | 5.5 | 5 | 10 | 5 | 50 | 6 | 20 | 12 | 12 | 12 | 12 | 7.5 | 85 Ohms | TOP=L2:L3=L2/L4:L6=L5/L7:BOTTOM=L7 |
| PCIE_TX_N2 | TX2-DIFF1 | PAIR | 5 | 5.5 | 5 | 10 | 5 | 50 | 6 | 20 | 12 | 12 | 12 | 12 | 7.5 | 85 Ohms | TOP=L2:L3=L2/L4:L6=L5/L7:BOTTOM=L7 |
| PCIE_TX_N2 | TX2-DIFF1 | PAIR | 6 | 5.5 | 5 | 10 | 5 | 50 | 6 | 20 | 12 | 12 | 12 | 12 | 7.5 | 85 Ohms | TOP=L2:L3=L2/L4:L6=L5/L7:BOTTOM=L7 |
| PCIE_TX_N2 | TX2-DIFF1 | PAIR | 7 | 5.5 | 5 | 10 | 5 | 50 | 6 | 20 | 12 | 12 | 12 | 12 | 7.5 | 85 Ohms | TOP=L2:L3=L2/L4:L6=L5/L7:BOTTOM=L7 |
| PCIE_TX_N2 | TX2-DIFF1 | PAIR | 8 | 5.38 | 5 | 10 | 5 | 50 | 6 | 33 | 12 | 12 | 12 | 12 | 6.62 | 85 Ohms | TOP=L2:L3=L2/L4:L6=L5/L7:BOTTOM=L7 |
| PCIE_TX_P2 | TX2-DIFF1 | PAIR | 1 | 5.38 | 5 | 10 | 5 | 50 | 6 | 33 | 12 | 12 | 12 | 12 | 6.62 | 85 Ohms | TOP=L2:L3=L2/L4:L6=L5/L7:BOTTOM=L7 |
| PCIE_TX_P2 | TX2-DIFF1 | PAIR | 2 | 5.5 | 5 | 10 | 5 | 50 | 6 | 20 | 12 | 12 | 12 | 12 | 7.5 | 85 Ohms | TOP=L2:L3=L2/L4:L6=L5/L7:BOTTOM=L7 |
| PCIE_TX_P2 | TX2-DIFF1 | PAIR | 3 | 5.5 | 5 | 10 | 5 | 50 | 6 | 20 | 12 | 12 | 12 | 12 | 7.5 | 85 Ohms | TOP=L2:L3=L2/L4:L6=L5/L7:BOTTOM=L7 |
| PCIE_TX_P2 | TX2-DIFF1 | PAIR | 4 | 5.5 | 5 | 10 | 5 | 50 | 6 | 20 | 12 | 12 | 12 | 12 | 7.5 | 85 Ohms | TOP=L2:L3=L2/L4:L6=L5/L7:BOTTOM=L7 |
| PCIE_TX_P2 | TX2-DIFF1 | PAIR | 5 | 5.5 | 5 | 10 | 5 | 50 | 6 | 20 | 12 | 12 | 12 | 12 | 7.5 | 85 Ohms | TOP=L2:L3=L2/L4:L6=L5/L7:BOTTOM=L7 |
| PCIE_TX_P2 | TX2-DIFF1 | PAIR | 6 | 5.5 | 5 | 10 | 5 | 50 | 6 | 20 | 12 | 12 | 12 | 12 | 7.5 | 85 Ohms | TOP=L2:L3=L2/L4:L6=L5/L7:BOTTOM=L7 |
| PCIE_TX_P2 | TX2-DIFF1 | PAIR | 7 | 5.5 | 5 | 10 | 5 | 50 | 6 | 20 | 12 | 12 | 12 | 12 | 7.5 | 85 Ohms | TOP=L2:L3=L2/L4:L6=L5/L7:BOTTOM=L7 |
| PCIE_TX_P2 | TX2-DIFF1 | PAIR | 8 | 5.38 | 5 | 10 | 5 | 50 | 6 | 33 | 12 | 12 | 12 | 12 | 6.62 | 85 Ohms | TOP=L2:L3=L2/L4:L6=L5/L7:BOTTOM=L7 |
| PCIE_TX_N30 | TX30-DIFF1 | PAIR | 1 | 5.38 | 5 | 10 | 5 | 50 | 6 | 33 | 12 | 12 | 12 | 12 | 6.62 | 85 Ohms | TOP=L2:L3=L2/L4:L6=L5/L7:BOTTOM=L7 |
| PCIE_TX_N30 | TX30-DIFF1 | PAIR | 2 | 5.5 | 5 | 10 | 5 | 50 | 6 | 20 | 12 | 12 | 12 | 12 | 7.5 | 85 Ohms | TOP=L2:L3=L2/L4:L6=L5/L7:BOTTOM=L7 |
| PCIE_TX_N30 | TX30-DIFF1 | PAIR | 3 | 5.5 | 5 | 10 | 5 | 50 | 6 | 20 | 12 | 12 | 12 | 12 | 7.5 | 85 Ohms | TOP=L2:L3=L2/L4:L6=L5/L7:BOTTOM=L7 |
| PCIE_TX_N30 | TX30-DIFF1 | PAIR | 4 | 5.5 | 5 | 10 | 5 | 50 | 6 | 20 | 12 | 12 | 12 | 12 | 7.5 | 85 Ohms | TOP=L2:L3=L2/L4:L6=L5/L7:BOTTOM=L7 |
| PCIE_TX_N30 | TX30-DIFF1 | PAIR | 5 | 5.5 | 5 | 10 | 5 | 50 | 6 | 20 | 12 | 12 | 12 | 12 | 7.5 | 85 Ohms | TOP=L2:L3=L2/L4:L6=L5/L7:BOTTOM=L7 |
| PCIE_TX_N30 | TX30-DIFF1 | PAIR | 6 | 5.5 | 5 | 10 | 5 | 50 | 6 | 20 | 12 | 12 | 12 | 12 | 7.5 | 85 Ohms | TOP=L2:L3=L2/L4:L6=L5/L7:BOTTOM=L7 |
| PCIE_TX_N30 | TX30-DIFF1 | PAIR | 7 | 5.5 | 5 | 10 | 5 | 50 | 6 | 20 | 12 | 12 | 12 | 12 | 7.5 | 85 Ohms | TOP=L2:L3=L2/L4:L6=L5/L7:BOTTOM=L7 |
| PCIE_TX_N30 | TX30-DIFF1 | PAIR | 8 | 5.38 | 5 | 10 | 5 | 50 | 6 | 33 | 12 | 12 | 12 | 12 | 6.62 | 85 Ohms | TOP=L2:L3=L2/L4:L6=L5/L7:BOTTOM=L7 |
| PCIE_TX_P30 | TX30-DIFF1 | PAIR | 1 | 5.38 | 5 | 10 | 5 | 50 | 6 | 33 | 12 | 12 | 12 | 12 | 6.62 | 85 Ohms | TOP=L2:L3=L2/L4:L6=L5/L7:BOTTOM=L7 |
| PCIE_TX_P30 | TX30-DIFF1 | PAIR | 2 | 5.5 | 5 | 10 | 5 | 50 | 6 | 20 | 12 | 12 | 12 | 12 | 7.5 | 85 Ohms | TOP=L2:L3=L2/L4:L6=L5/L7:BOTTOM=L7 |
| PCIE_TX_P30 | TX30-DIFF1 | PAIR | 3 | 5.5 | 5 | 10 | 5 | 50 | 6 | 20 | 12 | 12 | 12 | 12 | 7.5 | 85 Ohms | TOP=L2:L3=L2/L4:L6=L5/L7:BOTTOM=L7 |
| PCIE_TX_P30 | TX30-DIFF1 | PAIR | 4 | 5.5 | 5 | 10 | 5 | 50 | 6 | 20 | 12 | 12 | 12 | 12 | 7.5 | 85 Ohms | TOP=L2:L3=L2/L4:L6=L5/L7:BOTTOM=L7 |
| PCIE_TX_P30 | TX30-DIFF1 | PAIR | 5 | 5.5 | 5 | 10 | 5 | 50 | 6 | 20 | 12 | 12 | 12 | 12 | 7.5 | 85 Ohms | TOP=L2:L3=L2/L4:L6=L5/L7:BOTTOM=L7 |
| PCIE_TX_P30 | TX30-DIFF1 | PAIR | 6 | 5.5 | 5 | 10 | 5 | 50 | 6 | 20 | 12 | 12 | 12 | 12 | 7.5 | 85 Ohms | TOP=L2:L3=L2/L4:L6=L5/L7:BOTTOM=L7 |
| PCIE_TX_P30 | TX30-DIFF1 | PAIR | 7 | 5.5 | 5 | 10 | 5 | 50 | 6 | 20 | 12 | 12 | 12 | 12 | 7.5 | 85 Ohms | TOP=L2:L3=L2/L4:L6=L5/L7:BOTTOM=L7 |
| PCIE_TX_P30 | TX30-DIFF1 | PAIR | 8 | 5.38 | 5 | 10 | 5 | 50 | 6 | 33 | 12 | 12 | 12 | 12 | 6.62 | 85 Ohms | TOP=L2:L3=L2/L4:L6=L5/L7:BOTTOM=L7 |
| PCIE_TX_N31 | TX31-DIFF1 | PAIR | 1 | 5.38 | 5 | 10 | 5 | 50 | 6 | 33 | 12 | 12 | 12 | 12 | 6.62 | 85 Ohms | TOP=L2:L3=L2/L4:L6=L5/L7:BOTTOM=L7 |
| PCIE_TX_N31 | TX31-DIFF1 | PAIR | 2 | 5.5 | 5 | 10 | 5 | 50 | 6 | 20 | 12 | 12 | 12 | 12 | 7.5 | 85 Ohms | TOP=L2:L3=L2/L4:L6=L5/L7:BOTTOM=L7 |
| PCIE_TX_N31 | TX31-DIFF1 | PAIR | 3 | 5.5 | 5 | 10 | 5 | 50 | 6 | 20 | 12 | 12 | 12 | 12 | 7.5 | 85 Ohms | TOP=L2:L3=L2/L4:L6=L5/L7:BOTTOM=L7 |
| PCIE_TX_N31 | TX31-DIFF1 | PAIR | 4 | 5.5 | 5 | 10 | 5 | 50 | 6 | 20 | 12 | 12 | 12 | 12 | 7.5 | 85 Ohms | TOP=L2:L3=L2/L4:L6=L5/L7:BOTTOM=L7 |
| PCIE_TX_N31 | TX31-DIFF1 | PAIR | 5 | 5.5 | 5 | 10 | 5 | 50 | 6 | 20 | 12 | 12 | 12 | 12 | 7.5 | 85 Ohms | TOP=L2:L3=L2/L4:L6=L5/L7:BOTTOM=L7 |
| PCIE_TX_N31 | TX31-DIFF1 | PAIR | 6 | 5.5 | 5 | 10 | 5 | 50 | 6 | 20 | 12 | 12 | 12 | 12 | 7.5 | 85 Ohms | TOP=L2:L3=L2/L4:L6=L5/L7:BOTTOM=L7 |
| PCIE_TX_N31 | TX31-DIFF1 | PAIR | 7 | 5.5 | 5 | 10 | 5 | 50 | 6 | 20 | 12 | 12 | 12 | 12 | 7.5 | 85 Ohms | TOP=L2:L3=L2/L4:L6=L5/L7:BOTTOM=L7 |
| PCIE_TX_N31 | TX31-DIFF1 | PAIR | 8 | 5.38 | 5 | 10 | 5 | 50 | 6 | 33 | 12 | 12 | 12 | 12 | 6.62 | 85 Ohms | TOP=L2:L3=L2/L4:L6=L5/L7:BOTTOM=L7 |
| PCIE_TX_P31 | TX31-DIFF1 | PAIR | 1 | 5.38 | 5 | 10 | 5 | 50 | 6 | 33 | 12 | 12 | 12 | 12 | 6.62 | 85 Ohms | TOP=L2:L3=L2/L4:L6=L5/L7:BOTTOM=L7 |
| PCIE_TX_P31 | TX31-DIFF1 | PAIR | 2 | 5.5 | 5 | 10 | 5 | 50 | 6 | 20 | 12 | 12 | 12 | 12 | 7.5 | 85 Ohms | TOP=L2:L3=L2/L4:L6=L5/L7:BOTTOM=L7 |
| PCIE_TX_P31 | TX31-DIFF1 | PAIR | 3 | 5.5 | 5 | 10 | 5 | 50 | 6 | 20 | 12 | 12 | 12 | 12 | 7.5 | 85 Ohms | TOP=L2:L3=L2/L4:L6=L5/L7:BOTTOM=L7 |
| PCIE_TX_P31 | TX31-DIFF1 | PAIR | 4 | 5.5 | 5 | 10 | 5 | 50 | 6 | 20 | 12 | 12 | 12 | 12 | 7.5 | 85 Ohms | TOP=L2:L3=L2/L4:L6=L5/L7:BOTTOM=L7 |
| PCIE_TX_P31 | TX31-DIFF1 | PAIR | 5 | 5.5 | 5 | 10 | 5 | 50 | 6 | 20 | 12 | 12 | 12 | 12 | 7.5 | 85 Ohms | TOP=L2:L3=L2/L4:L6=L5/L7:BOTTOM=L7 |
| PCIE_TX_P31 | TX31-DIFF1 | PAIR | 6 | 5.5 | 5 | 10 | 5 | 50 | 6 | 20 | 12 | 12 | 12 | 12 | 7.5 | 85 Ohms | TOP=L2:L3=L2/L4:L6=L5/L7:BOTTOM=L7 |
| PCIE_TX_P31 | TX31-DIFF1 | PAIR | 7 | 5.5 | 5 | 10 | 5 | 50 | 6 | 20 | 12 | 12 | 12 | 12 | 7.5 | 85 Ohms | TOP=L2:L3=L2/L4:L6=L5/L7:BOTTOM=L7 |
| PCIE_TX_P31 | TX31-DIFF1 | PAIR | 8 | 5.38 | 5 | 10 | 5 | 50 | 6 | 33 | 12 | 12 | 12 | 12 | 6.62 | 85 Ohms | TOP=L2:L3=L2/L4:L6=L5/L7:BOTTOM=L7 |
| PCIE_TX_N32 | TX32-DIFF1 | PAIR | 1 | 5.38 | 5 | 10 | 5 | 50 | 6 | 33 | 12 | 12 | 12 | 12 | 6.62 | 85 Ohms | TOP=L2:L3=L2/L4:L6=L5/L7:BOTTOM=L7 |
| PCIE_TX_N32 | TX32-DIFF1 | PAIR | 2 | 5.5 | 5 | 10 | 5 | 50 | 6 | 20 | 12 | 12 | 12 | 12 | 7.5 | 85 Ohms | TOP=L2:L3=L2/L4:L6=L5/L7:BOTTOM=L7 |
| PCIE_TX_N32 | TX32-DIFF1 | PAIR | 3 | 5.5 | 5 | 10 | 5 | 50 | 6 | 20 | 12 | 12 | 12 | 12 | 7.5 | 85 Ohms | TOP=L2:L3=L2/L4:L6=L5/L7:BOTTOM=L7 |
| PCIE_TX_N32 | TX32-DIFF1 | PAIR | 4 | 5.5 | 5 | 10 | 5 | 50 | 6 | 20 | 12 | 12 | 12 | 12 | 7.5 | 85 Ohms | TOP=L2:L3=L2/L4:L6=L5/L7:BOTTOM=L7 |
| PCIE_TX_N32 | TX32-DIFF1 | PAIR | 5 | 5.5 | 5 | 10 | 5 | 50 | 6 | 20 | 12 | 12 | 12 | 12 | 7.5 | 85 Ohms | TOP=L2:L3=L2/L4:L6=L5/L7:BOTTOM=L7 |
| PCIE_TX_N32 | TX32-DIFF1 | PAIR | 6 | 5.5 | 5 | 10 | 5 | 50 | 6 | 20 | 12 | 12 | 12 | 12 | 7.5 | 85 Ohms | TOP=L2:L3=L2/L4:L6=L5/L7:BOTTOM=L7 |
| PCIE_TX_N32 | TX32-DIFF1 | PAIR | 7 | 5.5 | 5 | 10 | 5 | 50 | 6 | 20 | 12 | 12 | 12 | 12 | 7.5 | 85 Ohms | TOP=L2:L3=L2/L4:L6=L5/L7:BOTTOM=L7 |
| PCIE_TX_N32 | TX32-DIFF1 | PAIR | 8 | 5.38 | 5 | 10 | 5 | 50 | 6 | 33 | 12 | 12 | 12 | 12 | 6.62 | 85 Ohms | TOP=L2:L3=L2/L4:L6=L5/L7:BOTTOM=L7 |
| PCIE_TX_P32 | TX32-DIFF1 | PAIR | 1 | 5.38 | 5 | 10 | 5 | 50 | 6 | 33 | 12 | 12 | 12 | 12 | 6.62 | 85 Ohms | TOP=L2:L3=L2/L4:L6=L5/L7:BOTTOM=L7 |
| PCIE_TX_P32 | TX32-DIFF1 | PAIR | 2 | 5.5 | 5 | 10 | 5 | 50 | 6 | 20 | 12 | 12 | 12 | 12 | 7.5 | 85 Ohms | TOP=L2:L3=L2/L4:L6=L5/L7:BOTTOM=L7 |
| PCIE_TX_P32 | TX32-DIFF1 | PAIR | 3 | 5.5 | 5 | 10 | 5 | 50 | 6 | 20 | 12 | 12 | 12 | 12 | 7.5 | 85 Ohms | TOP=L2:L3=L2/L4:L6=L5/L7:BOTTOM=L7 |
| PCIE_TX_P32 | TX32-DIFF1 | PAIR | 4 | 5.5 | 5 | 10 | 5 | 50 | 6 | 20 | 12 | 12 | 12 | 12 | 7.5 | 85 Ohms | TOP=L2:L3=L2/L4:L6=L5/L7:BOTTOM=L7 |
| PCIE_TX_P32 | TX32-DIFF1 | PAIR | 5 | 5.5 | 5 | 10 | 5 | 50 | 6 | 20 | 12 | 12 | 12 | 12 | 7.5 | 85 Ohms | TOP=L2:L3=L2/L4:L6=L5/L7:BOTTOM=L7 |
| PCIE_TX_P32 | TX32-DIFF1 | PAIR | 6 | 5.5 | 5 | 10 | 5 | 50 | 6 | 20 | 12 | 12 | 12 | 12 | 7.5 | 85 Ohms | TOP=L2:L3=L2/L4:L6=L5/L7:BOTTOM=L7 |
| PCIE_TX_P32 | TX32-DIFF1 | PAIR | 7 | 5.5 | 5 | 10 | 5 | 50 | 6 | 20 | 12 | 12 | 12 | 12 | 7.5 | 85 Ohms | TOP=L2:L3=L2/L4:L6=L5/L7:BOTTOM=L7 |
| PCIE_TX_P32 | TX32-DIFF1 | PAIR | 8 | 5.38 | 5 | 10 | 5 | 50 | 6 | 33 | 12 | 12 | 12 | 12 | 6.62 | 85 Ohms | TOP=L2:L3=L2/L4:L6=L5/L7:BOTTOM=L7 |
| PCIE_TX_N33 | TX33-DIFF1 | PAIR | 1 | 5.38 | 5 | 10 | 5 | 50 | 6 | 33 | 12 | 12 | 12 | 12 | 6.62 | 85 Ohms | TOP=L2:L3=L2/L4:L6=L5/L7:BOTTOM=L7 |
| PCIE_TX_N33 | TX33-DIFF1 | PAIR | 2 | 5.5 | 5 | 10 | 5 | 50 | 6 | 20 | 12 | 12 | 12 | 12 | 7.5 | 85 Ohms | TOP=L2:L3=L2/L4:L6=L5/L7:BOTTOM=L7 |
| PCIE_TX_N33 | TX33-DIFF1 | PAIR | 3 | 5.5 | 5 | 10 | 5 | 50 | 6 | 20 | 12 | 12 | 12 | 12 | 7.5 | 85 Ohms | TOP=L2:L3=L2/L4:L6=L5/L7:BOTTOM=L7 |
| PCIE_TX_N33 | TX33-DIFF1 | PAIR | 4 | 5.5 | 5 | 10 | 5 | 50 | 6 | 20 | 12 | 12 | 12 | 12 | 7.5 | 85 Ohms | TOP=L2:L3=L2/L4:L6=L5/L7:BOTTOM=L7 |
| PCIE_TX_N33 | TX33-DIFF1 | PAIR | 5 | 5.5 | 5 | 10 | 5 | 50 | 6 | 20 | 12 | 12 | 12 | 12 | 7.5 | 85 Ohms | TOP=L2:L3=L2/L4:L6=L5/L7:BOTTOM=L7 |
| PCIE_TX_N33 | TX33-DIFF1 | PAIR | 6 | 5.5 | 5 | 10 | 5 | 50 | 6 | 20 | 12 | 12 | 12 | 12 | 7.5 | 85 Ohms | TOP=L2:L3=L2/L4:L6=L5/L7:BOTTOM=L7 |
| PCIE_TX_N33 | TX33-DIFF1 | PAIR | 7 | 5.5 | 5 | 10 | 5 | 50 | 6 | 20 | 12 | 12 | 12 | 12 | 7.5 | 85 Ohms | TOP=L2:L3=L2/L4:L6=L5/L7:BOTTOM=L7 |
| PCIE_TX_N33 | TX33-DIFF1 | PAIR | 8 | 5.38 | 5 | 10 | 5 | 50 | 6 | 33 | 12 | 12 | 12 | 12 | 6.62 | 85 Ohms | TOP=L2:L3=L2/L4:L6=L5/L7:BOTTOM=L7 |
| PCIE_TX_P33 | TX33-DIFF1 | PAIR | 1 | 5.38 | 5 | 10 | 5 | 50 | 6 | 33 | 12 | 12 | 12 | 12 | 6.62 | 85 Ohms | TOP=L2:L3=L2/L4:L6=L5/L7:BOTTOM=L7 |
| PCIE_TX_P33 | TX33-DIFF1 | PAIR | 2 | 5.5 | 5 | 10 | 5 | 50 | 6 | 20 | 12 | 12 | 12 | 12 | 7.5 | 85 Ohms | TOP=L2:L3=L2/L4:L6=L5/L7:BOTTOM=L7 |
| PCIE_TX_P33 | TX33-DIFF1 | PAIR | 3 | 5.5 | 5 | 10 | 5 | 50 | 6 | 20 | 12 | 12 | 12 | 12 | 7.5 | 85 Ohms | TOP=L2:L3=L2/L4:L6=L5/L7:BOTTOM=L7 |
| PCIE_TX_P33 | TX33-DIFF1 | PAIR | 4 | 5.5 | 5 | 10 | 5 | 50 | 6 | 20 | 12 | 12 | 12 | 12 | 7.5 | 85 Ohms | TOP=L2:L3=L2/L4:L6=L5/L7:BOTTOM=L7 |
| PCIE_TX_P33 | TX33-DIFF1 | PAIR | 5 | 5.5 | 5 | 10 | 5 | 50 | 6 | 20 | 12 | 12 | 12 | 12 | 7.5 | 85 Ohms | TOP=L2:L3=L2/L4:L6=L5/L7:BOTTOM=L7 |
| PCIE_TX_P33 | TX33-DIFF1 | PAIR | 6 | 5.5 | 5 | 10 | 5 | 50 | 6 | 20 | 12 | 12 | 12 | 12 | 7.5 | 85 Ohms | TOP=L2:L3=L2/L4:L6=L5/L7:BOTTOM=L7 |
| PCIE_TX_P33 | TX33-DIFF1 | PAIR | 7 | 5.5 | 5 | 10 | 5 | 50 | 6 | 20 | 12 | 12 | 12 | 12 | 7.5 | 85 Ohms | TOP=L2:L3=L2/L4:L6=L5/L7:BOTTOM=L7 |
| PCIE_TX_P33 | TX33-DIFF1 | PAIR | 8 | 5.38 | 5 | 10 | 5 | 50 | 6 | 33 | 12 | 12 | 12 | 12 | 6.62 | 85 Ohms | TOP=L2:L3=L2/L4:L6=L5/L7:BOTTOM=L7 |
| PCIE_TX_N34 | TX34-DIFF1 | PAIR | 1 | 5.38 | 5 | 10 | 5 | 50 | 6 | 33 | 12 | 12 | 12 | 12 | 6.62 | 85 Ohms | TOP=L2:L3=L2/L4:L6=L5/L7:BOTTOM=L7 |
| PCIE_TX_N34 | TX34-DIFF1 | PAIR | 2 | 5.5 | 5 | 10 | 5 | 50 | 6 | 20 | 12 | 12 | 12 | 12 | 7.5 | 85 Ohms | TOP=L2:L3=L2/L4:L6=L5/L7:BOTTOM=L7 |
| PCIE_TX_N34 | TX34-DIFF1 | PAIR | 3 | 5.5 | 5 | 10 | 5 | 50 | 6 | 20 | 12 | 12 | 12 | 12 | 7.5 | 85 Ohms | TOP=L2:L3=L2/L4:L6=L5/L7:BOTTOM=L7 |
| PCIE_TX_N34 | TX34-DIFF1 | PAIR | 4 | 5.5 | 5 | 10 | 5 | 50 | 6 | 20 | 12 | 12 | 12 | 12 | 7.5 | 85 Ohms | TOP=L2:L3=L2/L4:L6=L5/L7:BOTTOM=L7 |
| PCIE_TX_N34 | TX34-DIFF1 | PAIR | 5 | 5.5 | 5 | 10 | 5 | 50 | 6 | 20 | 12 | 12 | 12 | 12 | 7.5 | 85 Ohms | TOP=L2:L3=L2/L4:L6=L5/L7:BOTTOM=L7 |
| PCIE_TX_N34 | TX34-DIFF1 | PAIR | 6 | 5.5 | 5 | 10 | 5 | 50 | 6 | 20 | 12 | 12 | 12 | 12 | 7.5 | 85 Ohms | TOP=L2:L3=L2/L4:L6=L5/L7:BOTTOM=L7 |
| PCIE_TX_N34 | TX34-DIFF1 | PAIR | 7 | 5.5 | 5 | 10 | 5 | 50 | 6 | 20 | 12 | 12 | 12 | 12 | 7.5 | 85 Ohms | TOP=L2:L3=L2/L4:L6=L5/L7:BOTTOM=L7 |
| PCIE_TX_N34 | TX34-DIFF1 | PAIR | 8 | 5.38 | 5 | 10 | 5 | 50 | 6 | 33 | 12 | 12 | 12 | 12 | 6.62 | 85 Ohms | TOP=L2:L3=L2/L4:L6=L5/L7:BOTTOM=L7 |
| PCIE_TX_P34 | TX34-DIFF1 | PAIR | 1 | 5.38 | 5 | 10 | 5 | 50 | 6 | 33 | 12 | 12 | 12 | 12 | 6.62 | 85 Ohms | TOP=L2:L3=L2/L4:L6=L5/L7:BOTTOM=L7 |
| PCIE_TX_P34 | TX34-DIFF1 | PAIR | 2 | 5.5 | 5 | 10 | 5 | 50 | 6 | 20 | 12 | 12 | 12 | 12 | 7.5 | 85 Ohms | TOP=L2:L3=L2/L4:L6=L5/L7:BOTTOM=L7 |
| PCIE_TX_P34 | TX34-DIFF1 | PAIR | 3 | 5.5 | 5 | 10 | 5 | 50 | 6 | 20 | 12 | 12 | 12 | 12 | 7.5 | 85 Ohms | TOP=L2:L3=L2/L4:L6=L5/L7:BOTTOM=L7 |
| PCIE_TX_P34 | TX34-DIFF1 | PAIR | 4 | 5.5 | 5 | 10 | 5 | 50 | 6 | 20 | 12 | 12 | 12 | 12 | 7.5 | 85 Ohms | TOP=L2:L3=L2/L4:L6=L5/L7:BOTTOM=L7 |
| PCIE_TX_P34 | TX34-DIFF1 | PAIR | 5 | 5.5 | 5 | 10 | 5 | 50 | 6 | 20 | 12 | 12 | 12 | 12 | 7.5 | 85 Ohms | TOP=L2:L3=L2/L4:L6=L5/L7:BOTTOM=L7 |
| PCIE_TX_P34 | TX34-DIFF1 | PAIR | 6 | 5.5 | 5 | 10 | 5 | 50 | 6 | 20 | 12 | 12 | 12 | 12 | 7.5 | 85 Ohms | TOP=L2:L3=L2/L4:L6=L5/L7:BOTTOM=L7 |
| PCIE_TX_P34 | TX34-DIFF1 | PAIR | 7 | 5.5 | 5 | 10 | 5 | 50 | 6 | 20 | 12 | 12 | 12 | 12 | 7.5 | 85 Ohms | TOP=L2:L3=L2/L4:L6=L5/L7:BOTTOM=L7 |
| PCIE_TX_P34 | TX34-DIFF1 | PAIR | 8 | 5.38 | 5 | 10 | 5 | 50 | 6 | 33 | 12 | 12 | 12 | 12 | 6.62 | 85 Ohms | TOP=L2:L3=L2/L4:L6=L5/L7:BOTTOM=L7 |
| PCIE_TX_N35 | TX35-DIFF1 | PAIR | 1 | 5.38 | 5 | 10 | 5 | 50 | 6 | 33 | 12 | 12 | 12 | 12 | 6.62 | 85 Ohms | TOP=L2:L3=L2/L4:L6=L5/L7:BOTTOM=L7 |
| PCIE_TX_N35 | TX35-DIFF1 | PAIR | 2 | 5.5 | 5 | 10 | 5 | 50 | 6 | 20 | 12 | 12 | 12 | 12 | 7.5 | 85 Ohms | TOP=L2:L3=L2/L4:L6=L5/L7:BOTTOM=L7 |
| PCIE_TX_N35 | TX35-DIFF1 | PAIR | 3 | 5.5 | 5 | 10 | 5 | 50 | 6 | 20 | 12 | 12 | 12 | 12 | 7.5 | 85 Ohms | TOP=L2:L3=L2/L4:L6=L5/L7:BOTTOM=L7 |
| PCIE_TX_N35 | TX35-DIFF1 | PAIR | 4 | 5.5 | 5 | 10 | 5 | 50 | 6 | 20 | 12 | 12 | 12 | 12 | 7.5 | 85 Ohms | TOP=L2:L3=L2/L4:L6=L5/L7:BOTTOM=L7 |
| PCIE_TX_N35 | TX35-DIFF1 | PAIR | 5 | 5.5 | 5 | 10 | 5 | 50 | 6 | 20 | 12 | 12 | 12 | 12 | 7.5 | 85 Ohms | TOP=L2:L3=L2/L4:L6=L5/L7:BOTTOM=L7 |
| PCIE_TX_N35 | TX35-DIFF1 | PAIR | 6 | 5.5 | 5 | 10 | 5 | 50 | 6 | 20 | 12 | 12 | 12 | 12 | 7.5 | 85 Ohms | TOP=L2:L3=L2/L4:L6=L5/L7:BOTTOM=L7 |
| PCIE_TX_N35 | TX35-DIFF1 | PAIR | 7 | 5.5 | 5 | 10 | 5 | 50 | 6 | 20 | 12 | 12 | 12 | 12 | 7.5 | 85 Ohms | TOP=L2:L3=L2/L4:L6=L5/L7:BOTTOM=L7 |
| PCIE_TX_N35 | TX35-DIFF1 | PAIR | 8 | 5.38 | 5 | 10 | 5 | 50 | 6 | 33 | 12 | 12 | 12 | 12 | 6.62 | 85 Ohms | TOP=L2:L3=L2/L4:L6=L5/L7:BOTTOM=L7 |
| PCIE_TX_P35 | TX35-DIFF1 | PAIR | 1 | 5.38 | 5 | 10 | 5 | 50 | 6 | 33 | 12 | 12 | 12 | 12 | 6.62 | 85 Ohms | TOP=L2:L3=L2/L4:L6=L5/L7:BOTTOM=L7 |
| PCIE_TX_P35 | TX35-DIFF1 | PAIR | 2 | 5.5 | 5 | 10 | 5 | 50 | 6 | 20 | 12 | 12 | 12 | 12 | 7.5 | 85 Ohms | TOP=L2:L3=L2/L4:L6=L5/L7:BOTTOM=L7 |
| PCIE_TX_P35 | TX35-DIFF1 | PAIR | 3 | 5.5 | 5 | 10 | 5 | 50 | 6 | 20 | 12 | 12 | 12 | 12 | 7.5 | 85 Ohms | TOP=L2:L3=L2/L4:L6=L5/L7:BOTTOM=L7 |
| PCIE_TX_P35 | TX35-DIFF1 | PAIR | 4 | 5.5 | 5 | 10 | 5 | 50 | 6 | 20 | 12 | 12 | 12 | 12 | 7.5 | 85 Ohms | TOP=L2:L3=L2/L4:L6=L5/L7:BOTTOM=L7 |
| PCIE_TX_P35 | TX35-DIFF1 | PAIR | 5 | 5.5 | 5 | 10 | 5 | 50 | 6 | 20 | 12 | 12 | 12 | 12 | 7.5 | 85 Ohms | TOP=L2:L3=L2/L4:L6=L5/L7:BOTTOM=L7 |
| PCIE_TX_P35 | TX35-DIFF1 | PAIR | 6 | 5.5 | 5 | 10 | 5 | 50 | 6 | 20 | 12 | 12 | 12 | 12 | 7.5 | 85 Ohms | TOP=L2:L3=L2/L4:L6=L5/L7:BOTTOM=L7 |
| PCIE_TX_P35 | TX35-DIFF1 | PAIR | 7 | 5.5 | 5 | 10 | 5 | 50 | 6 | 20 | 12 | 12 | 12 | 12 | 7.5 | 85 Ohms | TOP=L2:L3=L2/L4:L6=L5/L7:BOTTOM=L7 |
| PCIE_TX_P35 | TX35-DIFF1 | PAIR | 8 | 5.38 | 5 | 10 | 5 | 50 | 6 | 33 | 12 | 12 | 12 | 12 | 6.62 | 85 Ohms | TOP=L2:L3=L2/L4:L6=L5/L7:BOTTOM=L7 |
| PCIE_TX_N36 | TX36-DIFF1 | PAIR | 1 | 5.38 | 5 | 10 | 5 | 50 | 6 | 33 | 12 | 12 | 12 | 12 | 6.62 | 85 Ohms | TOP=L2:L3=L2/L4:L6=L5/L7:BOTTOM=L7 |
| PCIE_TX_N36 | TX36-DIFF1 | PAIR | 2 | 5.5 | 5 | 10 | 5 | 50 | 6 | 20 | 12 | 12 | 12 | 12 | 7.5 | 85 Ohms | TOP=L2:L3=L2/L4:L6=L5/L7:BOTTOM=L7 |
| PCIE_TX_N36 | TX36-DIFF1 | PAIR | 3 | 5.5 | 5 | 10 | 5 | 50 | 6 | 20 | 12 | 12 | 12 | 12 | 7.5 | 85 Ohms | TOP=L2:L3=L2/L4:L6=L5/L7:BOTTOM=L7 |
| PCIE_TX_N36 | TX36-DIFF1 | PAIR | 4 | 5.5 | 5 | 10 | 5 | 50 | 6 | 20 | 12 | 12 | 12 | 12 | 7.5 | 85 Ohms | TOP=L2:L3=L2/L4:L6=L5/L7:BOTTOM=L7 |
| PCIE_TX_N36 | TX36-DIFF1 | PAIR | 5 | 5.5 | 5 | 10 | 5 | 50 | 6 | 20 | 12 | 12 | 12 | 12 | 7.5 | 85 Ohms | TOP=L2:L3=L2/L4:L6=L5/L7:BOTTOM=L7 |
| PCIE_TX_N36 | TX36-DIFF1 | PAIR | 6 | 5.5 | 5 | 10 | 5 | 50 | 6 | 20 | 12 | 12 | 12 | 12 | 7.5 | 85 Ohms | TOP=L2:L3=L2/L4:L6=L5/L7:BOTTOM=L7 |
| PCIE_TX_N36 | TX36-DIFF1 | PAIR | 7 | 5.5 | 5 | 10 | 5 | 50 | 6 | 20 | 12 | 12 | 12 | 12 | 7.5 | 85 Ohms | TOP=L2:L3=L2/L4:L6=L5/L7:BOTTOM=L7 |
| PCIE_TX_N36 | TX36-DIFF1 | PAIR | 8 | 5.38 | 5 | 10 | 5 | 50 | 6 | 33 | 12 | 12 | 12 | 12 | 6.62 | 85 Ohms | TOP=L2:L3=L2/L4:L6=L5/L7:BOTTOM=L7 |
| PCIE_TX_P36 | TX36-DIFF1 | PAIR | 1 | 5.38 | 5 | 10 | 5 | 50 | 6 | 33 | 12 | 12 | 12 | 12 | 6.62 | 85 Ohms | TOP=L2:L3=L2/L4:L6=L5/L7:BOTTOM=L7 |
| PCIE_TX_P36 | TX36-DIFF1 | PAIR | 2 | 5.5 | 5 | 10 | 5 | 50 | 6 | 20 | 12 | 12 | 12 | 12 | 7.5 | 85 Ohms | TOP=L2:L3=L2/L4:L6=L5/L7:BOTTOM=L7 |
| PCIE_TX_P36 | TX36-DIFF1 | PAIR | 3 | 5.5 | 5 | 10 | 5 | 50 | 6 | 20 | 12 | 12 | 12 | 12 | 7.5 | 85 Ohms | TOP=L2:L3=L2/L4:L6=L5/L7:BOTTOM=L7 |
| PCIE_TX_P36 | TX36-DIFF1 | PAIR | 4 | 5.5 | 5 | 10 | 5 | 50 | 6 | 20 | 12 | 12 | 12 | 12 | 7.5 | 85 Ohms | TOP=L2:L3=L2/L4:L6=L5/L7:BOTTOM=L7 |
| PCIE_TX_P36 | TX36-DIFF1 | PAIR | 5 | 5.5 | 5 | 10 | 5 | 50 | 6 | 20 | 12 | 12 | 12 | 12 | 7.5 | 85 Ohms | TOP=L2:L3=L2/L4:L6=L5/L7:BOTTOM=L7 |
| PCIE_TX_P36 | TX36-DIFF1 | PAIR | 6 | 5.5 | 5 | 10 | 5 | 50 | 6 | 20 | 12 | 12 | 12 | 12 | 7.5 | 85 Ohms | TOP=L2:L3=L2/L4:L6=L5/L7:BOTTOM=L7 |
| PCIE_TX_P36 | TX36-DIFF1 | PAIR | 7 | 5.5 | 5 | 10 | 5 | 50 | 6 | 20 | 12 | 12 | 12 | 12 | 7.5 | 85 Ohms | TOP=L2:L3=L2/L4:L6=L5/L7:BOTTOM=L7 |
| PCIE_TX_P36 | TX36-DIFF1 | PAIR | 8 | 5.38 | 5 | 10 | 5 | 50 | 6 | 33 | 12 | 12 | 12 | 12 | 6.62 | 85 Ohms | TOP=L2:L3=L2/L4:L6=L5/L7:BOTTOM=L7 |
| PCIE_TX_N37 | TX37-DIFF1 | PAIR | 1 | 5.38 | 5 | 10 | 5 | 50 | 6 | 33 | 12 | 12 | 12 | 12 | 6.62 | 85 Ohms | TOP=L2:L3=L2/L4:L6=L5/L7:BOTTOM=L7 |
| PCIE_TX_N37 | TX37-DIFF1 | PAIR | 2 | 5.5 | 5 | 10 | 5 | 50 | 6 | 20 | 12 | 12 | 12 | 12 | 7.5 | 85 Ohms | TOP=L2:L3=L2/L4:L6=L5/L7:BOTTOM=L7 |
| PCIE_TX_N37 | TX37-DIFF1 | PAIR | 3 | 5.5 | 5 | 10 | 5 | 50 | 6 | 20 | 12 | 12 | 12 | 12 | 7.5 | 85 Ohms | TOP=L2:L3=L2/L4:L6=L5/L7:BOTTOM=L7 |
| PCIE_TX_N37 | TX37-DIFF1 | PAIR | 4 | 5.5 | 5 | 10 | 5 | 50 | 6 | 20 | 12 | 12 | 12 | 12 | 7.5 | 85 Ohms | TOP=L2:L3=L2/L4:L6=L5/L7:BOTTOM=L7 |
| PCIE_TX_N37 | TX37-DIFF1 | PAIR | 5 | 5.5 | 5 | 10 | 5 | 50 | 6 | 20 | 12 | 12 | 12 | 12 | 7.5 | 85 Ohms | TOP=L2:L3=L2/L4:L6=L5/L7:BOTTOM=L7 |
| PCIE_TX_N37 | TX37-DIFF1 | PAIR | 6 | 5.5 | 5 | 10 | 5 | 50 | 6 | 20 | 12 | 12 | 12 | 12 | 7.5 | 85 Ohms | TOP=L2:L3=L2/L4:L6=L5/L7:BOTTOM=L7 |
| PCIE_TX_N37 | TX37-DIFF1 | PAIR | 7 | 5.5 | 5 | 10 | 5 | 50 | 6 | 20 | 12 | 12 | 12 | 12 | 7.5 | 85 Ohms | TOP=L2:L3=L2/L4:L6=L5/L7:BOTTOM=L7 |
| PCIE_TX_N37 | TX37-DIFF1 | PAIR | 8 | 5.38 | 5 | 10 | 5 | 50 | 6 | 33 | 12 | 12 | 12 | 12 | 6.62 | 85 Ohms | TOP=L2:L3=L2/L4:L6=L5/L7:BOTTOM=L7 |
| PCIE_TX_P37 | TX37-DIFF1 | PAIR | 1 | 5.38 | 5 | 10 | 5 | 50 | 6 | 33 | 12 | 12 | 12 | 12 | 6.62 | 85 Ohms | TOP=L2:L3=L2/L4:L6=L5/L7:BOTTOM=L7 |
| PCIE_TX_P37 | TX37-DIFF1 | PAIR | 2 | 5.5 | 5 | 10 | 5 | 50 | 6 | 20 | 12 | 12 | 12 | 12 | 7.5 | 85 Ohms | TOP=L2:L3=L2/L4:L6=L5/L7:BOTTOM=L7 |
| PCIE_TX_P37 | TX37-DIFF1 | PAIR | 3 | 5.5 | 5 | 10 | 5 | 50 | 6 | 20 | 12 | 12 | 12 | 12 | 7.5 | 85 Ohms | TOP=L2:L3=L2/L4:L6=L5/L7:BOTTOM=L7 |
| PCIE_TX_P37 | TX37-DIFF1 | PAIR | 4 | 5.5 | 5 | 10 | 5 | 50 | 6 | 20 | 12 | 12 | 12 | 12 | 7.5 | 85 Ohms | TOP=L2:L3=L2/L4:L6=L5/L7:BOTTOM=L7 |
| PCIE_TX_P37 | TX37-DIFF1 | PAIR | 5 | 5.5 | 5 | 10 | 5 | 50 | 6 | 20 | 12 | 12 | 12 | 12 | 7.5 | 85 Ohms | TOP=L2:L3=L2/L4:L6=L5/L7:BOTTOM=L7 |
| PCIE_TX_P37 | TX37-DIFF1 | PAIR | 6 | 5.5 | 5 | 10 | 5 | 50 | 6 | 20 | 12 | 12 | 12 | 12 | 7.5 | 85 Ohms | TOP=L2:L3=L2/L4:L6=L5/L7:BOTTOM=L7 |
| PCIE_TX_P37 | TX37-DIFF1 | PAIR | 7 | 5.5 | 5 | 10 | 5 | 50 | 6 | 20 | 12 | 12 | 12 | 12 | 7.5 | 85 Ohms | TOP=L2:L3=L2/L4:L6=L5/L7:BOTTOM=L7 |
| PCIE_TX_P37 | TX37-DIFF1 | PAIR | 8 | 5.38 | 5 | 10 | 5 | 50 | 6 | 33 | 12 | 12 | 12 | 12 | 6.62 | 85 Ohms | TOP=L2:L3=L2/L4:L6=L5/L7:BOTTOM=L7 |
| PCIE_TX_N38 | TX38-DIFF1 | PAIR | 1 | 5.38 | 5 | 10 | 5 | 50 | 6 | 33 | 12 | 12 | 12 | 12 | 6.62 | 85 Ohms | TOP=L2:L3=L2/L4:L6=L5/L7:BOTTOM=L7 |
| PCIE_TX_N38 | TX38-DIFF1 | PAIR | 2 | 5.5 | 5 | 10 | 5 | 50 | 6 | 20 | 12 | 12 | 12 | 12 | 7.5 | 85 Ohms | TOP=L2:L3=L2/L4:L6=L5/L7:BOTTOM=L7 |
| PCIE_TX_N38 | TX38-DIFF1 | PAIR | 3 | 5.5 | 5 | 10 | 5 | 50 | 6 | 20 | 12 | 12 | 12 | 12 | 7.5 | 85 Ohms | TOP=L2:L3=L2/L4:L6=L5/L7:BOTTOM=L7 |
| PCIE_TX_N38 | TX38-DIFF1 | PAIR | 4 | 5.5 | 5 | 10 | 5 | 50 | 6 | 20 | 12 | 12 | 12 | 12 | 7.5 | 85 Ohms | TOP=L2:L3=L2/L4:L6=L5/L7:BOTTOM=L7 |
| PCIE_TX_N38 | TX38-DIFF1 | PAIR | 5 | 5.5 | 5 | 10 | 5 | 50 | 6 | 20 | 12 | 12 | 12 | 12 | 7.5 | 85 Ohms | TOP=L2:L3=L2/L4:L6=L5/L7:BOTTOM=L7 |
| PCIE_TX_N38 | TX38-DIFF1 | PAIR | 6 | 5.5 | 5 | 10 | 5 | 50 | 6 | 20 | 12 | 12 | 12 | 12 | 7.5 | 85 Ohms | TOP=L2:L3=L2/L4:L6=L5/L7:BOTTOM=L7 |
| PCIE_TX_N38 | TX38-DIFF1 | PAIR | 7 | 5.5 | 5 | 10 | 5 | 50 | 6 | 20 | 12 | 12 | 12 | 12 | 7.5 | 85 Ohms | TOP=L2:L3=L2/L4:L6=L5/L7:BOTTOM=L7 |
| PCIE_TX_N38 | TX38-DIFF1 | PAIR | 8 | 5.38 | 5 | 10 | 5 | 50 | 6 | 33 | 12 | 12 | 12 | 12 | 6.62 | 85 Ohms | TOP=L2:L3=L2/L4:L6=L5/L7:BOTTOM=L7 |
| PCIE_TX_P38 | TX38-DIFF1 | PAIR | 1 | 5.38 | 5 | 10 | 5 | 50 | 6 | 33 | 12 | 12 | 12 | 12 | 6.62 | 85 Ohms | TOP=L2:L3=L2/L4:L6=L5/L7:BOTTOM=L7 |
| PCIE_TX_P38 | TX38-DIFF1 | PAIR | 2 | 5.5 | 5 | 10 | 5 | 50 | 6 | 20 | 12 | 12 | 12 | 12 | 7.5 | 85 Ohms | TOP=L2:L3=L2/L4:L6=L5/L7:BOTTOM=L7 |
| PCIE_TX_P38 | TX38-DIFF1 | PAIR | 3 | 5.5 | 5 | 10 | 5 | 50 | 6 | 20 | 12 | 12 | 12 | 12 | 7.5 | 85 Ohms | TOP=L2:L3=L2/L4:L6=L5/L7:BOTTOM=L7 |
| PCIE_TX_P38 | TX38-DIFF1 | PAIR | 4 | 5.5 | 5 | 10 | 5 | 50 | 6 | 20 | 12 | 12 | 12 | 12 | 7.5 | 85 Ohms | TOP=L2:L3=L2/L4:L6=L5/L7:BOTTOM=L7 |
| PCIE_TX_P38 | TX38-DIFF1 | PAIR | 5 | 5.5 | 5 | 10 | 5 | 50 | 6 | 20 | 12 | 12 | 12 | 12 | 7.5 | 85 Ohms | TOP=L2:L3=L2/L4:L6=L5/L7:BOTTOM=L7 |
| PCIE_TX_P38 | TX38-DIFF1 | PAIR | 6 | 5.5 | 5 | 10 | 5 | 50 | 6 | 20 | 12 | 12 | 12 | 12 | 7.5 | 85 Ohms | TOP=L2:L3=L2/L4:L6=L5/L7:BOTTOM=L7 |
| PCIE_TX_P38 | TX38-DIFF1 | PAIR | 7 | 5.5 | 5 | 10 | 5 | 50 | 6 | 20 | 12 | 12 | 12 | 12 | 7.5 | 85 Ohms | TOP=L2:L3=L2/L4:L6=L5/L7:BOTTOM=L7 |
| PCIE_TX_P38 | TX38-DIFF1 | PAIR | 8 | 5.38 | 5 | 10 | 5 | 50 | 6 | 33 | 12 | 12 | 12 | 12 | 6.62 | 85 Ohms | TOP=L2:L3=L2/L4:L6=L5/L7:BOTTOM=L7 |
| PCIE_TX_N39 | TX39-DIFF1 | PAIR | 1 | 5.38 | 5 | 10 | 5 | 50 | 6 | 33 | 12 | 12 | 12 | 12 | 6.62 | 85 Ohms | TOP=L2:L3=L2/L4:L6=L5/L7:BOTTOM=L7 |
| PCIE_TX_N39 | TX39-DIFF1 | PAIR | 2 | 5.5 | 5 | 10 | 5 | 50 | 6 | 20 | 12 | 12 | 12 | 12 | 7.5 | 85 Ohms | TOP=L2:L3=L2/L4:L6=L5/L7:BOTTOM=L7 |
| PCIE_TX_N39 | TX39-DIFF1 | PAIR | 3 | 5.5 | 5 | 10 | 5 | 50 | 6 | 20 | 12 | 12 | 12 | 12 | 7.5 | 85 Ohms | TOP=L2:L3=L2/L4:L6=L5/L7:BOTTOM=L7 |
| PCIE_TX_N39 | TX39-DIFF1 | PAIR | 4 | 5.5 | 5 | 10 | 5 | 50 | 6 | 20 | 12 | 12 | 12 | 12 | 7.5 | 85 Ohms | TOP=L2:L3=L2/L4:L6=L5/L7:BOTTOM=L7 |
| PCIE_TX_N39 | TX39-DIFF1 | PAIR | 5 | 5.5 | 5 | 10 | 5 | 50 | 6 | 20 | 12 | 12 | 12 | 12 | 7.5 | 85 Ohms | TOP=L2:L3=L2/L4:L6=L5/L7:BOTTOM=L7 |
| PCIE_TX_N39 | TX39-DIFF1 | PAIR | 6 | 5.5 | 5 | 10 | 5 | 50 | 6 | 20 | 12 | 12 | 12 | 12 | 7.5 | 85 Ohms | TOP=L2:L3=L2/L4:L6=L5/L7:BOTTOM=L7 |
| PCIE_TX_N39 | TX39-DIFF1 | PAIR | 7 | 5.5 | 5 | 10 | 5 | 50 | 6 | 20 | 12 | 12 | 12 | 12 | 7.5 | 85 Ohms | TOP=L2:L3=L2/L4:L6=L5/L7:BOTTOM=L7 |
| PCIE_TX_N39 | TX39-DIFF1 | PAIR | 8 | 5.38 | 5 | 10 | 5 | 50 | 6 | 33 | 12 | 12 | 12 | 12 | 6.62 | 85 Ohms | TOP=L2:L3=L2/L4:L6=L5/L7:BOTTOM=L7 |
| PCIE_TX_P39 | TX39-DIFF1 | PAIR | 1 | 5.38 | 5 | 10 | 5 | 50 | 6 | 33 | 12 | 12 | 12 | 12 | 6.62 | 85 Ohms | TOP=L2:L3=L2/L4:L6=L5/L7:BOTTOM=L7 |
| PCIE_TX_P39 | TX39-DIFF1 | PAIR | 2 | 5.5 | 5 | 10 | 5 | 50 | 6 | 20 | 12 | 12 | 12 | 12 | 7.5 | 85 Ohms | TOP=L2:L3=L2/L4:L6=L5/L7:BOTTOM=L7 |
| PCIE_TX_P39 | TX39-DIFF1 | PAIR | 3 | 5.5 | 5 | 10 | 5 | 50 | 6 | 20 | 12 | 12 | 12 | 12 | 7.5 | 85 Ohms | TOP=L2:L3=L2/L4:L6=L5/L7:BOTTOM=L7 |
| PCIE_TX_P39 | TX39-DIFF1 | PAIR | 4 | 5.5 | 5 | 10 | 5 | 50 | 6 | 20 | 12 | 12 | 12 | 12 | 7.5 | 85 Ohms | TOP=L2:L3=L2/L4:L6=L5/L7:BOTTOM=L7 |
| PCIE_TX_P39 | TX39-DIFF1 | PAIR | 5 | 5.5 | 5 | 10 | 5 | 50 | 6 | 20 | 12 | 12 | 12 | 12 | 7.5 | 85 Ohms | TOP=L2:L3=L2/L4:L6=L5/L7:BOTTOM=L7 |
| PCIE_TX_P39 | TX39-DIFF1 | PAIR | 6 | 5.5 | 5 | 10 | 5 | 50 | 6 | 20 | 12 | 12 | 12 | 12 | 7.5 | 85 Ohms | TOP=L2:L3=L2/L4:L6=L5/L7:BOTTOM=L7 |
| PCIE_TX_P39 | TX39-DIFF1 | PAIR | 7 | 5.5 | 5 | 10 | 5 | 50 | 6 | 20 | 12 | 12 | 12 | 12 | 7.5 | 85 Ohms | TOP=L2:L3=L2/L4:L6=L5/L7:BOTTOM=L7 |
| PCIE_TX_P39 | TX39-DIFF1 | PAIR | 8 | 5.38 | 5 | 10 | 5 | 50 | 6 | 33 | 12 | 12 | 12 | 12 | 6.62 | 85 Ohms | TOP=L2:L3=L2/L4:L6=L5/L7:BOTTOM=L7 |
| PCIE_TX_N3 | TX3-DIFF1 | PAIR | 1 | 5.38 | 5 | 10 | 5 | 50 | 6 | 33 | 12 | 12 | 12 | 12 | 6.62 | 85 Ohms | TOP=L2:L3=L2/L4:L6=L5/L7:BOTTOM=L7 |
| PCIE_TX_N3 | TX3-DIFF1 | PAIR | 2 | 5.5 | 5 | 10 | 5 | 50 | 6 | 20 | 12 | 12 | 12 | 12 | 7.5 | 85 Ohms | TOP=L2:L3=L2/L4:L6=L5/L7:BOTTOM=L7 |
| PCIE_TX_N3 | TX3-DIFF1 | PAIR | 3 | 5.5 | 5 | 10 | 5 | 50 | 6 | 20 | 12 | 12 | 12 | 12 | 7.5 | 85 Ohms | TOP=L2:L3=L2/L4:L6=L5/L7:BOTTOM=L7 |
| PCIE_TX_N3 | TX3-DIFF1 | PAIR | 4 | 5.5 | 5 | 10 | 5 | 50 | 6 | 20 | 12 | 12 | 12 | 12 | 7.5 | 85 Ohms | TOP=L2:L3=L2/L4:L6=L5/L7:BOTTOM=L7 |
| PCIE_TX_N3 | TX3-DIFF1 | PAIR | 5 | 5.5 | 5 | 10 | 5 | 50 | 6 | 20 | 12 | 12 | 12 | 12 | 7.5 | 85 Ohms | TOP=L2:L3=L2/L4:L6=L5/L7:BOTTOM=L7 |
| PCIE_TX_N3 | TX3-DIFF1 | PAIR | 6 | 5.5 | 5 | 10 | 5 | 50 | 6 | 20 | 12 | 12 | 12 | 12 | 7.5 | 85 Ohms | TOP=L2:L3=L2/L4:L6=L5/L7:BOTTOM=L7 |
| PCIE_TX_N3 | TX3-DIFF1 | PAIR | 7 | 5.5 | 5 | 10 | 5 | 50 | 6 | 20 | 12 | 12 | 12 | 12 | 7.5 | 85 Ohms | TOP=L2:L3=L2/L4:L6=L5/L7:BOTTOM=L7 |
| PCIE_TX_N3 | TX3-DIFF1 | PAIR | 8 | 5.38 | 5 | 10 | 5 | 50 | 6 | 33 | 12 | 12 | 12 | 12 | 6.62 | 85 Ohms | TOP=L2:L3=L2/L4:L6=L5/L7:BOTTOM=L7 |
| PCIE_TX_P3 | TX3-DIFF1 | PAIR | 1 | 5.38 | 5 | 10 | 5 | 50 | 6 | 33 | 12 | 12 | 12 | 12 | 6.62 | 85 Ohms | TOP=L2:L3=L2/L4:L6=L5/L7:BOTTOM=L7 |
| PCIE_TX_P3 | TX3-DIFF1 | PAIR | 2 | 5.5 | 5 | 10 | 5 | 50 | 6 | 20 | 12 | 12 | 12 | 12 | 7.5 | 85 Ohms | TOP=L2:L3=L2/L4:L6=L5/L7:BOTTOM=L7 |
| PCIE_TX_P3 | TX3-DIFF1 | PAIR | 3 | 5.5 | 5 | 10 | 5 | 50 | 6 | 20 | 12 | 12 | 12 | 12 | 7.5 | 85 Ohms | TOP=L2:L3=L2/L4:L6=L5/L7:BOTTOM=L7 |
| PCIE_TX_P3 | TX3-DIFF1 | PAIR | 4 | 5.5 | 5 | 10 | 5 | 50 | 6 | 20 | 12 | 12 | 12 | 12 | 7.5 | 85 Ohms | TOP=L2:L3=L2/L4:L6=L5/L7:BOTTOM=L7 |
| PCIE_TX_P3 | TX3-DIFF1 | PAIR | 5 | 5.5 | 5 | 10 | 5 | 50 | 6 | 20 | 12 | 12 | 12 | 12 | 7.5 | 85 Ohms | TOP=L2:L3=L2/L4:L6=L5/L7:BOTTOM=L7 |
| PCIE_TX_P3 | TX3-DIFF1 | PAIR | 6 | 5.5 | 5 | 10 | 5 | 50 | 6 | 20 | 12 | 12 | 12 | 12 | 7.5 | 85 Ohms | TOP=L2:L3=L2/L4:L6=L5/L7:BOTTOM=L7 |
| PCIE_TX_P3 | TX3-DIFF1 | PAIR | 7 | 5.5 | 5 | 10 | 5 | 50 | 6 | 20 | 12 | 12 | 12 | 12 | 7.5 | 85 Ohms | TOP=L2:L3=L2/L4:L6=L5/L7:BOTTOM=L7 |
| PCIE_TX_P3 | TX3-DIFF1 | PAIR | 8 | 5.38 | 5 | 10 | 5 | 50 | 6 | 33 | 12 | 12 | 12 | 12 | 6.62 | 85 Ohms | TOP=L2:L3=L2/L4:L6=L5/L7:BOTTOM=L7 |
| PCIE_TX_N40 | TX40-DIFF1 | PAIR | 1 | 5.38 | 5 | 10 | 5 | 50 | 6 | 33 | 12 | 12 | 12 | 12 | 6.62 | 85 Ohms | TOP=L2:L3=L2/L4:L6=L5/L7:BOTTOM=L7 |
| PCIE_TX_N40 | TX40-DIFF1 | PAIR | 2 | 5.5 | 5 | 10 | 5 | 50 | 6 | 20 | 12 | 12 | 12 | 12 | 7.5 | 85 Ohms | TOP=L2:L3=L2/L4:L6=L5/L7:BOTTOM=L7 |
| PCIE_TX_N40 | TX40-DIFF1 | PAIR | 3 | 5.5 | 5 | 10 | 5 | 50 | 6 | 20 | 12 | 12 | 12 | 12 | 7.5 | 85 Ohms | TOP=L2:L3=L2/L4:L6=L5/L7:BOTTOM=L7 |
| PCIE_TX_N40 | TX40-DIFF1 | PAIR | 4 | 5.5 | 5 | 10 | 5 | 50 | 6 | 20 | 12 | 12 | 12 | 12 | 7.5 | 85 Ohms | TOP=L2:L3=L2/L4:L6=L5/L7:BOTTOM=L7 |
| PCIE_TX_N40 | TX40-DIFF1 | PAIR | 5 | 5.5 | 5 | 10 | 5 | 50 | 6 | 20 | 12 | 12 | 12 | 12 | 7.5 | 85 Ohms | TOP=L2:L3=L2/L4:L6=L5/L7:BOTTOM=L7 |
| PCIE_TX_N40 | TX40-DIFF1 | PAIR | 6 | 5.5 | 5 | 10 | 5 | 50 | 6 | 20 | 12 | 12 | 12 | 12 | 7.5 | 85 Ohms | TOP=L2:L3=L2/L4:L6=L5/L7:BOTTOM=L7 |
| PCIE_TX_N40 | TX40-DIFF1 | PAIR | 7 | 5.5 | 5 | 10 | 5 | 50 | 6 | 20 | 12 | 12 | 12 | 12 | 7.5 | 85 Ohms | TOP=L2:L3=L2/L4:L6=L5/L7:BOTTOM=L7 |
| PCIE_TX_N40 | TX40-DIFF1 | PAIR | 8 | 5.38 | 5 | 10 | 5 | 50 | 6 | 33 | 12 | 12 | 12 | 12 | 6.62 | 85 Ohms | TOP=L2:L3=L2/L4:L6=L5/L7:BOTTOM=L7 |
| PCIE_TX_P40 | TX40-DIFF1 | PAIR | 1 | 5.38 | 5 | 10 | 5 | 50 | 6 | 33 | 12 | 12 | 12 | 12 | 6.62 | 85 Ohms | TOP=L2:L3=L2/L4:L6=L5/L7:BOTTOM=L7 |
| PCIE_TX_P40 | TX40-DIFF1 | PAIR | 2 | 5.5 | 5 | 10 | 5 | 50 | 6 | 20 | 12 | 12 | 12 | 12 | 7.5 | 85 Ohms | TOP=L2:L3=L2/L4:L6=L5/L7:BOTTOM=L7 |
| PCIE_TX_P40 | TX40-DIFF1 | PAIR | 3 | 5.5 | 5 | 10 | 5 | 50 | 6 | 20 | 12 | 12 | 12 | 12 | 7.5 | 85 Ohms | TOP=L2:L3=L2/L4:L6=L5/L7:BOTTOM=L7 |
| PCIE_TX_P40 | TX40-DIFF1 | PAIR | 4 | 5.5 | 5 | 10 | 5 | 50 | 6 | 20 | 12 | 12 | 12 | 12 | 7.5 | 85 Ohms | TOP=L2:L3=L2/L4:L6=L5/L7:BOTTOM=L7 |
| PCIE_TX_P40 | TX40-DIFF1 | PAIR | 5 | 5.5 | 5 | 10 | 5 | 50 | 6 | 20 | 12 | 12 | 12 | 12 | 7.5 | 85 Ohms | TOP=L2:L3=L2/L4:L6=L5/L7:BOTTOM=L7 |
| PCIE_TX_P40 | TX40-DIFF1 | PAIR | 6 | 5.5 | 5 | 10 | 5 | 50 | 6 | 20 | 12 | 12 | 12 | 12 | 7.5 | 85 Ohms | TOP=L2:L3=L2/L4:L6=L5/L7:BOTTOM=L7 |
| PCIE_TX_P40 | TX40-DIFF1 | PAIR | 7 | 5.5 | 5 | 10 | 5 | 50 | 6 | 20 | 12 | 12 | 12 | 12 | 7.5 | 85 Ohms | TOP=L2:L3=L2/L4:L6=L5/L7:BOTTOM=L7 |
| PCIE_TX_P40 | TX40-DIFF1 | PAIR | 8 | 5.38 | 5 | 10 | 5 | 50 | 6 | 33 | 12 | 12 | 12 | 12 | 6.62 | 85 Ohms | TOP=L2:L3=L2/L4:L6=L5/L7:BOTTOM=L7 |
| PCIE_TX_N41 | TX41-DIFF1 | PAIR | 1 | 5.38 | 5 | 10 | 5 | 50 | 6 | 33 | 12 | 12 | 12 | 12 | 6.62 | 85 Ohms | TOP=L2:L3=L2/L4:L6=L5/L7:BOTTOM=L7 |
| PCIE_TX_N41 | TX41-DIFF1 | PAIR | 2 | 5.5 | 5 | 10 | 5 | 50 | 6 | 20 | 12 | 12 | 12 | 12 | 7.5 | 85 Ohms | TOP=L2:L3=L2/L4:L6=L5/L7:BOTTOM=L7 |
| PCIE_TX_N41 | TX41-DIFF1 | PAIR | 3 | 5.5 | 5 | 10 | 5 | 50 | 6 | 20 | 12 | 12 | 12 | 12 | 7.5 | 85 Ohms | TOP=L2:L3=L2/L4:L6=L5/L7:BOTTOM=L7 |
| PCIE_TX_N41 | TX41-DIFF1 | PAIR | 4 | 5.5 | 5 | 10 | 5 | 50 | 6 | 20 | 12 | 12 | 12 | 12 | 7.5 | 85 Ohms | TOP=L2:L3=L2/L4:L6=L5/L7:BOTTOM=L7 |
| PCIE_TX_N41 | TX41-DIFF1 | PAIR | 5 | 5.5 | 5 | 10 | 5 | 50 | 6 | 20 | 12 | 12 | 12 | 12 | 7.5 | 85 Ohms | TOP=L2:L3=L2/L4:L6=L5/L7:BOTTOM=L7 |
| PCIE_TX_N41 | TX41-DIFF1 | PAIR | 6 | 5.5 | 5 | 10 | 5 | 50 | 6 | 20 | 12 | 12 | 12 | 12 | 7.5 | 85 Ohms | TOP=L2:L3=L2/L4:L6=L5/L7:BOTTOM=L7 |
| PCIE_TX_N41 | TX41-DIFF1 | PAIR | 7 | 5.5 | 5 | 10 | 5 | 50 | 6 | 20 | 12 | 12 | 12 | 12 | 7.5 | 85 Ohms | TOP=L2:L3=L2/L4:L6=L5/L7:BOTTOM=L7 |
| PCIE_TX_N41 | TX41-DIFF1 | PAIR | 8 | 5.38 | 5 | 10 | 5 | 50 | 6 | 33 | 12 | 12 | 12 | 12 | 6.62 | 85 Ohms | TOP=L2:L3=L2/L4:L6=L5/L7:BOTTOM=L7 |
| PCIE_TX_P41 | TX41-DIFF1 | PAIR | 1 | 5.38 | 5 | 10 | 5 | 50 | 6 | 33 | 12 | 12 | 12 | 12 | 6.62 | 85 Ohms | TOP=L2:L3=L2/L4:L6=L5/L7:BOTTOM=L7 |
| PCIE_TX_P41 | TX41-DIFF1 | PAIR | 2 | 5.5 | 5 | 10 | 5 | 50 | 6 | 20 | 12 | 12 | 12 | 12 | 7.5 | 85 Ohms | TOP=L2:L3=L2/L4:L6=L5/L7:BOTTOM=L7 |
| PCIE_TX_P41 | TX41-DIFF1 | PAIR | 3 | 5.5 | 5 | 10 | 5 | 50 | 6 | 20 | 12 | 12 | 12 | 12 | 7.5 | 85 Ohms | TOP=L2:L3=L2/L4:L6=L5/L7:BOTTOM=L7 |
| PCIE_TX_P41 | TX41-DIFF1 | PAIR | 4 | 5.5 | 5 | 10 | 5 | 50 | 6 | 20 | 12 | 12 | 12 | 12 | 7.5 | 85 Ohms | TOP=L2:L3=L2/L4:L6=L5/L7:BOTTOM=L7 |
| PCIE_TX_P41 | TX41-DIFF1 | PAIR | 5 | 5.5 | 5 | 10 | 5 | 50 | 6 | 20 | 12 | 12 | 12 | 12 | 7.5 | 85 Ohms | TOP=L2:L3=L2/L4:L6=L5/L7:BOTTOM=L7 |
| PCIE_TX_P41 | TX41-DIFF1 | PAIR | 6 | 5.5 | 5 | 10 | 5 | 50 | 6 | 20 | 12 | 12 | 12 | 12 | 7.5 | 85 Ohms | TOP=L2:L3=L2/L4:L6=L5/L7:BOTTOM=L7 |
| PCIE_TX_P41 | TX41-DIFF1 | PAIR | 7 | 5.5 | 5 | 10 | 5 | 50 | 6 | 20 | 12 | 12 | 12 | 12 | 7.5 | 85 Ohms | TOP=L2:L3=L2/L4:L6=L5/L7:BOTTOM=L7 |
| PCIE_TX_P41 | TX41-DIFF1 | PAIR | 8 | 5.38 | 5 | 10 | 5 | 50 | 6 | 33 | 12 | 12 | 12 | 12 | 6.62 | 85 Ohms | TOP=L2:L3=L2/L4:L6=L5/L7:BOTTOM=L7 |
| PCIE_TX_N42 | TX42-DIFF1 | PAIR | 1 | 5.38 | 5 | 10 | 5 | 50 | 6 | 33 | 12 | 12 | 12 | 12 | 6.62 | 85 Ohms | TOP=L2:L3=L2/L4:L6=L5/L7:BOTTOM=L7 |
| PCIE_TX_N42 | TX42-DIFF1 | PAIR | 2 | 5.5 | 5 | 10 | 5 | 50 | 6 | 20 | 12 | 12 | 12 | 12 | 7.5 | 85 Ohms | TOP=L2:L3=L2/L4:L6=L5/L7:BOTTOM=L7 |
| PCIE_TX_N42 | TX42-DIFF1 | PAIR | 3 | 5.5 | 5 | 10 | 5 | 50 | 6 | 20 | 12 | 12 | 12 | 12 | 7.5 | 85 Ohms | TOP=L2:L3=L2/L4:L6=L5/L7:BOTTOM=L7 |
| PCIE_TX_N42 | TX42-DIFF1 | PAIR | 4 | 5.5 | 5 | 10 | 5 | 50 | 6 | 20 | 12 | 12 | 12 | 12 | 7.5 | 85 Ohms | TOP=L2:L3=L2/L4:L6=L5/L7:BOTTOM=L7 |
| PCIE_TX_N42 | TX42-DIFF1 | PAIR | 5 | 5.5 | 5 | 10 | 5 | 50 | 6 | 20 | 12 | 12 | 12 | 12 | 7.5 | 85 Ohms | TOP=L2:L3=L2/L4:L6=L5/L7:BOTTOM=L7 |
| PCIE_TX_N42 | TX42-DIFF1 | PAIR | 6 | 5.5 | 5 | 10 | 5 | 50 | 6 | 20 | 12 | 12 | 12 | 12 | 7.5 | 85 Ohms | TOP=L2:L3=L2/L4:L6=L5/L7:BOTTOM=L7 |
| PCIE_TX_N42 | TX42-DIFF1 | PAIR | 7 | 5.5 | 5 | 10 | 5 | 50 | 6 | 20 | 12 | 12 | 12 | 12 | 7.5 | 85 Ohms | TOP=L2:L3=L2/L4:L6=L5/L7:BOTTOM=L7 |
| PCIE_TX_N42 | TX42-DIFF1 | PAIR | 8 | 5.38 | 5 | 10 | 5 | 50 | 6 | 33 | 12 | 12 | 12 | 12 | 6.62 | 85 Ohms | TOP=L2:L3=L2/L4:L6=L5/L7:BOTTOM=L7 |
| PCIE_TX_P42 | TX42-DIFF1 | PAIR | 1 | 5.38 | 5 | 10 | 5 | 50 | 6 | 33 | 12 | 12 | 12 | 12 | 6.62 | 85 Ohms | TOP=L2:L3=L2/L4:L6=L5/L7:BOTTOM=L7 |
| PCIE_TX_P42 | TX42-DIFF1 | PAIR | 2 | 5.5 | 5 | 10 | 5 | 50 | 6 | 20 | 12 | 12 | 12 | 12 | 7.5 | 85 Ohms | TOP=L2:L3=L2/L4:L6=L5/L7:BOTTOM=L7 |
| PCIE_TX_P42 | TX42-DIFF1 | PAIR | 3 | 5.5 | 5 | 10 | 5 | 50 | 6 | 20 | 12 | 12 | 12 | 12 | 7.5 | 85 Ohms | TOP=L2:L3=L2/L4:L6=L5/L7:BOTTOM=L7 |
| PCIE_TX_P42 | TX42-DIFF1 | PAIR | 4 | 5.5 | 5 | 10 | 5 | 50 | 6 | 20 | 12 | 12 | 12 | 12 | 7.5 | 85 Ohms | TOP=L2:L3=L2/L4:L6=L5/L7:BOTTOM=L7 |
| PCIE_TX_P42 | TX42-DIFF1 | PAIR | 5 | 5.5 | 5 | 10 | 5 | 50 | 6 | 20 | 12 | 12 | 12 | 12 | 7.5 | 85 Ohms | TOP=L2:L3=L2/L4:L6=L5/L7:BOTTOM=L7 |
| PCIE_TX_P42 | TX42-DIFF1 | PAIR | 6 | 5.5 | 5 | 10 | 5 | 50 | 6 | 20 | 12 | 12 | 12 | 12 | 7.5 | 85 Ohms | TOP=L2:L3=L2/L4:L6=L5/L7:BOTTOM=L7 |
| PCIE_TX_P42 | TX42-DIFF1 | PAIR | 7 | 5.5 | 5 | 10 | 5 | 50 | 6 | 20 | 12 | 12 | 12 | 12 | 7.5 | 85 Ohms | TOP=L2:L3=L2/L4:L6=L5/L7:BOTTOM=L7 |
| PCIE_TX_P42 | TX42-DIFF1 | PAIR | 8 | 5.38 | 5 | 10 | 5 | 50 | 6 | 33 | 12 | 12 | 12 | 12 | 6.62 | 85 Ohms | TOP=L2:L3=L2/L4:L6=L5/L7:BOTTOM=L7 |
| PCIE_TX_N43 | TX43-DIFF1 | PAIR | 1 | 5.38 | 5 | 10 | 5 | 50 | 6 | 33 | 12 | 12 | 12 | 12 | 6.62 | 85 Ohms | TOP=L2:L3=L2/L4:L6=L5/L7:BOTTOM=L7 |
| PCIE_TX_N43 | TX43-DIFF1 | PAIR | 2 | 5.5 | 5 | 10 | 5 | 50 | 6 | 20 | 12 | 12 | 12 | 12 | 7.5 | 85 Ohms | TOP=L2:L3=L2/L4:L6=L5/L7:BOTTOM=L7 |
| PCIE_TX_N43 | TX43-DIFF1 | PAIR | 3 | 5.5 | 5 | 10 | 5 | 50 | 6 | 20 | 12 | 12 | 12 | 12 | 7.5 | 85 Ohms | TOP=L2:L3=L2/L4:L6=L5/L7:BOTTOM=L7 |
| PCIE_TX_N43 | TX43-DIFF1 | PAIR | 4 | 5.5 | 5 | 10 | 5 | 50 | 6 | 20 | 12 | 12 | 12 | 12 | 7.5 | 85 Ohms | TOP=L2:L3=L2/L4:L6=L5/L7:BOTTOM=L7 |
| PCIE_TX_N43 | TX43-DIFF1 | PAIR | 5 | 5.5 | 5 | 10 | 5 | 50 | 6 | 20 | 12 | 12 | 12 | 12 | 7.5 | 85 Ohms | TOP=L2:L3=L2/L4:L6=L5/L7:BOTTOM=L7 |
| PCIE_TX_N43 | TX43-DIFF1 | PAIR | 6 | 5.5 | 5 | 10 | 5 | 50 | 6 | 20 | 12 | 12 | 12 | 12 | 7.5 | 85 Ohms | TOP=L2:L3=L2/L4:L6=L5/L7:BOTTOM=L7 |
| PCIE_TX_N43 | TX43-DIFF1 | PAIR | 7 | 5.5 | 5 | 10 | 5 | 50 | 6 | 20 | 12 | 12 | 12 | 12 | 7.5 | 85 Ohms | TOP=L2:L3=L2/L4:L6=L5/L7:BOTTOM=L7 |
| PCIE_TX_N43 | TX43-DIFF1 | PAIR | 8 | 5.38 | 5 | 10 | 5 | 50 | 6 | 33 | 12 | 12 | 12 | 12 | 6.62 | 85 Ohms | TOP=L2:L3=L2/L4:L6=L5/L7:BOTTOM=L7 |
| PCIE_TX_P43 | TX43-DIFF1 | PAIR | 1 | 5.38 | 5 | 10 | 5 | 50 | 6 | 33 | 12 | 12 | 12 | 12 | 6.62 | 85 Ohms | TOP=L2:L3=L2/L4:L6=L5/L7:BOTTOM=L7 |
| PCIE_TX_P43 | TX43-DIFF1 | PAIR | 2 | 5.5 | 5 | 10 | 5 | 50 | 6 | 20 | 12 | 12 | 12 | 12 | 7.5 | 85 Ohms | TOP=L2:L3=L2/L4:L6=L5/L7:BOTTOM=L7 |
| PCIE_TX_P43 | TX43-DIFF1 | PAIR | 3 | 5.5 | 5 | 10 | 5 | 50 | 6 | 20 | 12 | 12 | 12 | 12 | 7.5 | 85 Ohms | TOP=L2:L3=L2/L4:L6=L5/L7:BOTTOM=L7 |
| PCIE_TX_P43 | TX43-DIFF1 | PAIR | 4 | 5.5 | 5 | 10 | 5 | 50 | 6 | 20 | 12 | 12 | 12 | 12 | 7.5 | 85 Ohms | TOP=L2:L3=L2/L4:L6=L5/L7:BOTTOM=L7 |
| PCIE_TX_P43 | TX43-DIFF1 | PAIR | 5 | 5.5 | 5 | 10 | 5 | 50 | 6 | 20 | 12 | 12 | 12 | 12 | 7.5 | 85 Ohms | TOP=L2:L3=L2/L4:L6=L5/L7:BOTTOM=L7 |
| PCIE_TX_P43 | TX43-DIFF1 | PAIR | 6 | 5.5 | 5 | 10 | 5 | 50 | 6 | 20 | 12 | 12 | 12 | 12 | 7.5 | 85 Ohms | TOP=L2:L3=L2/L4:L6=L5/L7:BOTTOM=L7 |
| PCIE_TX_P43 | TX43-DIFF1 | PAIR | 7 | 5.5 | 5 | 10 | 5 | 50 | 6 | 20 | 12 | 12 | 12 | 12 | 7.5 | 85 Ohms | TOP=L2:L3=L2/L4:L6=L5/L7:BOTTOM=L7 |
| PCIE_TX_P43 | TX43-DIFF1 | PAIR | 8 | 5.38 | 5 | 10 | 5 | 50 | 6 | 33 | 12 | 12 | 12 | 12 | 6.62 | 85 Ohms | TOP=L2:L3=L2/L4:L6=L5/L7:BOTTOM=L7 |
| PCIE_TX_N44 | TX44-DIFF1 | PAIR | 1 | 5.38 | 5 | 10 | 5 | 50 | 6 | 33 | 12 | 12 | 12 | 12 | 6.62 | 85 Ohms | TOP=L2:L3=L2/L4:L6=L5/L7:BOTTOM=L7 |
| PCIE_TX_N44 | TX44-DIFF1 | PAIR | 2 | 5.5 | 5 | 10 | 5 | 50 | 6 | 20 | 12 | 12 | 12 | 12 | 7.5 | 85 Ohms | TOP=L2:L3=L2/L4:L6=L5/L7:BOTTOM=L7 |
| PCIE_TX_N44 | TX44-DIFF1 | PAIR | 3 | 5.5 | 5 | 10 | 5 | 50 | 6 | 20 | 12 | 12 | 12 | 12 | 7.5 | 85 Ohms | TOP=L2:L3=L2/L4:L6=L5/L7:BOTTOM=L7 |
| PCIE_TX_N44 | TX44-DIFF1 | PAIR | 4 | 5.5 | 5 | 10 | 5 | 50 | 6 | 20 | 12 | 12 | 12 | 12 | 7.5 | 85 Ohms | TOP=L2:L3=L2/L4:L6=L5/L7:BOTTOM=L7 |
| PCIE_TX_N44 | TX44-DIFF1 | PAIR | 5 | 5.5 | 5 | 10 | 5 | 50 | 6 | 20 | 12 | 12 | 12 | 12 | 7.5 | 85 Ohms | TOP=L2:L3=L2/L4:L6=L5/L7:BOTTOM=L7 |
| PCIE_TX_N44 | TX44-DIFF1 | PAIR | 6 | 5.5 | 5 | 10 | 5 | 50 | 6 | 20 | 12 | 12 | 12 | 12 | 7.5 | 85 Ohms | TOP=L2:L3=L2/L4:L6=L5/L7:BOTTOM=L7 |
| PCIE_TX_N44 | TX44-DIFF1 | PAIR | 7 | 5.5 | 5 | 10 | 5 | 50 | 6 | 20 | 12 | 12 | 12 | 12 | 7.5 | 85 Ohms | TOP=L2:L3=L2/L4:L6=L5/L7:BOTTOM=L7 |
| PCIE_TX_N44 | TX44-DIFF1 | PAIR | 8 | 5.38 | 5 | 10 | 5 | 50 | 6 | 33 | 12 | 12 | 12 | 12 | 6.62 | 85 Ohms | TOP=L2:L3=L2/L4:L6=L5/L7:BOTTOM=L7 |
| PCIE_TX_P44 | TX44-DIFF1 | PAIR | 1 | 5.38 | 5 | 10 | 5 | 50 | 6 | 33 | 12 | 12 | 12 | 12 | 6.62 | 85 Ohms | TOP=L2:L3=L2/L4:L6=L5/L7:BOTTOM=L7 |
| PCIE_TX_P44 | TX44-DIFF1 | PAIR | 2 | 5.5 | 5 | 10 | 5 | 50 | 6 | 20 | 12 | 12 | 12 | 12 | 7.5 | 85 Ohms | TOP=L2:L3=L2/L4:L6=L5/L7:BOTTOM=L7 |
| PCIE_TX_P44 | TX44-DIFF1 | PAIR | 3 | 5.5 | 5 | 10 | 5 | 50 | 6 | 20 | 12 | 12 | 12 | 12 | 7.5 | 85 Ohms | TOP=L2:L3=L2/L4:L6=L5/L7:BOTTOM=L7 |
| PCIE_TX_P44 | TX44-DIFF1 | PAIR | 4 | 5.5 | 5 | 10 | 5 | 50 | 6 | 20 | 12 | 12 | 12 | 12 | 7.5 | 85 Ohms | TOP=L2:L3=L2/L4:L6=L5/L7:BOTTOM=L7 |
| PCIE_TX_P44 | TX44-DIFF1 | PAIR | 5 | 5.5 | 5 | 10 | 5 | 50 | 6 | 20 | 12 | 12 | 12 | 12 | 7.5 | 85 Ohms | TOP=L2:L3=L2/L4:L6=L5/L7:BOTTOM=L7 |
| PCIE_TX_P44 | TX44-DIFF1 | PAIR | 6 | 5.5 | 5 | 10 | 5 | 50 | 6 | 20 | 12 | 12 | 12 | 12 | 7.5 | 85 Ohms | TOP=L2:L3=L2/L4:L6=L5/L7:BOTTOM=L7 |
| PCIE_TX_P44 | TX44-DIFF1 | PAIR | 7 | 5.5 | 5 | 10 | 5 | 50 | 6 | 20 | 12 | 12 | 12 | 12 | 7.5 | 85 Ohms | TOP=L2:L3=L2/L4:L6=L5/L7:BOTTOM=L7 |
| PCIE_TX_P44 | TX44-DIFF1 | PAIR | 8 | 5.38 | 5 | 10 | 5 | 50 | 6 | 33 | 12 | 12 | 12 | 12 | 6.62 | 85 Ohms | TOP=L2:L3=L2/L4:L6=L5/L7:BOTTOM=L7 |
| PCIE_TX_N45 | TX45-DIFF1 | PAIR | 1 | 5.38 | 5 | 10 | 5 | 50 | 6 | 33 | 12 | 12 | 12 | 12 | 6.62 | 85 Ohms | TOP=L2:L3=L2/L4:L6=L5/L7:BOTTOM=L7 |
| PCIE_TX_N45 | TX45-DIFF1 | PAIR | 2 | 5.5 | 5 | 10 | 5 | 50 | 6 | 20 | 12 | 12 | 12 | 12 | 7.5 | 85 Ohms | TOP=L2:L3=L2/L4:L6=L5/L7:BOTTOM=L7 |
| PCIE_TX_N45 | TX45-DIFF1 | PAIR | 3 | 5.5 | 5 | 10 | 5 | 50 | 6 | 20 | 12 | 12 | 12 | 12 | 7.5 | 85 Ohms | TOP=L2:L3=L2/L4:L6=L5/L7:BOTTOM=L7 |
| PCIE_TX_N45 | TX45-DIFF1 | PAIR | 4 | 5.5 | 5 | 10 | 5 | 50 | 6 | 20 | 12 | 12 | 12 | 12 | 7.5 | 85 Ohms | TOP=L2:L3=L2/L4:L6=L5/L7:BOTTOM=L7 |
| PCIE_TX_N45 | TX45-DIFF1 | PAIR | 5 | 5.5 | 5 | 10 | 5 | 50 | 6 | 20 | 12 | 12 | 12 | 12 | 7.5 | 85 Ohms | TOP=L2:L3=L2/L4:L6=L5/L7:BOTTOM=L7 |
| PCIE_TX_N45 | TX45-DIFF1 | PAIR | 6 | 5.5 | 5 | 10 | 5 | 50 | 6 | 20 | 12 | 12 | 12 | 12 | 7.5 | 85 Ohms | TOP=L2:L3=L2/L4:L6=L5/L7:BOTTOM=L7 |
| PCIE_TX_N45 | TX45-DIFF1 | PAIR | 7 | 5.5 | 5 | 10 | 5 | 50 | 6 | 20 | 12 | 12 | 12 | 12 | 7.5 | 85 Ohms | TOP=L2:L3=L2/L4:L6=L5/L7:BOTTOM=L7 |
| PCIE_TX_N45 | TX45-DIFF1 | PAIR | 8 | 5.38 | 5 | 10 | 5 | 50 | 6 | 33 | 12 | 12 | 12 | 12 | 6.62 | 85 Ohms | TOP=L2:L3=L2/L4:L6=L5/L7:BOTTOM=L7 |
| PCIE_TX_P45 | TX45-DIFF1 | PAIR | 1 | 5.38 | 5 | 10 | 5 | 50 | 6 | 33 | 12 | 12 | 12 | 12 | 6.62 | 85 Ohms | TOP=L2:L3=L2/L4:L6=L5/L7:BOTTOM=L7 |
| PCIE_TX_P45 | TX45-DIFF1 | PAIR | 2 | 5.5 | 5 | 10 | 5 | 50 | 6 | 20 | 12 | 12 | 12 | 12 | 7.5 | 85 Ohms | TOP=L2:L3=L2/L4:L6=L5/L7:BOTTOM=L7 |
| PCIE_TX_P45 | TX45-DIFF1 | PAIR | 3 | 5.5 | 5 | 10 | 5 | 50 | 6 | 20 | 12 | 12 | 12 | 12 | 7.5 | 85 Ohms | TOP=L2:L3=L2/L4:L6=L5/L7:BOTTOM=L7 |
| PCIE_TX_P45 | TX45-DIFF1 | PAIR | 4 | 5.5 | 5 | 10 | 5 | 50 | 6 | 20 | 12 | 12 | 12 | 12 | 7.5 | 85 Ohms | TOP=L2:L3=L2/L4:L6=L5/L7:BOTTOM=L7 |
| PCIE_TX_P45 | TX45-DIFF1 | PAIR | 5 | 5.5 | 5 | 10 | 5 | 50 | 6 | 20 | 12 | 12 | 12 | 12 | 7.5 | 85 Ohms | TOP=L2:L3=L2/L4:L6=L5/L7:BOTTOM=L7 |
| PCIE_TX_P45 | TX45-DIFF1 | PAIR | 6 | 5.5 | 5 | 10 | 5 | 50 | 6 | 20 | 12 | 12 | 12 | 12 | 7.5 | 85 Ohms | TOP=L2:L3=L2/L4:L6=L5/L7:BOTTOM=L7 |
| PCIE_TX_P45 | TX45-DIFF1 | PAIR | 7 | 5.5 | 5 | 10 | 5 | 50 | 6 | 20 | 12 | 12 | 12 | 12 | 7.5 | 85 Ohms | TOP=L2:L3=L2/L4:L6=L5/L7:BOTTOM=L7 |
| PCIE_TX_P45 | TX45-DIFF1 | PAIR | 8 | 5.38 | 5 | 10 | 5 | 50 | 6 | 33 | 12 | 12 | 12 | 12 | 6.62 | 85 Ohms | TOP=L2:L3=L2/L4:L6=L5/L7:BOTTOM=L7 |
| PCIE_TX_N46 | TX46-DIFF1 | PAIR | 1 | 5.38 | 5 | 10 | 5 | 50 | 6 | 33 | 12 | 12 | 12 | 12 | 6.62 | 85 Ohms | TOP=L2:L3=L2/L4:L6=L5/L7:BOTTOM=L7 |
| PCIE_TX_N46 | TX46-DIFF1 | PAIR | 2 | 5.5 | 5 | 10 | 5 | 50 | 6 | 20 | 12 | 12 | 12 | 12 | 7.5 | 85 Ohms | TOP=L2:L3=L2/L4:L6=L5/L7:BOTTOM=L7 |
| PCIE_TX_N46 | TX46-DIFF1 | PAIR | 3 | 5.5 | 5 | 10 | 5 | 50 | 6 | 20 | 12 | 12 | 12 | 12 | 7.5 | 85 Ohms | TOP=L2:L3=L2/L4:L6=L5/L7:BOTTOM=L7 |
| PCIE_TX_N46 | TX46-DIFF1 | PAIR | 4 | 5.5 | 5 | 10 | 5 | 50 | 6 | 20 | 12 | 12 | 12 | 12 | 7.5 | 85 Ohms | TOP=L2:L3=L2/L4:L6=L5/L7:BOTTOM=L7 |
| PCIE_TX_N46 | TX46-DIFF1 | PAIR | 5 | 5.5 | 5 | 10 | 5 | 50 | 6 | 20 | 12 | 12 | 12 | 12 | 7.5 | 85 Ohms | TOP=L2:L3=L2/L4:L6=L5/L7:BOTTOM=L7 |
| PCIE_TX_N46 | TX46-DIFF1 | PAIR | 6 | 5.5 | 5 | 10 | 5 | 50 | 6 | 20 | 12 | 12 | 12 | 12 | 7.5 | 85 Ohms | TOP=L2:L3=L2/L4:L6=L5/L7:BOTTOM=L7 |
| PCIE_TX_N46 | TX46-DIFF1 | PAIR | 7 | 5.5 | 5 | 10 | 5 | 50 | 6 | 20 | 12 | 12 | 12 | 12 | 7.5 | 85 Ohms | TOP=L2:L3=L2/L4:L6=L5/L7:BOTTOM=L7 |
| PCIE_TX_N46 | TX46-DIFF1 | PAIR | 8 | 5.38 | 5 | 10 | 5 | 50 | 6 | 33 | 12 | 12 | 12 | 12 | 6.62 | 85 Ohms | TOP=L2:L3=L2/L4:L6=L5/L7:BOTTOM=L7 |
| PCIE_TX_P46 | TX46-DIFF1 | PAIR | 1 | 5.38 | 5 | 10 | 5 | 50 | 6 | 33 | 12 | 12 | 12 | 12 | 6.62 | 85 Ohms | TOP=L2:L3=L2/L4:L6=L5/L7:BOTTOM=L7 |
| PCIE_TX_P46 | TX46-DIFF1 | PAIR | 2 | 5.5 | 5 | 10 | 5 | 50 | 6 | 20 | 12 | 12 | 12 | 12 | 7.5 | 85 Ohms | TOP=L2:L3=L2/L4:L6=L5/L7:BOTTOM=L7 |
| PCIE_TX_P46 | TX46-DIFF1 | PAIR | 3 | 5.5 | 5 | 10 | 5 | 50 | 6 | 20 | 12 | 12 | 12 | 12 | 7.5 | 85 Ohms | TOP=L2:L3=L2/L4:L6=L5/L7:BOTTOM=L7 |
| PCIE_TX_P46 | TX46-DIFF1 | PAIR | 4 | 5.5 | 5 | 10 | 5 | 50 | 6 | 20 | 12 | 12 | 12 | 12 | 7.5 | 85 Ohms | TOP=L2:L3=L2/L4:L6=L5/L7:BOTTOM=L7 |
| PCIE_TX_P46 | TX46-DIFF1 | PAIR | 5 | 5.5 | 5 | 10 | 5 | 50 | 6 | 20 | 12 | 12 | 12 | 12 | 7.5 | 85 Ohms | TOP=L2:L3=L2/L4:L6=L5/L7:BOTTOM=L7 |
| PCIE_TX_P46 | TX46-DIFF1 | PAIR | 6 | 5.5 | 5 | 10 | 5 | 50 | 6 | 20 | 12 | 12 | 12 | 12 | 7.5 | 85 Ohms | TOP=L2:L3=L2/L4:L6=L5/L7:BOTTOM=L7 |
| PCIE_TX_P46 | TX46-DIFF1 | PAIR | 7 | 5.5 | 5 | 10 | 5 | 50 | 6 | 20 | 12 | 12 | 12 | 12 | 7.5 | 85 Ohms | TOP=L2:L3=L2/L4:L6=L5/L7:BOTTOM=L7 |
| PCIE_TX_P46 | TX46-DIFF1 | PAIR | 8 | 5.38 | 5 | 10 | 5 | 50 | 6 | 33 | 12 | 12 | 12 | 12 | 6.62 | 85 Ohms | TOP=L2:L3=L2/L4:L6=L5/L7:BOTTOM=L7 |
| PCIE_TX_N47 | TX47-DIFF1 | PAIR | 1 | 5.38 | 5 | 10 | 5 | 50 | 6 | 33 | 12 | 12 | 12 | 12 | 6.62 | 85 Ohms | TOP=L2:L3=L2/L4:L6=L5/L7:BOTTOM=L7 |
| PCIE_TX_N47 | TX47-DIFF1 | PAIR | 2 | 5.5 | 5 | 10 | 5 | 50 | 6 | 20 | 12 | 12 | 12 | 12 | 7.5 | 85 Ohms | TOP=L2:L3=L2/L4:L6=L5/L7:BOTTOM=L7 |
| PCIE_TX_N47 | TX47-DIFF1 | PAIR | 3 | 5.5 | 5 | 10 | 5 | 50 | 6 | 20 | 12 | 12 | 12 | 12 | 7.5 | 85 Ohms | TOP=L2:L3=L2/L4:L6=L5/L7:BOTTOM=L7 |
| PCIE_TX_N47 | TX47-DIFF1 | PAIR | 4 | 5.5 | 5 | 10 | 5 | 50 | 6 | 20 | 12 | 12 | 12 | 12 | 7.5 | 85 Ohms | TOP=L2:L3=L2/L4:L6=L5/L7:BOTTOM=L7 |
| PCIE_TX_N47 | TX47-DIFF1 | PAIR | 5 | 5.5 | 5 | 10 | 5 | 50 | 6 | 20 | 12 | 12 | 12 | 12 | 7.5 | 85 Ohms | TOP=L2:L3=L2/L4:L6=L5/L7:BOTTOM=L7 |
| PCIE_TX_N47 | TX47-DIFF1 | PAIR | 6 | 5.5 | 5 | 10 | 5 | 50 | 6 | 20 | 12 | 12 | 12 | 12 | 7.5 | 85 Ohms | TOP=L2:L3=L2/L4:L6=L5/L7:BOTTOM=L7 |
| PCIE_TX_N47 | TX47-DIFF1 | PAIR | 7 | 5.5 | 5 | 10 | 5 | 50 | 6 | 20 | 12 | 12 | 12 | 12 | 7.5 | 85 Ohms | TOP=L2:L3=L2/L4:L6=L5/L7:BOTTOM=L7 |
| PCIE_TX_N47 | TX47-DIFF1 | PAIR | 8 | 5.38 | 5 | 10 | 5 | 50 | 6 | 33 | 12 | 12 | 12 | 12 | 6.62 | 85 Ohms | TOP=L2:L3=L2/L4:L6=L5/L7:BOTTOM=L7 |
| PCIE_TX_P47 | TX47-DIFF1 | PAIR | 1 | 5.38 | 5 | 10 | 5 | 50 | 6 | 33 | 12 | 12 | 12 | 12 | 6.62 | 85 Ohms | TOP=L2:L3=L2/L4:L6=L5/L7:BOTTOM=L7 |
| PCIE_TX_P47 | TX47-DIFF1 | PAIR | 2 | 5.5 | 5 | 10 | 5 | 50 | 6 | 20 | 12 | 12 | 12 | 12 | 7.5 | 85 Ohms | TOP=L2:L3=L2/L4:L6=L5/L7:BOTTOM=L7 |
| PCIE_TX_P47 | TX47-DIFF1 | PAIR | 3 | 5.5 | 5 | 10 | 5 | 50 | 6 | 20 | 12 | 12 | 12 | 12 | 7.5 | 85 Ohms | TOP=L2:L3=L2/L4:L6=L5/L7:BOTTOM=L7 |
| PCIE_TX_P47 | TX47-DIFF1 | PAIR | 4 | 5.5 | 5 | 10 | 5 | 50 | 6 | 20 | 12 | 12 | 12 | 12 | 7.5 | 85 Ohms | TOP=L2:L3=L2/L4:L6=L5/L7:BOTTOM=L7 |
| PCIE_TX_P47 | TX47-DIFF1 | PAIR | 5 | 5.5 | 5 | 10 | 5 | 50 | 6 | 20 | 12 | 12 | 12 | 12 | 7.5 | 85 Ohms | TOP=L2:L3=L2/L4:L6=L5/L7:BOTTOM=L7 |
| PCIE_TX_P47 | TX47-DIFF1 | PAIR | 6 | 5.5 | 5 | 10 | 5 | 50 | 6 | 20 | 12 | 12 | 12 | 12 | 7.5 | 85 Ohms | TOP=L2:L3=L2/L4:L6=L5/L7:BOTTOM=L7 |
| PCIE_TX_P47 | TX47-DIFF1 | PAIR | 7 | 5.5 | 5 | 10 | 5 | 50 | 6 | 20 | 12 | 12 | 12 | 12 | 7.5 | 85 Ohms | TOP=L2:L3=L2/L4:L6=L5/L7:BOTTOM=L7 |
| PCIE_TX_P47 | TX47-DIFF1 | PAIR | 8 | 5.38 | 5 | 10 | 5 | 50 | 6 | 33 | 12 | 12 | 12 | 12 | 6.62 | 85 Ohms | TOP=L2:L3=L2/L4:L6=L5/L7:BOTTOM=L7 |
| PCIE_TX_N48 | TX48-DIFF1 | PAIR | 1 | 5.38 | 5 | 10 | 5 | 50 | 6 | 33 | 12 | 12 | 12 | 12 | 6.62 | 85 Ohms | TOP=L2:L3=L2/L4:L6=L5/L7:BOTTOM=L7 |
| PCIE_TX_N48 | TX48-DIFF1 | PAIR | 2 | 5.5 | 5 | 10 | 5 | 50 | 6 | 20 | 12 | 12 | 12 | 12 | 7.5 | 85 Ohms | TOP=L2:L3=L2/L4:L6=L5/L7:BOTTOM=L7 |
| PCIE_TX_N48 | TX48-DIFF1 | PAIR | 3 | 5.5 | 5 | 10 | 5 | 50 | 6 | 20 | 12 | 12 | 12 | 12 | 7.5 | 85 Ohms | TOP=L2:L3=L2/L4:L6=L5/L7:BOTTOM=L7 |
| PCIE_TX_N48 | TX48-DIFF1 | PAIR | 4 | 5.5 | 5 | 10 | 5 | 50 | 6 | 20 | 12 | 12 | 12 | 12 | 7.5 | 85 Ohms | TOP=L2:L3=L2/L4:L6=L5/L7:BOTTOM=L7 |
| PCIE_TX_N48 | TX48-DIFF1 | PAIR | 5 | 5.5 | 5 | 10 | 5 | 50 | 6 | 20 | 12 | 12 | 12 | 12 | 7.5 | 85 Ohms | TOP=L2:L3=L2/L4:L6=L5/L7:BOTTOM=L7 |
| PCIE_TX_N48 | TX48-DIFF1 | PAIR | 6 | 5.5 | 5 | 10 | 5 | 50 | 6 | 20 | 12 | 12 | 12 | 12 | 7.5 | 85 Ohms | TOP=L2:L3=L2/L4:L6=L5/L7:BOTTOM=L7 |
| PCIE_TX_N48 | TX48-DIFF1 | PAIR | 7 | 5.5 | 5 | 10 | 5 | 50 | 6 | 20 | 12 | 12 | 12 | 12 | 7.5 | 85 Ohms | TOP=L2:L3=L2/L4:L6=L5/L7:BOTTOM=L7 |
| PCIE_TX_N48 | TX48-DIFF1 | PAIR | 8 | 5.38 | 5 | 10 | 5 | 50 | 6 | 33 | 12 | 12 | 12 | 12 | 6.62 | 85 Ohms | TOP=L2:L3=L2/L4:L6=L5/L7:BOTTOM=L7 |
| PCIE_TX_P48 | TX48-DIFF1 | PAIR | 1 | 5.38 | 5 | 10 | 5 | 50 | 6 | 33 | 12 | 12 | 12 | 12 | 6.62 | 85 Ohms | TOP=L2:L3=L2/L4:L6=L5/L7:BOTTOM=L7 |
| PCIE_TX_P48 | TX48-DIFF1 | PAIR | 2 | 5.5 | 5 | 10 | 5 | 50 | 6 | 20 | 12 | 12 | 12 | 12 | 7.5 | 85 Ohms | TOP=L2:L3=L2/L4:L6=L5/L7:BOTTOM=L7 |
| PCIE_TX_P48 | TX48-DIFF1 | PAIR | 3 | 5.5 | 5 | 10 | 5 | 50 | 6 | 20 | 12 | 12 | 12 | 12 | 7.5 | 85 Ohms | TOP=L2:L3=L2/L4:L6=L5/L7:BOTTOM=L7 |
| PCIE_TX_P48 | TX48-DIFF1 | PAIR | 4 | 5.5 | 5 | 10 | 5 | 50 | 6 | 20 | 12 | 12 | 12 | 12 | 7.5 | 85 Ohms | TOP=L2:L3=L2/L4:L6=L5/L7:BOTTOM=L7 |
| PCIE_TX_P48 | TX48-DIFF1 | PAIR | 5 | 5.5 | 5 | 10 | 5 | 50 | 6 | 20 | 12 | 12 | 12 | 12 | 7.5 | 85 Ohms | TOP=L2:L3=L2/L4:L6=L5/L7:BOTTOM=L7 |
| PCIE_TX_P48 | TX48-DIFF1 | PAIR | 6 | 5.5 | 5 | 10 | 5 | 50 | 6 | 20 | 12 | 12 | 12 | 12 | 7.5 | 85 Ohms | TOP=L2:L3=L2/L4:L6=L5/L7:BOTTOM=L7 |
| PCIE_TX_P48 | TX48-DIFF1 | PAIR | 7 | 5.5 | 5 | 10 | 5 | 50 | 6 | 20 | 12 | 12 | 12 | 12 | 7.5 | 85 Ohms | TOP=L2:L3=L2/L4:L6=L5/L7:BOTTOM=L7 |
| PCIE_TX_P48 | TX48-DIFF1 | PAIR | 8 | 5.38 | 5 | 10 | 5 | 50 | 6 | 33 | 12 | 12 | 12 | 12 | 6.62 | 85 Ohms | TOP=L2:L3=L2/L4:L6=L5/L7:BOTTOM=L7 |
| PCIE_TX_N49 | TX49-DIFF1 | PAIR | 1 | 5.38 | 5 | 10 | 5 | 50 | 6 | 33 | 12 | 12 | 12 | 12 | 6.62 | 85 Ohms | TOP=L2:L3=L2/L4:L6=L5/L7:BOTTOM=L7 |
| PCIE_TX_N49 | TX49-DIFF1 | PAIR | 2 | 5.5 | 5 | 10 | 5 | 50 | 6 | 20 | 12 | 12 | 12 | 12 | 7.5 | 85 Ohms | TOP=L2:L3=L2/L4:L6=L5/L7:BOTTOM=L7 |
| PCIE_TX_N49 | TX49-DIFF1 | PAIR | 3 | 5.5 | 5 | 10 | 5 | 50 | 6 | 20 | 12 | 12 | 12 | 12 | 7.5 | 85 Ohms | TOP=L2:L3=L2/L4:L6=L5/L7:BOTTOM=L7 |
| PCIE_TX_N49 | TX49-DIFF1 | PAIR | 4 | 5.5 | 5 | 10 | 5 | 50 | 6 | 20 | 12 | 12 | 12 | 12 | 7.5 | 85 Ohms | TOP=L2:L3=L2/L4:L6=L5/L7:BOTTOM=L7 |
| PCIE_TX_N49 | TX49-DIFF1 | PAIR | 5 | 5.5 | 5 | 10 | 5 | 50 | 6 | 20 | 12 | 12 | 12 | 12 | 7.5 | 85 Ohms | TOP=L2:L3=L2/L4:L6=L5/L7:BOTTOM=L7 |
| PCIE_TX_N49 | TX49-DIFF1 | PAIR | 6 | 5.5 | 5 | 10 | 5 | 50 | 6 | 20 | 12 | 12 | 12 | 12 | 7.5 | 85 Ohms | TOP=L2:L3=L2/L4:L6=L5/L7:BOTTOM=L7 |
| PCIE_TX_N49 | TX49-DIFF1 | PAIR | 7 | 5.5 | 5 | 10 | 5 | 50 | 6 | 20 | 12 | 12 | 12 | 12 | 7.5 | 85 Ohms | TOP=L2:L3=L2/L4:L6=L5/L7:BOTTOM=L7 |
| PCIE_TX_N49 | TX49-DIFF1 | PAIR | 8 | 5.38 | 5 | 10 | 5 | 50 | 6 | 33 | 12 | 12 | 12 | 12 | 6.62 | 85 Ohms | TOP=L2:L3=L2/L4:L6=L5/L7:BOTTOM=L7 |
| PCIE_TX_P49 | TX49-DIFF1 | PAIR | 1 | 5.38 | 5 | 10 | 5 | 50 | 6 | 33 | 12 | 12 | 12 | 12 | 6.62 | 85 Ohms | TOP=L2:L3=L2/L4:L6=L5/L7:BOTTOM=L7 |
| PCIE_TX_P49 | TX49-DIFF1 | PAIR | 2 | 5.5 | 5 | 10 | 5 | 50 | 6 | 20 | 12 | 12 | 12 | 12 | 7.5 | 85 Ohms | TOP=L2:L3=L2/L4:L6=L5/L7:BOTTOM=L7 |
| PCIE_TX_P49 | TX49-DIFF1 | PAIR | 3 | 5.5 | 5 | 10 | 5 | 50 | 6 | 20 | 12 | 12 | 12 | 12 | 7.5 | 85 Ohms | TOP=L2:L3=L2/L4:L6=L5/L7:BOTTOM=L7 |
| PCIE_TX_P49 | TX49-DIFF1 | PAIR | 4 | 5.5 | 5 | 10 | 5 | 50 | 6 | 20 | 12 | 12 | 12 | 12 | 7.5 | 85 Ohms | TOP=L2:L3=L2/L4:L6=L5/L7:BOTTOM=L7 |
| PCIE_TX_P49 | TX49-DIFF1 | PAIR | 5 | 5.5 | 5 | 10 | 5 | 50 | 6 | 20 | 12 | 12 | 12 | 12 | 7.5 | 85 Ohms | TOP=L2:L3=L2/L4:L6=L5/L7:BOTTOM=L7 |
| PCIE_TX_P49 | TX49-DIFF1 | PAIR | 6 | 5.5 | 5 | 10 | 5 | 50 | 6 | 20 | 12 | 12 | 12 | 12 | 7.5 | 85 Ohms | TOP=L2:L3=L2/L4:L6=L5/L7:BOTTOM=L7 |
| PCIE_TX_P49 | TX49-DIFF1 | PAIR | 7 | 5.5 | 5 | 10 | 5 | 50 | 6 | 20 | 12 | 12 | 12 | 12 | 7.5 | 85 Ohms | TOP=L2:L3=L2/L4:L6=L5/L7:BOTTOM=L7 |
| PCIE_TX_P49 | TX49-DIFF1 | PAIR | 8 | 5.38 | 5 | 10 | 5 | 50 | 6 | 33 | 12 | 12 | 12 | 12 | 6.62 | 85 Ohms | TOP=L2:L3=L2/L4:L6=L5/L7:BOTTOM=L7 |
| PCIE_TX_N4 | TX4-DIFF1 | PAIR | 1 | 5.38 | 5 | 10 | 5 | 50 | 6 | 33 | 12 | 12 | 12 | 12 | 6.62 | 85 Ohms | TOP=L2:L3=L2/L4:L6=L5/L7:BOTTOM=L7 |
| PCIE_TX_N4 | TX4-DIFF1 | PAIR | 2 | 5.5 | 5 | 10 | 5 | 50 | 6 | 20 | 12 | 12 | 12 | 12 | 7.5 | 85 Ohms | TOP=L2:L3=L2/L4:L6=L5/L7:BOTTOM=L7 |
| PCIE_TX_N4 | TX4-DIFF1 | PAIR | 3 | 5.5 | 5 | 10 | 5 | 50 | 6 | 20 | 12 | 12 | 12 | 12 | 7.5 | 85 Ohms | TOP=L2:L3=L2/L4:L6=L5/L7:BOTTOM=L7 |
| PCIE_TX_N4 | TX4-DIFF1 | PAIR | 4 | 5.5 | 5 | 10 | 5 | 50 | 6 | 20 | 12 | 12 | 12 | 12 | 7.5 | 85 Ohms | TOP=L2:L3=L2/L4:L6=L5/L7:BOTTOM=L7 |
| PCIE_TX_N4 | TX4-DIFF1 | PAIR | 5 | 5.5 | 5 | 10 | 5 | 50 | 6 | 20 | 12 | 12 | 12 | 12 | 7.5 | 85 Ohms | TOP=L2:L3=L2/L4:L6=L5/L7:BOTTOM=L7 |
| PCIE_TX_N4 | TX4-DIFF1 | PAIR | 6 | 5.5 | 5 | 10 | 5 | 50 | 6 | 20 | 12 | 12 | 12 | 12 | 7.5 | 85 Ohms | TOP=L2:L3=L2/L4:L6=L5/L7:BOTTOM=L7 |
| PCIE_TX_N4 | TX4-DIFF1 | PAIR | 7 | 5.5 | 5 | 10 | 5 | 50 | 6 | 20 | 12 | 12 | 12 | 12 | 7.5 | 85 Ohms | TOP=L2:L3=L2/L4:L6=L5/L7:BOTTOM=L7 |
| PCIE_TX_N4 | TX4-DIFF1 | PAIR | 8 | 5.38 | 5 | 10 | 5 | 50 | 6 | 33 | 12 | 12 | 12 | 12 | 6.62 | 85 Ohms | TOP=L2:L3=L2/L4:L6=L5/L7:BOTTOM=L7 |
| PCIE_TX_P4 | TX4-DIFF1 | PAIR | 1 | 5.38 | 5 | 10 | 5 | 50 | 6 | 33 | 12 | 12 | 12 | 12 | 6.62 | 85 Ohms | TOP=L2:L3=L2/L4:L6=L5/L7:BOTTOM=L7 |
| PCIE_TX_P4 | TX4-DIFF1 | PAIR | 2 | 5.5 | 5 | 10 | 5 | 50 | 6 | 20 | 12 | 12 | 12 | 12 | 7.5 | 85 Ohms | TOP=L2:L3=L2/L4:L6=L5/L7:BOTTOM=L7 |
| PCIE_TX_P4 | TX4-DIFF1 | PAIR | 3 | 5.5 | 5 | 10 | 5 | 50 | 6 | 20 | 12 | 12 | 12 | 12 | 7.5 | 85 Ohms | TOP=L2:L3=L2/L4:L6=L5/L7:BOTTOM=L7 |
| PCIE_TX_P4 | TX4-DIFF1 | PAIR | 4 | 5.5 | 5 | 10 | 5 | 50 | 6 | 20 | 12 | 12 | 12 | 12 | 7.5 | 85 Ohms | TOP=L2:L3=L2/L4:L6=L5/L7:BOTTOM=L7 |
| PCIE_TX_P4 | TX4-DIFF1 | PAIR | 5 | 5.5 | 5 | 10 | 5 | 50 | 6 | 20 | 12 | 12 | 12 | 12 | 7.5 | 85 Ohms | TOP=L2:L3=L2/L4:L6=L5/L7:BOTTOM=L7 |
| PCIE_TX_P4 | TX4-DIFF1 | PAIR | 6 | 5.5 | 5 | 10 | 5 | 50 | 6 | 20 | 12 | 12 | 12 | 12 | 7.5 | 85 Ohms | TOP=L2:L3=L2/L4:L6=L5/L7:BOTTOM=L7 |
| PCIE_TX_P4 | TX4-DIFF1 | PAIR | 7 | 5.5 | 5 | 10 | 5 | 50 | 6 | 20 | 12 | 12 | 12 | 12 | 7.5 | 85 Ohms | TOP=L2:L3=L2/L4:L6=L5/L7:BOTTOM=L7 |
| PCIE_TX_P4 | TX4-DIFF1 | PAIR | 8 | 5.38 | 5 | 10 | 5 | 50 | 6 | 33 | 12 | 12 | 12 | 12 | 6.62 | 85 Ohms | TOP=L2:L3=L2/L4:L6=L5/L7:BOTTOM=L7 |
| PCIE_TX_N50 | TX50-DIFF1 | PAIR | 1 | 5.38 | 5 | 10 | 5 | 50 | 6 | 33 | 12 | 12 | 12 | 12 | 6.62 | 85 Ohms | TOP=L2:L3=L2/L4:L6=L5/L7:BOTTOM=L7 |
| PCIE_TX_N50 | TX50-DIFF1 | PAIR | 2 | 5.5 | 5 | 10 | 5 | 50 | 6 | 20 | 12 | 12 | 12 | 12 | 7.5 | 85 Ohms | TOP=L2:L3=L2/L4:L6=L5/L7:BOTTOM=L7 |
| PCIE_TX_N50 | TX50-DIFF1 | PAIR | 3 | 5.5 | 5 | 10 | 5 | 50 | 6 | 20 | 12 | 12 | 12 | 12 | 7.5 | 85 Ohms | TOP=L2:L3=L2/L4:L6=L5/L7:BOTTOM=L7 |
| PCIE_TX_N50 | TX50-DIFF1 | PAIR | 4 | 5.5 | 5 | 10 | 5 | 50 | 6 | 20 | 12 | 12 | 12 | 12 | 7.5 | 85 Ohms | TOP=L2:L3=L2/L4:L6=L5/L7:BOTTOM=L7 |
| PCIE_TX_N50 | TX50-DIFF1 | PAIR | 5 | 5.5 | 5 | 10 | 5 | 50 | 6 | 20 | 12 | 12 | 12 | 12 | 7.5 | 85 Ohms | TOP=L2:L3=L2/L4:L6=L5/L7:BOTTOM=L7 |
| PCIE_TX_N50 | TX50-DIFF1 | PAIR | 6 | 5.5 | 5 | 10 | 5 | 50 | 6 | 20 | 12 | 12 | 12 | 12 | 7.5 | 85 Ohms | TOP=L2:L3=L2/L4:L6=L5/L7:BOTTOM=L7 |
| PCIE_TX_N50 | TX50-DIFF1 | PAIR | 7 | 5.5 | 5 | 10 | 5 | 50 | 6 | 20 | 12 | 12 | 12 | 12 | 7.5 | 85 Ohms | TOP=L2:L3=L2/L4:L6=L5/L7:BOTTOM=L7 |
| PCIE_TX_N50 | TX50-DIFF1 | PAIR | 8 | 5.38 | 5 | 10 | 5 | 50 | 6 | 33 | 12 | 12 | 12 | 12 | 6.62 | 85 Ohms | TOP=L2:L3=L2/L4:L6=L5/L7:BOTTOM=L7 |
| PCIE_TX_P50 | TX50-DIFF1 | PAIR | 1 | 5.38 | 5 | 10 | 5 | 50 | 6 | 33 | 12 | 12 | 12 | 12 | 6.62 | 85 Ohms | TOP=L2:L3=L2/L4:L6=L5/L7:BOTTOM=L7 |
| PCIE_TX_P50 | TX50-DIFF1 | PAIR | 2 | 5.5 | 5 | 10 | 5 | 50 | 6 | 20 | 12 | 12 | 12 | 12 | 7.5 | 85 Ohms | TOP=L2:L3=L2/L4:L6=L5/L7:BOTTOM=L7 |
| PCIE_TX_P50 | TX50-DIFF1 | PAIR | 3 | 5.5 | 5 | 10 | 5 | 50 | 6 | 20 | 12 | 12 | 12 | 12 | 7.5 | 85 Ohms | TOP=L2:L3=L2/L4:L6=L5/L7:BOTTOM=L7 |
| PCIE_TX_P50 | TX50-DIFF1 | PAIR | 4 | 5.5 | 5 | 10 | 5 | 50 | 6 | 20 | 12 | 12 | 12 | 12 | 7.5 | 85 Ohms | TOP=L2:L3=L2/L4:L6=L5/L7:BOTTOM=L7 |
| PCIE_TX_P50 | TX50-DIFF1 | PAIR | 5 | 5.5 | 5 | 10 | 5 | 50 | 6 | 20 | 12 | 12 | 12 | 12 | 7.5 | 85 Ohms | TOP=L2:L3=L2/L4:L6=L5/L7:BOTTOM=L7 |
| PCIE_TX_P50 | TX50-DIFF1 | PAIR | 6 | 5.5 | 5 | 10 | 5 | 50 | 6 | 20 | 12 | 12 | 12 | 12 | 7.5 | 85 Ohms | TOP=L2:L3=L2/L4:L6=L5/L7:BOTTOM=L7 |
| PCIE_TX_P50 | TX50-DIFF1 | PAIR | 7 | 5.5 | 5 | 10 | 5 | 50 | 6 | 20 | 12 | 12 | 12 | 12 | 7.5 | 85 Ohms | TOP=L2:L3=L2/L4:L6=L5/L7:BOTTOM=L7 |
| PCIE_TX_P50 | TX50-DIFF1 | PAIR | 8 | 5.38 | 5 | 10 | 5 | 50 | 6 | 33 | 12 | 12 | 12 | 12 | 6.62 | 85 Ohms | TOP=L2:L3=L2/L4:L6=L5/L7:BOTTOM=L7 |
| PCIE_TX_N51 | TX51-DIFF1 | PAIR | 1 | 5.38 | 5 | 10 | 5 | 50 | 6 | 33 | 12 | 12 | 12 | 12 | 6.62 | 85 Ohms | TOP=L2:L3=L2/L4:L6=L5/L7:BOTTOM=L7 |
| PCIE_TX_N51 | TX51-DIFF1 | PAIR | 2 | 5.5 | 5 | 10 | 5 | 50 | 6 | 20 | 12 | 12 | 12 | 12 | 7.5 | 85 Ohms | TOP=L2:L3=L2/L4:L6=L5/L7:BOTTOM=L7 |
| PCIE_TX_N51 | TX51-DIFF1 | PAIR | 3 | 5.5 | 5 | 10 | 5 | 50 | 6 | 20 | 12 | 12 | 12 | 12 | 7.5 | 85 Ohms | TOP=L2:L3=L2/L4:L6=L5/L7:BOTTOM=L7 |
| PCIE_TX_N51 | TX51-DIFF1 | PAIR | 4 | 5.5 | 5 | 10 | 5 | 50 | 6 | 20 | 12 | 12 | 12 | 12 | 7.5 | 85 Ohms | TOP=L2:L3=L2/L4:L6=L5/L7:BOTTOM=L7 |
| PCIE_TX_N51 | TX51-DIFF1 | PAIR | 5 | 5.5 | 5 | 10 | 5 | 50 | 6 | 20 | 12 | 12 | 12 | 12 | 7.5 | 85 Ohms | TOP=L2:L3=L2/L4:L6=L5/L7:BOTTOM=L7 |
| PCIE_TX_N51 | TX51-DIFF1 | PAIR | 6 | 5.5 | 5 | 10 | 5 | 50 | 6 | 20 | 12 | 12 | 12 | 12 | 7.5 | 85 Ohms | TOP=L2:L3=L2/L4:L6=L5/L7:BOTTOM=L7 |
| PCIE_TX_N51 | TX51-DIFF1 | PAIR | 7 | 5.5 | 5 | 10 | 5 | 50 | 6 | 20 | 12 | 12 | 12 | 12 | 7.5 | 85 Ohms | TOP=L2:L3=L2/L4:L6=L5/L7:BOTTOM=L7 |
| PCIE_TX_N51 | TX51-DIFF1 | PAIR | 8 | 5.38 | 5 | 10 | 5 | 50 | 6 | 33 | 12 | 12 | 12 | 12 | 6.62 | 85 Ohms | TOP=L2:L3=L2/L4:L6=L5/L7:BOTTOM=L7 |
| PCIE_TX_P51 | TX51-DIFF1 | PAIR | 1 | 5.38 | 5 | 10 | 5 | 50 | 6 | 33 | 12 | 12 | 12 | 12 | 6.62 | 85 Ohms | TOP=L2:L3=L2/L4:L6=L5/L7:BOTTOM=L7 |
| PCIE_TX_P51 | TX51-DIFF1 | PAIR | 2 | 5.5 | 5 | 10 | 5 | 50 | 6 | 20 | 12 | 12 | 12 | 12 | 7.5 | 85 Ohms | TOP=L2:L3=L2/L4:L6=L5/L7:BOTTOM=L7 |
| PCIE_TX_P51 | TX51-DIFF1 | PAIR | 3 | 5.5 | 5 | 10 | 5 | 50 | 6 | 20 | 12 | 12 | 12 | 12 | 7.5 | 85 Ohms | TOP=L2:L3=L2/L4:L6=L5/L7:BOTTOM=L7 |
| PCIE_TX_P51 | TX51-DIFF1 | PAIR | 4 | 5.5 | 5 | 10 | 5 | 50 | 6 | 20 | 12 | 12 | 12 | 12 | 7.5 | 85 Ohms | TOP=L2:L3=L2/L4:L6=L5/L7:BOTTOM=L7 |
| PCIE_TX_P51 | TX51-DIFF1 | PAIR | 5 | 5.5 | 5 | 10 | 5 | 50 | 6 | 20 | 12 | 12 | 12 | 12 | 7.5 | 85 Ohms | TOP=L2:L3=L2/L4:L6=L5/L7:BOTTOM=L7 |
| PCIE_TX_P51 | TX51-DIFF1 | PAIR | 6 | 5.5 | 5 | 10 | 5 | 50 | 6 | 20 | 12 | 12 | 12 | 12 | 7.5 | 85 Ohms | TOP=L2:L3=L2/L4:L6=L5/L7:BOTTOM=L7 |
| PCIE_TX_P51 | TX51-DIFF1 | PAIR | 7 | 5.5 | 5 | 10 | 5 | 50 | 6 | 20 | 12 | 12 | 12 | 12 | 7.5 | 85 Ohms | TOP=L2:L3=L2/L4:L6=L5/L7:BOTTOM=L7 |
| PCIE_TX_P51 | TX51-DIFF1 | PAIR | 8 | 5.38 | 5 | 10 | 5 | 50 | 6 | 33 | 12 | 12 | 12 | 12 | 6.62 | 85 Ohms | TOP=L2:L3=L2/L4:L6=L5/L7:BOTTOM=L7 |
| PCIE_TX_N52 | TX52-DIFF1 | PAIR | 1 | 5.38 | 5 | 10 | 5 | 50 | 6 | 33 | 12 | 12 | 12 | 12 | 6.62 | 85 Ohms | TOP=L2:L3=L2/L4:L6=L5/L7:BOTTOM=L7 |
| PCIE_TX_N52 | TX52-DIFF1 | PAIR | 2 | 5.5 | 5 | 10 | 5 | 50 | 6 | 20 | 12 | 12 | 12 | 12 | 7.5 | 85 Ohms | TOP=L2:L3=L2/L4:L6=L5/L7:BOTTOM=L7 |
| PCIE_TX_N52 | TX52-DIFF1 | PAIR | 3 | 5.5 | 5 | 10 | 5 | 50 | 6 | 20 | 12 | 12 | 12 | 12 | 7.5 | 85 Ohms | TOP=L2:L3=L2/L4:L6=L5/L7:BOTTOM=L7 |
| PCIE_TX_N52 | TX52-DIFF1 | PAIR | 4 | 5.5 | 5 | 10 | 5 | 50 | 6 | 20 | 12 | 12 | 12 | 12 | 7.5 | 85 Ohms | TOP=L2:L3=L2/L4:L6=L5/L7:BOTTOM=L7 |
| PCIE_TX_N52 | TX52-DIFF1 | PAIR | 5 | 5.5 | 5 | 10 | 5 | 50 | 6 | 20 | 12 | 12 | 12 | 12 | 7.5 | 85 Ohms | TOP=L2:L3=L2/L4:L6=L5/L7:BOTTOM=L7 |
| PCIE_TX_N52 | TX52-DIFF1 | PAIR | 6 | 5.5 | 5 | 10 | 5 | 50 | 6 | 20 | 12 | 12 | 12 | 12 | 7.5 | 85 Ohms | TOP=L2:L3=L2/L4:L6=L5/L7:BOTTOM=L7 |
| PCIE_TX_N52 | TX52-DIFF1 | PAIR | 7 | 5.5 | 5 | 10 | 5 | 50 | 6 | 20 | 12 | 12 | 12 | 12 | 7.5 | 85 Ohms | TOP=L2:L3=L2/L4:L6=L5/L7:BOTTOM=L7 |
| PCIE_TX_N52 | TX52-DIFF1 | PAIR | 8 | 5.38 | 5 | 10 | 5 | 50 | 6 | 33 | 12 | 12 | 12 | 12 | 6.62 | 85 Ohms | TOP=L2:L3=L2/L4:L6=L5/L7:BOTTOM=L7 |
| PCIE_TX_P52 | TX52-DIFF1 | PAIR | 1 | 5.38 | 5 | 10 | 5 | 50 | 6 | 33 | 12 | 12 | 12 | 12 | 6.62 | 85 Ohms | TOP=L2:L3=L2/L4:L6=L5/L7:BOTTOM=L7 |
| PCIE_TX_P52 | TX52-DIFF1 | PAIR | 2 | 5.5 | 5 | 10 | 5 | 50 | 6 | 20 | 12 | 12 | 12 | 12 | 7.5 | 85 Ohms | TOP=L2:L3=L2/L4:L6=L5/L7:BOTTOM=L7 |
| PCIE_TX_P52 | TX52-DIFF1 | PAIR | 3 | 5.5 | 5 | 10 | 5 | 50 | 6 | 20 | 12 | 12 | 12 | 12 | 7.5 | 85 Ohms | TOP=L2:L3=L2/L4:L6=L5/L7:BOTTOM=L7 |
| PCIE_TX_P52 | TX52-DIFF1 | PAIR | 4 | 5.5 | 5 | 10 | 5 | 50 | 6 | 20 | 12 | 12 | 12 | 12 | 7.5 | 85 Ohms | TOP=L2:L3=L2/L4:L6=L5/L7:BOTTOM=L7 |
| PCIE_TX_P52 | TX52-DIFF1 | PAIR | 5 | 5.5 | 5 | 10 | 5 | 50 | 6 | 20 | 12 | 12 | 12 | 12 | 7.5 | 85 Ohms | TOP=L2:L3=L2/L4:L6=L5/L7:BOTTOM=L7 |
| PCIE_TX_P52 | TX52-DIFF1 | PAIR | 6 | 5.5 | 5 | 10 | 5 | 50 | 6 | 20 | 12 | 12 | 12 | 12 | 7.5 | 85 Ohms | TOP=L2:L3=L2/L4:L6=L5/L7:BOTTOM=L7 |
| PCIE_TX_P52 | TX52-DIFF1 | PAIR | 7 | 5.5 | 5 | 10 | 5 | 50 | 6 | 20 | 12 | 12 | 12 | 12 | 7.5 | 85 Ohms | TOP=L2:L3=L2/L4:L6=L5/L7:BOTTOM=L7 |
| PCIE_TX_P52 | TX52-DIFF1 | PAIR | 8 | 5.38 | 5 | 10 | 5 | 50 | 6 | 33 | 12 | 12 | 12 | 12 | 6.62 | 85 Ohms | TOP=L2:L3=L2/L4:L6=L5/L7:BOTTOM=L7 |
| PCIE_TX_N53 | TX53-DIFF1 | PAIR | 1 | 5.38 | 5 | 10 | 5 | 50 | 6 | 33 | 12 | 12 | 12 | 12 | 6.62 | 85 Ohms | TOP=L2:L3=L2/L4:L6=L5/L7:BOTTOM=L7 |
| PCIE_TX_N53 | TX53-DIFF1 | PAIR | 2 | 5.5 | 5 | 10 | 5 | 50 | 6 | 20 | 12 | 12 | 12 | 12 | 7.5 | 85 Ohms | TOP=L2:L3=L2/L4:L6=L5/L7:BOTTOM=L7 |
| PCIE_TX_N53 | TX53-DIFF1 | PAIR | 3 | 5.5 | 5 | 10 | 5 | 50 | 6 | 20 | 12 | 12 | 12 | 12 | 7.5 | 85 Ohms | TOP=L2:L3=L2/L4:L6=L5/L7:BOTTOM=L7 |
| PCIE_TX_N53 | TX53-DIFF1 | PAIR | 4 | 5.5 | 5 | 10 | 5 | 50 | 6 | 20 | 12 | 12 | 12 | 12 | 7.5 | 85 Ohms | TOP=L2:L3=L2/L4:L6=L5/L7:BOTTOM=L7 |
| PCIE_TX_N53 | TX53-DIFF1 | PAIR | 5 | 5.5 | 5 | 10 | 5 | 50 | 6 | 20 | 12 | 12 | 12 | 12 | 7.5 | 85 Ohms | TOP=L2:L3=L2/L4:L6=L5/L7:BOTTOM=L7 |
| PCIE_TX_N53 | TX53-DIFF1 | PAIR | 6 | 5.5 | 5 | 10 | 5 | 50 | 6 | 20 | 12 | 12 | 12 | 12 | 7.5 | 85 Ohms | TOP=L2:L3=L2/L4:L6=L5/L7:BOTTOM=L7 |
| PCIE_TX_N53 | TX53-DIFF1 | PAIR | 7 | 5.5 | 5 | 10 | 5 | 50 | 6 | 20 | 12 | 12 | 12 | 12 | 7.5 | 85 Ohms | TOP=L2:L3=L2/L4:L6=L5/L7:BOTTOM=L7 |
| PCIE_TX_N53 | TX53-DIFF1 | PAIR | 8 | 5.38 | 5 | 10 | 5 | 50 | 6 | 33 | 12 | 12 | 12 | 12 | 6.62 | 85 Ohms | TOP=L2:L3=L2/L4:L6=L5/L7:BOTTOM=L7 |
| PCIE_TX_P53 | TX53-DIFF1 | PAIR | 1 | 5.38 | 5 | 10 | 5 | 50 | 6 | 33 | 12 | 12 | 12 | 12 | 6.62 | 85 Ohms | TOP=L2:L3=L2/L4:L6=L5/L7:BOTTOM=L7 |
| PCIE_TX_P53 | TX53-DIFF1 | PAIR | 2 | 5.5 | 5 | 10 | 5 | 50 | 6 | 20 | 12 | 12 | 12 | 12 | 7.5 | 85 Ohms | TOP=L2:L3=L2/L4:L6=L5/L7:BOTTOM=L7 |
| PCIE_TX_P53 | TX53-DIFF1 | PAIR | 3 | 5.5 | 5 | 10 | 5 | 50 | 6 | 20 | 12 | 12 | 12 | 12 | 7.5 | 85 Ohms | TOP=L2:L3=L2/L4:L6=L5/L7:BOTTOM=L7 |
| PCIE_TX_P53 | TX53-DIFF1 | PAIR | 4 | 5.5 | 5 | 10 | 5 | 50 | 6 | 20 | 12 | 12 | 12 | 12 | 7.5 | 85 Ohms | TOP=L2:L3=L2/L4:L6=L5/L7:BOTTOM=L7 |
| PCIE_TX_P53 | TX53-DIFF1 | PAIR | 5 | 5.5 | 5 | 10 | 5 | 50 | 6 | 20 | 12 | 12 | 12 | 12 | 7.5 | 85 Ohms | TOP=L2:L3=L2/L4:L6=L5/L7:BOTTOM=L7 |
| PCIE_TX_P53 | TX53-DIFF1 | PAIR | 6 | 5.5 | 5 | 10 | 5 | 50 | 6 | 20 | 12 | 12 | 12 | 12 | 7.5 | 85 Ohms | TOP=L2:L3=L2/L4:L6=L5/L7:BOTTOM=L7 |
| PCIE_TX_P53 | TX53-DIFF1 | PAIR | 7 | 5.5 | 5 | 10 | 5 | 50 | 6 | 20 | 12 | 12 | 12 | 12 | 7.5 | 85 Ohms | TOP=L2:L3=L2/L4:L6=L5/L7:BOTTOM=L7 |
| PCIE_TX_P53 | TX53-DIFF1 | PAIR | 8 | 5.38 | 5 | 10 | 5 | 50 | 6 | 33 | 12 | 12 | 12 | 12 | 6.62 | 85 Ohms | TOP=L2:L3=L2/L4:L6=L5/L7:BOTTOM=L7 |
| PCIE_TX_N54 | TX54-DIFF1 | PAIR | 1 | 5.38 | 5 | 10 | 5 | 50 | 6 | 33 | 12 | 12 | 12 | 12 | 6.62 | 85 Ohms | TOP=L2:L3=L2/L4:L6=L5/L7:BOTTOM=L7 |
| PCIE_TX_N54 | TX54-DIFF1 | PAIR | 2 | 5.5 | 5 | 10 | 5 | 50 | 6 | 20 | 12 | 12 | 12 | 12 | 7.5 | 85 Ohms | TOP=L2:L3=L2/L4:L6=L5/L7:BOTTOM=L7 |
| PCIE_TX_N54 | TX54-DIFF1 | PAIR | 3 | 5.5 | 5 | 10 | 5 | 50 | 6 | 20 | 12 | 12 | 12 | 12 | 7.5 | 85 Ohms | TOP=L2:L3=L2/L4:L6=L5/L7:BOTTOM=L7 |
| PCIE_TX_N54 | TX54-DIFF1 | PAIR | 4 | 5.5 | 5 | 10 | 5 | 50 | 6 | 20 | 12 | 12 | 12 | 12 | 7.5 | 85 Ohms | TOP=L2:L3=L2/L4:L6=L5/L7:BOTTOM=L7 |
| PCIE_TX_N54 | TX54-DIFF1 | PAIR | 5 | 5.5 | 5 | 10 | 5 | 50 | 6 | 20 | 12 | 12 | 12 | 12 | 7.5 | 85 Ohms | TOP=L2:L3=L2/L4:L6=L5/L7:BOTTOM=L7 |
| PCIE_TX_N54 | TX54-DIFF1 | PAIR | 6 | 5.5 | 5 | 10 | 5 | 50 | 6 | 20 | 12 | 12 | 12 | 12 | 7.5 | 85 Ohms | TOP=L2:L3=L2/L4:L6=L5/L7:BOTTOM=L7 |
| PCIE_TX_N54 | TX54-DIFF1 | PAIR | 7 | 5.5 | 5 | 10 | 5 | 50 | 6 | 20 | 12 | 12 | 12 | 12 | 7.5 | 85 Ohms | TOP=L2:L3=L2/L4:L6=L5/L7:BOTTOM=L7 |
| PCIE_TX_N54 | TX54-DIFF1 | PAIR | 8 | 5.38 | 5 | 10 | 5 | 50 | 6 | 33 | 12 | 12 | 12 | 12 | 6.62 | 85 Ohms | TOP=L2:L3=L2/L4:L6=L5/L7:BOTTOM=L7 |
| PCIE_TX_P54 | TX54-DIFF1 | PAIR | 1 | 5.38 | 5 | 10 | 5 | 50 | 6 | 33 | 12 | 12 | 12 | 12 | 6.62 | 85 Ohms | TOP=L2:L3=L2/L4:L6=L5/L7:BOTTOM=L7 |
| PCIE_TX_P54 | TX54-DIFF1 | PAIR | 2 | 5.5 | 5 | 10 | 5 | 50 | 6 | 20 | 12 | 12 | 12 | 12 | 7.5 | 85 Ohms | TOP=L2:L3=L2/L4:L6=L5/L7:BOTTOM=L7 |
| PCIE_TX_P54 | TX54-DIFF1 | PAIR | 3 | 5.5 | 5 | 10 | 5 | 50 | 6 | 20 | 12 | 12 | 12 | 12 | 7.5 | 85 Ohms | TOP=L2:L3=L2/L4:L6=L5/L7:BOTTOM=L7 |
| PCIE_TX_P54 | TX54-DIFF1 | PAIR | 4 | 5.5 | 5 | 10 | 5 | 50 | 6 | 20 | 12 | 12 | 12 | 12 | 7.5 | 85 Ohms | TOP=L2:L3=L2/L4:L6=L5/L7:BOTTOM=L7 |
| PCIE_TX_P54 | TX54-DIFF1 | PAIR | 5 | 5.5 | 5 | 10 | 5 | 50 | 6 | 20 | 12 | 12 | 12 | 12 | 7.5 | 85 Ohms | TOP=L2:L3=L2/L4:L6=L5/L7:BOTTOM=L7 |
| PCIE_TX_P54 | TX54-DIFF1 | PAIR | 6 | 5.5 | 5 | 10 | 5 | 50 | 6 | 20 | 12 | 12 | 12 | 12 | 7.5 | 85 Ohms | TOP=L2:L3=L2/L4:L6=L5/L7:BOTTOM=L7 |
| PCIE_TX_P54 | TX54-DIFF1 | PAIR | 7 | 5.5 | 5 | 10 | 5 | 50 | 6 | 20 | 12 | 12 | 12 | 12 | 7.5 | 85 Ohms | TOP=L2:L3=L2/L4:L6=L5/L7:BOTTOM=L7 |
| PCIE_TX_P54 | TX54-DIFF1 | PAIR | 8 | 5.38 | 5 | 10 | 5 | 50 | 6 | 33 | 12 | 12 | 12 | 12 | 6.62 | 85 Ohms | TOP=L2:L3=L2/L4:L6=L5/L7:BOTTOM=L7 |
| PCIE_TX_N55 | TX55-DIFF1 | PAIR | 1 | 5.38 | 5 | 10 | 5 | 50 | 6 | 33 | 12 | 12 | 12 | 12 | 6.62 | 85 Ohms | TOP=L2:L3=L2/L4:L6=L5/L7:BOTTOM=L7 |
| PCIE_TX_N55 | TX55-DIFF1 | PAIR | 2 | 5.5 | 5 | 10 | 5 | 50 | 6 | 20 | 12 | 12 | 12 | 12 | 7.5 | 85 Ohms | TOP=L2:L3=L2/L4:L6=L5/L7:BOTTOM=L7 |
| PCIE_TX_N55 | TX55-DIFF1 | PAIR | 3 | 5.5 | 5 | 10 | 5 | 50 | 6 | 20 | 12 | 12 | 12 | 12 | 7.5 | 85 Ohms | TOP=L2:L3=L2/L4:L6=L5/L7:BOTTOM=L7 |
| PCIE_TX_N55 | TX55-DIFF1 | PAIR | 4 | 5.5 | 5 | 10 | 5 | 50 | 6 | 20 | 12 | 12 | 12 | 12 | 7.5 | 85 Ohms | TOP=L2:L3=L2/L4:L6=L5/L7:BOTTOM=L7 |
| PCIE_TX_N55 | TX55-DIFF1 | PAIR | 5 | 5.5 | 5 | 10 | 5 | 50 | 6 | 20 | 12 | 12 | 12 | 12 | 7.5 | 85 Ohms | TOP=L2:L3=L2/L4:L6=L5/L7:BOTTOM=L7 |
| PCIE_TX_N55 | TX55-DIFF1 | PAIR | 6 | 5.5 | 5 | 10 | 5 | 50 | 6 | 20 | 12 | 12 | 12 | 12 | 7.5 | 85 Ohms | TOP=L2:L3=L2/L4:L6=L5/L7:BOTTOM=L7 |
| PCIE_TX_N55 | TX55-DIFF1 | PAIR | 7 | 5.5 | 5 | 10 | 5 | 50 | 6 | 20 | 12 | 12 | 12 | 12 | 7.5 | 85 Ohms | TOP=L2:L3=L2/L4:L6=L5/L7:BOTTOM=L7 |
| PCIE_TX_N55 | TX55-DIFF1 | PAIR | 8 | 5.38 | 5 | 10 | 5 | 50 | 6 | 33 | 12 | 12 | 12 | 12 | 6.62 | 85 Ohms | TOP=L2:L3=L2/L4:L6=L5/L7:BOTTOM=L7 |
| PCIE_TX_P55 | TX55-DIFF1 | PAIR | 1 | 5.38 | 5 | 10 | 5 | 50 | 6 | 33 | 12 | 12 | 12 | 12 | 6.62 | 85 Ohms | TOP=L2:L3=L2/L4:L6=L5/L7:BOTTOM=L7 |
| PCIE_TX_P55 | TX55-DIFF1 | PAIR | 2 | 5.5 | 5 | 10 | 5 | 50 | 6 | 20 | 12 | 12 | 12 | 12 | 7.5 | 85 Ohms | TOP=L2:L3=L2/L4:L6=L5/L7:BOTTOM=L7 |
| PCIE_TX_P55 | TX55-DIFF1 | PAIR | 3 | 5.5 | 5 | 10 | 5 | 50 | 6 | 20 | 12 | 12 | 12 | 12 | 7.5 | 85 Ohms | TOP=L2:L3=L2/L4:L6=L5/L7:BOTTOM=L7 |
| PCIE_TX_P55 | TX55-DIFF1 | PAIR | 4 | 5.5 | 5 | 10 | 5 | 50 | 6 | 20 | 12 | 12 | 12 | 12 | 7.5 | 85 Ohms | TOP=L2:L3=L2/L4:L6=L5/L7:BOTTOM=L7 |
| PCIE_TX_P55 | TX55-DIFF1 | PAIR | 5 | 5.5 | 5 | 10 | 5 | 50 | 6 | 20 | 12 | 12 | 12 | 12 | 7.5 | 85 Ohms | TOP=L2:L3=L2/L4:L6=L5/L7:BOTTOM=L7 |
| PCIE_TX_P55 | TX55-DIFF1 | PAIR | 6 | 5.5 | 5 | 10 | 5 | 50 | 6 | 20 | 12 | 12 | 12 | 12 | 7.5 | 85 Ohms | TOP=L2:L3=L2/L4:L6=L5/L7:BOTTOM=L7 |
| PCIE_TX_P55 | TX55-DIFF1 | PAIR | 7 | 5.5 | 5 | 10 | 5 | 50 | 6 | 20 | 12 | 12 | 12 | 12 | 7.5 | 85 Ohms | TOP=L2:L3=L2/L4:L6=L5/L7:BOTTOM=L7 |
| PCIE_TX_P55 | TX55-DIFF1 | PAIR | 8 | 5.38 | 5 | 10 | 5 | 50 | 6 | 33 | 12 | 12 | 12 | 12 | 6.62 | 85 Ohms | TOP=L2:L3=L2/L4:L6=L5/L7:BOTTOM=L7 |
| PCIE_TX_N56 | TX56-DIFF1 | PAIR | 1 | 5.38 | 5 | 10 | 5 | 50 | 6 | 33 | 12 | 12 | 12 | 12 | 6.62 | 85 Ohms | TOP=L2:L3=L2/L4:L6=L5/L7:BOTTOM=L7 |
| PCIE_TX_N56 | TX56-DIFF1 | PAIR | 2 | 5.5 | 5 | 10 | 5 | 50 | 6 | 20 | 12 | 12 | 12 | 12 | 7.5 | 85 Ohms | TOP=L2:L3=L2/L4:L6=L5/L7:BOTTOM=L7 |
| PCIE_TX_N56 | TX56-DIFF1 | PAIR | 3 | 5.5 | 5 | 10 | 5 | 50 | 6 | 20 | 12 | 12 | 12 | 12 | 7.5 | 85 Ohms | TOP=L2:L3=L2/L4:L6=L5/L7:BOTTOM=L7 |
| PCIE_TX_N56 | TX56-DIFF1 | PAIR | 4 | 5.5 | 5 | 10 | 5 | 50 | 6 | 20 | 12 | 12 | 12 | 12 | 7.5 | 85 Ohms | TOP=L2:L3=L2/L4:L6=L5/L7:BOTTOM=L7 |
| PCIE_TX_N56 | TX56-DIFF1 | PAIR | 5 | 5.5 | 5 | 10 | 5 | 50 | 6 | 20 | 12 | 12 | 12 | 12 | 7.5 | 85 Ohms | TOP=L2:L3=L2/L4:L6=L5/L7:BOTTOM=L7 |
| PCIE_TX_N56 | TX56-DIFF1 | PAIR | 6 | 5.5 | 5 | 10 | 5 | 50 | 6 | 20 | 12 | 12 | 12 | 12 | 7.5 | 85 Ohms | TOP=L2:L3=L2/L4:L6=L5/L7:BOTTOM=L7 |
| PCIE_TX_N56 | TX56-DIFF1 | PAIR | 7 | 5.5 | 5 | 10 | 5 | 50 | 6 | 20 | 12 | 12 | 12 | 12 | 7.5 | 85 Ohms | TOP=L2:L3=L2/L4:L6=L5/L7:BOTTOM=L7 |
| PCIE_TX_N56 | TX56-DIFF1 | PAIR | 8 | 5.38 | 5 | 10 | 5 | 50 | 6 | 33 | 12 | 12 | 12 | 12 | 6.62 | 85 Ohms | TOP=L2:L3=L2/L4:L6=L5/L7:BOTTOM=L7 |
| PCIE_TX_P56 | TX56-DIFF1 | PAIR | 1 | 5.38 | 5 | 10 | 5 | 50 | 6 | 33 | 12 | 12 | 12 | 12 | 6.62 | 85 Ohms | TOP=L2:L3=L2/L4:L6=L5/L7:BOTTOM=L7 |
| PCIE_TX_P56 | TX56-DIFF1 | PAIR | 2 | 5.5 | 5 | 10 | 5 | 50 | 6 | 20 | 12 | 12 | 12 | 12 | 7.5 | 85 Ohms | TOP=L2:L3=L2/L4:L6=L5/L7:BOTTOM=L7 |
| PCIE_TX_P56 | TX56-DIFF1 | PAIR | 3 | 5.5 | 5 | 10 | 5 | 50 | 6 | 20 | 12 | 12 | 12 | 12 | 7.5 | 85 Ohms | TOP=L2:L3=L2/L4:L6=L5/L7:BOTTOM=L7 |
| PCIE_TX_P56 | TX56-DIFF1 | PAIR | 4 | 5.5 | 5 | 10 | 5 | 50 | 6 | 20 | 12 | 12 | 12 | 12 | 7.5 | 85 Ohms | TOP=L2:L3=L2/L4:L6=L5/L7:BOTTOM=L7 |
| PCIE_TX_P56 | TX56-DIFF1 | PAIR | 5 | 5.5 | 5 | 10 | 5 | 50 | 6 | 20 | 12 | 12 | 12 | 12 | 7.5 | 85 Ohms | TOP=L2:L3=L2/L4:L6=L5/L7:BOTTOM=L7 |
| PCIE_TX_P56 | TX56-DIFF1 | PAIR | 6 | 5.5 | 5 | 10 | 5 | 50 | 6 | 20 | 12 | 12 | 12 | 12 | 7.5 | 85 Ohms | TOP=L2:L3=L2/L4:L6=L5/L7:BOTTOM=L7 |
| PCIE_TX_P56 | TX56-DIFF1 | PAIR | 7 | 5.5 | 5 | 10 | 5 | 50 | 6 | 20 | 12 | 12 | 12 | 12 | 7.5 | 85 Ohms | TOP=L2:L3=L2/L4:L6=L5/L7:BOTTOM=L7 |
| PCIE_TX_P56 | TX56-DIFF1 | PAIR | 8 | 5.38 | 5 | 10 | 5 | 50 | 6 | 33 | 12 | 12 | 12 | 12 | 6.62 | 85 Ohms | TOP=L2:L3=L2/L4:L6=L5/L7:BOTTOM=L7 |
| PCIE_TX_N57 | TX57-DIFF1 | PAIR | 1 | 5.38 | 5 | 10 | 5 | 50 | 6 | 33 | 12 | 12 | 12 | 12 | 6.62 | 85 Ohms | TOP=L2:L3=L2/L4:L6=L5/L7:BOTTOM=L7 |
| PCIE_TX_N57 | TX57-DIFF1 | PAIR | 2 | 5.5 | 5 | 10 | 5 | 50 | 6 | 20 | 12 | 12 | 12 | 12 | 7.5 | 85 Ohms | TOP=L2:L3=L2/L4:L6=L5/L7:BOTTOM=L7 |
| PCIE_TX_N57 | TX57-DIFF1 | PAIR | 3 | 5.5 | 5 | 10 | 5 | 50 | 6 | 20 | 12 | 12 | 12 | 12 | 7.5 | 85 Ohms | TOP=L2:L3=L2/L4:L6=L5/L7:BOTTOM=L7 |
| PCIE_TX_N57 | TX57-DIFF1 | PAIR | 4 | 5.5 | 5 | 10 | 5 | 50 | 6 | 20 | 12 | 12 | 12 | 12 | 7.5 | 85 Ohms | TOP=L2:L3=L2/L4:L6=L5/L7:BOTTOM=L7 |
| PCIE_TX_N57 | TX57-DIFF1 | PAIR | 5 | 5.5 | 5 | 10 | 5 | 50 | 6 | 20 | 12 | 12 | 12 | 12 | 7.5 | 85 Ohms | TOP=L2:L3=L2/L4:L6=L5/L7:BOTTOM=L7 |
| PCIE_TX_N57 | TX57-DIFF1 | PAIR | 6 | 5.5 | 5 | 10 | 5 | 50 | 6 | 20 | 12 | 12 | 12 | 12 | 7.5 | 85 Ohms | TOP=L2:L3=L2/L4:L6=L5/L7:BOTTOM=L7 |
| PCIE_TX_N57 | TX57-DIFF1 | PAIR | 7 | 5.5 | 5 | 10 | 5 | 50 | 6 | 20 | 12 | 12 | 12 | 12 | 7.5 | 85 Ohms | TOP=L2:L3=L2/L4:L6=L5/L7:BOTTOM=L7 |
| PCIE_TX_N57 | TX57-DIFF1 | PAIR | 8 | 5.38 | 5 | 10 | 5 | 50 | 6 | 33 | 12 | 12 | 12 | 12 | 6.62 | 85 Ohms | TOP=L2:L3=L2/L4:L6=L5/L7:BOTTOM=L7 |
| PCIE_TX_P57 | TX57-DIFF1 | PAIR | 1 | 5.38 | 5 | 10 | 5 | 50 | 6 | 33 | 12 | 12 | 12 | 12 | 6.62 | 85 Ohms | TOP=L2:L3=L2/L4:L6=L5/L7:BOTTOM=L7 |
| PCIE_TX_P57 | TX57-DIFF1 | PAIR | 2 | 5.5 | 5 | 10 | 5 | 50 | 6 | 20 | 12 | 12 | 12 | 12 | 7.5 | 85 Ohms | TOP=L2:L3=L2/L4:L6=L5/L7:BOTTOM=L7 |
| PCIE_TX_P57 | TX57-DIFF1 | PAIR | 3 | 5.5 | 5 | 10 | 5 | 50 | 6 | 20 | 12 | 12 | 12 | 12 | 7.5 | 85 Ohms | TOP=L2:L3=L2/L4:L6=L5/L7:BOTTOM=L7 |
| PCIE_TX_P57 | TX57-DIFF1 | PAIR | 4 | 5.5 | 5 | 10 | 5 | 50 | 6 | 20 | 12 | 12 | 12 | 12 | 7.5 | 85 Ohms | TOP=L2:L3=L2/L4:L6=L5/L7:BOTTOM=L7 |
| PCIE_TX_P57 | TX57-DIFF1 | PAIR | 5 | 5.5 | 5 | 10 | 5 | 50 | 6 | 20 | 12 | 12 | 12 | 12 | 7.5 | 85 Ohms | TOP=L2:L3=L2/L4:L6=L5/L7:BOTTOM=L7 |
| PCIE_TX_P57 | TX57-DIFF1 | PAIR | 6 | 5.5 | 5 | 10 | 5 | 50 | 6 | 20 | 12 | 12 | 12 | 12 | 7.5 | 85 Ohms | TOP=L2:L3=L2/L4:L6=L5/L7:BOTTOM=L7 |
| PCIE_TX_P57 | TX57-DIFF1 | PAIR | 7 | 5.5 | 5 | 10 | 5 | 50 | 6 | 20 | 12 | 12 | 12 | 12 | 7.5 | 85 Ohms | TOP=L2:L3=L2/L4:L6=L5/L7:BOTTOM=L7 |
| PCIE_TX_P57 | TX57-DIFF1 | PAIR | 8 | 5.38 | 5 | 10 | 5 | 50 | 6 | 33 | 12 | 12 | 12 | 12 | 6.62 | 85 Ohms | TOP=L2:L3=L2/L4:L6=L5/L7:BOTTOM=L7 |
| PCIE_TX_N58 | TX58-DIFF1 | PAIR | 1 | 5.38 | 5 | 10 | 5 | 50 | 6 | 33 | 12 | 12 | 12 | 12 | 6.62 | 85 Ohms | TOP=L2:L3=L2/L4:L6=L5/L7:BOTTOM=L7 |
| PCIE_TX_N58 | TX58-DIFF1 | PAIR | 2 | 5.5 | 5 | 10 | 5 | 50 | 6 | 20 | 12 | 12 | 12 | 12 | 7.5 | 85 Ohms | TOP=L2:L3=L2/L4:L6=L5/L7:BOTTOM=L7 |
| PCIE_TX_N58 | TX58-DIFF1 | PAIR | 3 | 5.5 | 5 | 10 | 5 | 50 | 6 | 20 | 12 | 12 | 12 | 12 | 7.5 | 85 Ohms | TOP=L2:L3=L2/L4:L6=L5/L7:BOTTOM=L7 |
| PCIE_TX_N58 | TX58-DIFF1 | PAIR | 4 | 5.5 | 5 | 10 | 5 | 50 | 6 | 20 | 12 | 12 | 12 | 12 | 7.5 | 85 Ohms | TOP=L2:L3=L2/L4:L6=L5/L7:BOTTOM=L7 |
| PCIE_TX_N58 | TX58-DIFF1 | PAIR | 5 | 5.5 | 5 | 10 | 5 | 50 | 6 | 20 | 12 | 12 | 12 | 12 | 7.5 | 85 Ohms | TOP=L2:L3=L2/L4:L6=L5/L7:BOTTOM=L7 |
| PCIE_TX_N58 | TX58-DIFF1 | PAIR | 6 | 5.5 | 5 | 10 | 5 | 50 | 6 | 20 | 12 | 12 | 12 | 12 | 7.5 | 85 Ohms | TOP=L2:L3=L2/L4:L6=L5/L7:BOTTOM=L7 |
| PCIE_TX_N58 | TX58-DIFF1 | PAIR | 7 | 5.5 | 5 | 10 | 5 | 50 | 6 | 20 | 12 | 12 | 12 | 12 | 7.5 | 85 Ohms | TOP=L2:L3=L2/L4:L6=L5/L7:BOTTOM=L7 |
| PCIE_TX_N58 | TX58-DIFF1 | PAIR | 8 | 5.38 | 5 | 10 | 5 | 50 | 6 | 33 | 12 | 12 | 12 | 12 | 6.62 | 85 Ohms | TOP=L2:L3=L2/L4:L6=L5/L7:BOTTOM=L7 |
| PCIE_TX_P58 | TX58-DIFF1 | PAIR | 1 | 5.38 | 5 | 10 | 5 | 50 | 6 | 33 | 12 | 12 | 12 | 12 | 6.62 | 85 Ohms | TOP=L2:L3=L2/L4:L6=L5/L7:BOTTOM=L7 |
| PCIE_TX_P58 | TX58-DIFF1 | PAIR | 2 | 5.5 | 5 | 10 | 5 | 50 | 6 | 20 | 12 | 12 | 12 | 12 | 7.5 | 85 Ohms | TOP=L2:L3=L2/L4:L6=L5/L7:BOTTOM=L7 |
| PCIE_TX_P58 | TX58-DIFF1 | PAIR | 3 | 5.5 | 5 | 10 | 5 | 50 | 6 | 20 | 12 | 12 | 12 | 12 | 7.5 | 85 Ohms | TOP=L2:L3=L2/L4:L6=L5/L7:BOTTOM=L7 |
| PCIE_TX_P58 | TX58-DIFF1 | PAIR | 4 | 5.5 | 5 | 10 | 5 | 50 | 6 | 20 | 12 | 12 | 12 | 12 | 7.5 | 85 Ohms | TOP=L2:L3=L2/L4:L6=L5/L7:BOTTOM=L7 |
| PCIE_TX_P58 | TX58-DIFF1 | PAIR | 5 | 5.5 | 5 | 10 | 5 | 50 | 6 | 20 | 12 | 12 | 12 | 12 | 7.5 | 85 Ohms | TOP=L2:L3=L2/L4:L6=L5/L7:BOTTOM=L7 |
| PCIE_TX_P58 | TX58-DIFF1 | PAIR | 6 | 5.5 | 5 | 10 | 5 | 50 | 6 | 20 | 12 | 12 | 12 | 12 | 7.5 | 85 Ohms | TOP=L2:L3=L2/L4:L6=L5/L7:BOTTOM=L7 |
| PCIE_TX_P58 | TX58-DIFF1 | PAIR | 7 | 5.5 | 5 | 10 | 5 | 50 | 6 | 20 | 12 | 12 | 12 | 12 | 7.5 | 85 Ohms | TOP=L2:L3=L2/L4:L6=L5/L7:BOTTOM=L7 |
| PCIE_TX_P58 | TX58-DIFF1 | PAIR | 8 | 5.38 | 5 | 10 | 5 | 50 | 6 | 33 | 12 | 12 | 12 | 12 | 6.62 | 85 Ohms | TOP=L2:L3=L2/L4:L6=L5/L7:BOTTOM=L7 |
| PCIE_TX_N59 | TX59-DIFF1 | PAIR | 1 | 5.38 | 5 | 10 | 5 | 50 | 6 | 33 | 12 | 12 | 12 | 12 | 6.62 | 85 Ohms | TOP=L2:L3=L2/L4:L6=L5/L7:BOTTOM=L7 |
| PCIE_TX_N59 | TX59-DIFF1 | PAIR | 2 | 5.5 | 5 | 10 | 5 | 50 | 6 | 20 | 12 | 12 | 12 | 12 | 7.5 | 85 Ohms | TOP=L2:L3=L2/L4:L6=L5/L7:BOTTOM=L7 |
| PCIE_TX_N59 | TX59-DIFF1 | PAIR | 3 | 5.5 | 5 | 10 | 5 | 50 | 6 | 20 | 12 | 12 | 12 | 12 | 7.5 | 85 Ohms | TOP=L2:L3=L2/L4:L6=L5/L7:BOTTOM=L7 |
| PCIE_TX_N59 | TX59-DIFF1 | PAIR | 4 | 5.5 | 5 | 10 | 5 | 50 | 6 | 20 | 12 | 12 | 12 | 12 | 7.5 | 85 Ohms | TOP=L2:L3=L2/L4:L6=L5/L7:BOTTOM=L7 |
| PCIE_TX_N59 | TX59-DIFF1 | PAIR | 5 | 5.5 | 5 | 10 | 5 | 50 | 6 | 20 | 12 | 12 | 12 | 12 | 7.5 | 85 Ohms | TOP=L2:L3=L2/L4:L6=L5/L7:BOTTOM=L7 |
| PCIE_TX_N59 | TX59-DIFF1 | PAIR | 6 | 5.5 | 5 | 10 | 5 | 50 | 6 | 20 | 12 | 12 | 12 | 12 | 7.5 | 85 Ohms | TOP=L2:L3=L2/L4:L6=L5/L7:BOTTOM=L7 |
| PCIE_TX_N59 | TX59-DIFF1 | PAIR | 7 | 5.5 | 5 | 10 | 5 | 50 | 6 | 20 | 12 | 12 | 12 | 12 | 7.5 | 85 Ohms | TOP=L2:L3=L2/L4:L6=L5/L7:BOTTOM=L7 |
| PCIE_TX_N59 | TX59-DIFF1 | PAIR | 8 | 5.38 | 5 | 10 | 5 | 50 | 6 | 33 | 12 | 12 | 12 | 12 | 6.62 | 85 Ohms | TOP=L2:L3=L2/L4:L6=L5/L7:BOTTOM=L7 |
| PCIE_TX_P59 | TX59-DIFF1 | PAIR | 1 | 5.38 | 5 | 10 | 5 | 50 | 6 | 33 | 12 | 12 | 12 | 12 | 6.62 | 85 Ohms | TOP=L2:L3=L2/L4:L6=L5/L7:BOTTOM=L7 |
| PCIE_TX_P59 | TX59-DIFF1 | PAIR | 2 | 5.5 | 5 | 10 | 5 | 50 | 6 | 20 | 12 | 12 | 12 | 12 | 7.5 | 85 Ohms | TOP=L2:L3=L2/L4:L6=L5/L7:BOTTOM=L7 |
| PCIE_TX_P59 | TX59-DIFF1 | PAIR | 3 | 5.5 | 5 | 10 | 5 | 50 | 6 | 20 | 12 | 12 | 12 | 12 | 7.5 | 85 Ohms | TOP=L2:L3=L2/L4:L6=L5/L7:BOTTOM=L7 |
| PCIE_TX_P59 | TX59-DIFF1 | PAIR | 4 | 5.5 | 5 | 10 | 5 | 50 | 6 | 20 | 12 | 12 | 12 | 12 | 7.5 | 85 Ohms | TOP=L2:L3=L2/L4:L6=L5/L7:BOTTOM=L7 |
| PCIE_TX_P59 | TX59-DIFF1 | PAIR | 5 | 5.5 | 5 | 10 | 5 | 50 | 6 | 20 | 12 | 12 | 12 | 12 | 7.5 | 85 Ohms | TOP=L2:L3=L2/L4:L6=L5/L7:BOTTOM=L7 |
| PCIE_TX_P59 | TX59-DIFF1 | PAIR | 6 | 5.5 | 5 | 10 | 5 | 50 | 6 | 20 | 12 | 12 | 12 | 12 | 7.5 | 85 Ohms | TOP=L2:L3=L2/L4:L6=L5/L7:BOTTOM=L7 |
| PCIE_TX_P59 | TX59-DIFF1 | PAIR | 7 | 5.5 | 5 | 10 | 5 | 50 | 6 | 20 | 12 | 12 | 12 | 12 | 7.5 | 85 Ohms | TOP=L2:L3=L2/L4:L6=L5/L7:BOTTOM=L7 |
| PCIE_TX_P59 | TX59-DIFF1 | PAIR | 8 | 5.38 | 5 | 10 | 5 | 50 | 6 | 33 | 12 | 12 | 12 | 12 | 6.62 | 85 Ohms | TOP=L2:L3=L2/L4:L6=L5/L7:BOTTOM=L7 |
| PCIE_TX_N5 | TX5-DIFF1 | PAIR | 1 | 5.38 | 5 | 10 | 5 | 50 | 6 | 33 | 12 | 12 | 12 | 12 | 6.62 | 85 Ohms | TOP=L2:L3=L2/L4:L6=L5/L7:BOTTOM=L7 |
| PCIE_TX_N5 | TX5-DIFF1 | PAIR | 2 | 5.5 | 5 | 10 | 5 | 50 | 6 | 20 | 12 | 12 | 12 | 12 | 7.5 | 85 Ohms | TOP=L2:L3=L2/L4:L6=L5/L7:BOTTOM=L7 |
| PCIE_TX_N5 | TX5-DIFF1 | PAIR | 3 | 5.5 | 5 | 10 | 5 | 50 | 6 | 20 | 12 | 12 | 12 | 12 | 7.5 | 85 Ohms | TOP=L2:L3=L2/L4:L6=L5/L7:BOTTOM=L7 |
| PCIE_TX_N5 | TX5-DIFF1 | PAIR | 4 | 5.5 | 5 | 10 | 5 | 50 | 6 | 20 | 12 | 12 | 12 | 12 | 7.5 | 85 Ohms | TOP=L2:L3=L2/L4:L6=L5/L7:BOTTOM=L7 |
| PCIE_TX_N5 | TX5-DIFF1 | PAIR | 5 | 5.5 | 5 | 10 | 5 | 50 | 6 | 20 | 12 | 12 | 12 | 12 | 7.5 | 85 Ohms | TOP=L2:L3=L2/L4:L6=L5/L7:BOTTOM=L7 |
| PCIE_TX_N5 | TX5-DIFF1 | PAIR | 6 | 5.5 | 5 | 10 | 5 | 50 | 6 | 20 | 12 | 12 | 12 | 12 | 7.5 | 85 Ohms | TOP=L2:L3=L2/L4:L6=L5/L7:BOTTOM=L7 |
| PCIE_TX_N5 | TX5-DIFF1 | PAIR | 7 | 5.5 | 5 | 10 | 5 | 50 | 6 | 20 | 12 | 12 | 12 | 12 | 7.5 | 85 Ohms | TOP=L2:L3=L2/L4:L6=L5/L7:BOTTOM=L7 |
| PCIE_TX_N5 | TX5-DIFF1 | PAIR | 8 | 5.38 | 5 | 10 | 5 | 50 | 6 | 33 | 12 | 12 | 12 | 12 | 6.62 | 85 Ohms | TOP=L2:L3=L2/L4:L6=L5/L7:BOTTOM=L7 |
| PCIE_TX_P5 | TX5-DIFF1 | PAIR | 1 | 5.38 | 5 | 10 | 5 | 50 | 6 | 33 | 12 | 12 | 12 | 12 | 6.62 | 85 Ohms | TOP=L2:L3=L2/L4:L6=L5/L7:BOTTOM=L7 |
| PCIE_TX_P5 | TX5-DIFF1 | PAIR | 2 | 5.5 | 5 | 10 | 5 | 50 | 6 | 20 | 12 | 12 | 12 | 12 | 7.5 | 85 Ohms | TOP=L2:L3=L2/L4:L6=L5/L7:BOTTOM=L7 |
| PCIE_TX_P5 | TX5-DIFF1 | PAIR | 3 | 5.5 | 5 | 10 | 5 | 50 | 6 | 20 | 12 | 12 | 12 | 12 | 7.5 | 85 Ohms | TOP=L2:L3=L2/L4:L6=L5/L7:BOTTOM=L7 |
| PCIE_TX_P5 | TX5-DIFF1 | PAIR | 4 | 5.5 | 5 | 10 | 5 | 50 | 6 | 20 | 12 | 12 | 12 | 12 | 7.5 | 85 Ohms | TOP=L2:L3=L2/L4:L6=L5/L7:BOTTOM=L7 |
| PCIE_TX_P5 | TX5-DIFF1 | PAIR | 5 | 5.5 | 5 | 10 | 5 | 50 | 6 | 20 | 12 | 12 | 12 | 12 | 7.5 | 85 Ohms | TOP=L2:L3=L2/L4:L6=L5/L7:BOTTOM=L7 |
| PCIE_TX_P5 | TX5-DIFF1 | PAIR | 6 | 5.5 | 5 | 10 | 5 | 50 | 6 | 20 | 12 | 12 | 12 | 12 | 7.5 | 85 Ohms | TOP=L2:L3=L2/L4:L6=L5/L7:BOTTOM=L7 |
| PCIE_TX_P5 | TX5-DIFF1 | PAIR | 7 | 5.5 | 5 | 10 | 5 | 50 | 6 | 20 | 12 | 12 | 12 | 12 | 7.5 | 85 Ohms | TOP=L2:L3=L2/L4:L6=L5/L7:BOTTOM=L7 |
| PCIE_TX_P5 | TX5-DIFF1 | PAIR | 8 | 5.38 | 5 | 10 | 5 | 50 | 6 | 33 | 12 | 12 | 12 | 12 | 6.62 | 85 Ohms | TOP=L2:L3=L2/L4:L6=L5/L7:BOTTOM=L7 |
| PCIE_TX_N60 | TX60-DIFF1 | PAIR | 1 | 5.38 | 5 | 10 | 5 | 50 | 6 | 33 | 12 | 12 | 12 | 12 | 6.62 | 85 Ohms | TOP=L2:L3=L2/L4:L6=L5/L7:BOTTOM=L7 |
| PCIE_TX_N60 | TX60-DIFF1 | PAIR | 2 | 5.5 | 5 | 10 | 5 | 50 | 6 | 20 | 12 | 12 | 12 | 12 | 7.5 | 85 Ohms | TOP=L2:L3=L2/L4:L6=L5/L7:BOTTOM=L7 |
| PCIE_TX_N60 | TX60-DIFF1 | PAIR | 3 | 5.5 | 5 | 10 | 5 | 50 | 6 | 20 | 12 | 12 | 12 | 12 | 7.5 | 85 Ohms | TOP=L2:L3=L2/L4:L6=L5/L7:BOTTOM=L7 |
| PCIE_TX_N60 | TX60-DIFF1 | PAIR | 4 | 5.5 | 5 | 10 | 5 | 50 | 6 | 20 | 12 | 12 | 12 | 12 | 7.5 | 85 Ohms | TOP=L2:L3=L2/L4:L6=L5/L7:BOTTOM=L7 |
| PCIE_TX_N60 | TX60-DIFF1 | PAIR | 5 | 5.5 | 5 | 10 | 5 | 50 | 6 | 20 | 12 | 12 | 12 | 12 | 7.5 | 85 Ohms | TOP=L2:L3=L2/L4:L6=L5/L7:BOTTOM=L7 |
| PCIE_TX_N60 | TX60-DIFF1 | PAIR | 6 | 5.5 | 5 | 10 | 5 | 50 | 6 | 20 | 12 | 12 | 12 | 12 | 7.5 | 85 Ohms | TOP=L2:L3=L2/L4:L6=L5/L7:BOTTOM=L7 |
| PCIE_TX_N60 | TX60-DIFF1 | PAIR | 7 | 5.5 | 5 | 10 | 5 | 50 | 6 | 20 | 12 | 12 | 12 | 12 | 7.5 | 85 Ohms | TOP=L2:L3=L2/L4:L6=L5/L7:BOTTOM=L7 |
| PCIE_TX_N60 | TX60-DIFF1 | PAIR | 8 | 5.38 | 5 | 10 | 5 | 50 | 6 | 33 | 12 | 12 | 12 | 12 | 6.62 | 85 Ohms | TOP=L2:L3=L2/L4:L6=L5/L7:BOTTOM=L7 |
| PCIE_TX_P60 | TX60-DIFF1 | PAIR | 1 | 5.38 | 5 | 10 | 5 | 50 | 6 | 33 | 12 | 12 | 12 | 12 | 6.62 | 85 Ohms | TOP=L2:L3=L2/L4:L6=L5/L7:BOTTOM=L7 |
| PCIE_TX_P60 | TX60-DIFF1 | PAIR | 2 | 5.5 | 5 | 10 | 5 | 50 | 6 | 20 | 12 | 12 | 12 | 12 | 7.5 | 85 Ohms | TOP=L2:L3=L2/L4:L6=L5/L7:BOTTOM=L7 |
| PCIE_TX_P60 | TX60-DIFF1 | PAIR | 3 | 5.5 | 5 | 10 | 5 | 50 | 6 | 20 | 12 | 12 | 12 | 12 | 7.5 | 85 Ohms | TOP=L2:L3=L2/L4:L6=L5/L7:BOTTOM=L7 |
| PCIE_TX_P60 | TX60-DIFF1 | PAIR | 4 | 5.5 | 5 | 10 | 5 | 50 | 6 | 20 | 12 | 12 | 12 | 12 | 7.5 | 85 Ohms | TOP=L2:L3=L2/L4:L6=L5/L7:BOTTOM=L7 |
| PCIE_TX_P60 | TX60-DIFF1 | PAIR | 5 | 5.5 | 5 | 10 | 5 | 50 | 6 | 20 | 12 | 12 | 12 | 12 | 7.5 | 85 Ohms | TOP=L2:L3=L2/L4:L6=L5/L7:BOTTOM=L7 |
| PCIE_TX_P60 | TX60-DIFF1 | PAIR | 6 | 5.5 | 5 | 10 | 5 | 50 | 6 | 20 | 12 | 12 | 12 | 12 | 7.5 | 85 Ohms | TOP=L2:L3=L2/L4:L6=L5/L7:BOTTOM=L7 |
| PCIE_TX_P60 | TX60-DIFF1 | PAIR | 7 | 5.5 | 5 | 10 | 5 | 50 | 6 | 20 | 12 | 12 | 12 | 12 | 7.5 | 85 Ohms | TOP=L2:L3=L2/L4:L6=L5/L7:BOTTOM=L7 |
| PCIE_TX_P60 | TX60-DIFF1 | PAIR | 8 | 5.38 | 5 | 10 | 5 | 50 | 6 | 33 | 12 | 12 | 12 | 12 | 6.62 | 85 Ohms | TOP=L2:L3=L2/L4:L6=L5/L7:BOTTOM=L7 |
| PCIE_TX_N61 | TX61-DIFF1 | PAIR | 1 | 5.38 | 5 | 10 | 5 | 50 | 6 | 33 | 12 | 12 | 12 | 12 | 6.62 | 85 Ohms | TOP=L2:L3=L2/L4:L6=L5/L7:BOTTOM=L7 |
| PCIE_TX_N61 | TX61-DIFF1 | PAIR | 2 | 5.5 | 5 | 10 | 5 | 50 | 6 | 20 | 12 | 12 | 12 | 12 | 7.5 | 85 Ohms | TOP=L2:L3=L2/L4:L6=L5/L7:BOTTOM=L7 |
| PCIE_TX_N61 | TX61-DIFF1 | PAIR | 3 | 5.5 | 5 | 10 | 5 | 50 | 6 | 20 | 12 | 12 | 12 | 12 | 7.5 | 85 Ohms | TOP=L2:L3=L2/L4:L6=L5/L7:BOTTOM=L7 |
| PCIE_TX_N61 | TX61-DIFF1 | PAIR | 4 | 5.5 | 5 | 10 | 5 | 50 | 6 | 20 | 12 | 12 | 12 | 12 | 7.5 | 85 Ohms | TOP=L2:L3=L2/L4:L6=L5/L7:BOTTOM=L7 |
| PCIE_TX_N61 | TX61-DIFF1 | PAIR | 5 | 5.5 | 5 | 10 | 5 | 50 | 6 | 20 | 12 | 12 | 12 | 12 | 7.5 | 85 Ohms | TOP=L2:L3=L2/L4:L6=L5/L7:BOTTOM=L7 |
| PCIE_TX_N61 | TX61-DIFF1 | PAIR | 6 | 5.5 | 5 | 10 | 5 | 50 | 6 | 20 | 12 | 12 | 12 | 12 | 7.5 | 85 Ohms | TOP=L2:L3=L2/L4:L6=L5/L7:BOTTOM=L7 |
| PCIE_TX_N61 | TX61-DIFF1 | PAIR | 7 | 5.5 | 5 | 10 | 5 | 50 | 6 | 20 | 12 | 12 | 12 | 12 | 7.5 | 85 Ohms | TOP=L2:L3=L2/L4:L6=L5/L7:BOTTOM=L7 |
| PCIE_TX_N61 | TX61-DIFF1 | PAIR | 8 | 5.38 | 5 | 10 | 5 | 50 | 6 | 33 | 12 | 12 | 12 | 12 | 6.62 | 85 Ohms | TOP=L2:L3=L2/L4:L6=L5/L7:BOTTOM=L7 |
| PCIE_TX_P61 | TX61-DIFF1 | PAIR | 1 | 5.38 | 5 | 10 | 5 | 50 | 6 | 33 | 12 | 12 | 12 | 12 | 6.62 | 85 Ohms | TOP=L2:L3=L2/L4:L6=L5/L7:BOTTOM=L7 |
| PCIE_TX_P61 | TX61-DIFF1 | PAIR | 2 | 5.5 | 5 | 10 | 5 | 50 | 6 | 20 | 12 | 12 | 12 | 12 | 7.5 | 85 Ohms | TOP=L2:L3=L2/L4:L6=L5/L7:BOTTOM=L7 |
| PCIE_TX_P61 | TX61-DIFF1 | PAIR | 3 | 5.5 | 5 | 10 | 5 | 50 | 6 | 20 | 12 | 12 | 12 | 12 | 7.5 | 85 Ohms | TOP=L2:L3=L2/L4:L6=L5/L7:BOTTOM=L7 |
| PCIE_TX_P61 | TX61-DIFF1 | PAIR | 4 | 5.5 | 5 | 10 | 5 | 50 | 6 | 20 | 12 | 12 | 12 | 12 | 7.5 | 85 Ohms | TOP=L2:L3=L2/L4:L6=L5/L7:BOTTOM=L7 |
| PCIE_TX_P61 | TX61-DIFF1 | PAIR | 5 | 5.5 | 5 | 10 | 5 | 50 | 6 | 20 | 12 | 12 | 12 | 12 | 7.5 | 85 Ohms | TOP=L2:L3=L2/L4:L6=L5/L7:BOTTOM=L7 |
| PCIE_TX_P61 | TX61-DIFF1 | PAIR | 6 | 5.5 | 5 | 10 | 5 | 50 | 6 | 20 | 12 | 12 | 12 | 12 | 7.5 | 85 Ohms | TOP=L2:L3=L2/L4:L6=L5/L7:BOTTOM=L7 |
| PCIE_TX_P61 | TX61-DIFF1 | PAIR | 7 | 5.5 | 5 | 10 | 5 | 50 | 6 | 20 | 12 | 12 | 12 | 12 | 7.5 | 85 Ohms | TOP=L2:L3=L2/L4:L6=L5/L7:BOTTOM=L7 |
| PCIE_TX_P61 | TX61-DIFF1 | PAIR | 8 | 5.38 | 5 | 10 | 5 | 50 | 6 | 33 | 12 | 12 | 12 | 12 | 6.62 | 85 Ohms | TOP=L2:L3=L2/L4:L6=L5/L7:BOTTOM=L7 |
| PCIE_TX_N62 | TX62-DIFF1 | PAIR | 1 | 5.38 | 5 | 10 | 5 | 50 | 6 | 33 | 12 | 12 | 12 | 12 | 6.62 | 85 Ohms | TOP=L2:L3=L2/L4:L6=L5/L7:BOTTOM=L7 |
| PCIE_TX_N62 | TX62-DIFF1 | PAIR | 2 | 5.5 | 5 | 10 | 5 | 50 | 6 | 20 | 12 | 12 | 12 | 12 | 7.5 | 85 Ohms | TOP=L2:L3=L2/L4:L6=L5/L7:BOTTOM=L7 |
| PCIE_TX_N62 | TX62-DIFF1 | PAIR | 3 | 5.5 | 5 | 10 | 5 | 50 | 6 | 20 | 12 | 12 | 12 | 12 | 7.5 | 85 Ohms | TOP=L2:L3=L2/L4:L6=L5/L7:BOTTOM=L7 |
| PCIE_TX_N62 | TX62-DIFF1 | PAIR | 4 | 5.5 | 5 | 10 | 5 | 50 | 6 | 20 | 12 | 12 | 12 | 12 | 7.5 | 85 Ohms | TOP=L2:L3=L2/L4:L6=L5/L7:BOTTOM=L7 |
| PCIE_TX_N62 | TX62-DIFF1 | PAIR | 5 | 5.5 | 5 | 10 | 5 | 50 | 6 | 20 | 12 | 12 | 12 | 12 | 7.5 | 85 Ohms | TOP=L2:L3=L2/L4:L6=L5/L7:BOTTOM=L7 |
| PCIE_TX_N62 | TX62-DIFF1 | PAIR | 6 | 5.5 | 5 | 10 | 5 | 50 | 6 | 20 | 12 | 12 | 12 | 12 | 7.5 | 85 Ohms | TOP=L2:L3=L2/L4:L6=L5/L7:BOTTOM=L7 |
| PCIE_TX_N62 | TX62-DIFF1 | PAIR | 7 | 5.5 | 5 | 10 | 5 | 50 | 6 | 20 | 12 | 12 | 12 | 12 | 7.5 | 85 Ohms | TOP=L2:L3=L2/L4:L6=L5/L7:BOTTOM=L7 |
| PCIE_TX_N62 | TX62-DIFF1 | PAIR | 8 | 5.38 | 5 | 10 | 5 | 50 | 6 | 33 | 12 | 12 | 12 | 12 | 6.62 | 85 Ohms | TOP=L2:L3=L2/L4:L6=L5/L7:BOTTOM=L7 |
| PCIE_TX_P62 | TX62-DIFF1 | PAIR | 1 | 5.38 | 5 | 10 | 5 | 50 | 6 | 33 | 12 | 12 | 12 | 12 | 6.62 | 85 Ohms | TOP=L2:L3=L2/L4:L6=L5/L7:BOTTOM=L7 |
| PCIE_TX_P62 | TX62-DIFF1 | PAIR | 2 | 5.5 | 5 | 10 | 5 | 50 | 6 | 20 | 12 | 12 | 12 | 12 | 7.5 | 85 Ohms | TOP=L2:L3=L2/L4:L6=L5/L7:BOTTOM=L7 |
| PCIE_TX_P62 | TX62-DIFF1 | PAIR | 3 | 5.5 | 5 | 10 | 5 | 50 | 6 | 20 | 12 | 12 | 12 | 12 | 7.5 | 85 Ohms | TOP=L2:L3=L2/L4:L6=L5/L7:BOTTOM=L7 |
| PCIE_TX_P62 | TX62-DIFF1 | PAIR | 4 | 5.5 | 5 | 10 | 5 | 50 | 6 | 20 | 12 | 12 | 12 | 12 | 7.5 | 85 Ohms | TOP=L2:L3=L2/L4:L6=L5/L7:BOTTOM=L7 |
| PCIE_TX_P62 | TX62-DIFF1 | PAIR | 5 | 5.5 | 5 | 10 | 5 | 50 | 6 | 20 | 12 | 12 | 12 | 12 | 7.5 | 85 Ohms | TOP=L2:L3=L2/L4:L6=L5/L7:BOTTOM=L7 |
| PCIE_TX_P62 | TX62-DIFF1 | PAIR | 6 | 5.5 | 5 | 10 | 5 | 50 | 6 | 20 | 12 | 12 | 12 | 12 | 7.5 | 85 Ohms | TOP=L2:L3=L2/L4:L6=L5/L7:BOTTOM=L7 |
| PCIE_TX_P62 | TX62-DIFF1 | PAIR | 7 | 5.5 | 5 | 10 | 5 | 50 | 6 | 20 | 12 | 12 | 12 | 12 | 7.5 | 85 Ohms | TOP=L2:L3=L2/L4:L6=L5/L7:BOTTOM=L7 |
| PCIE_TX_P62 | TX62-DIFF1 | PAIR | 8 | 5.38 | 5 | 10 | 5 | 50 | 6 | 33 | 12 | 12 | 12 | 12 | 6.62 | 85 Ohms | TOP=L2:L3=L2/L4:L6=L5/L7:BOTTOM=L7 |
| PCIE_TX_N63 | TX63-DIFF1 | PAIR | 1 | 5.38 | 5 | 10 | 5 | 50 | 6 | 33 | 12 | 12 | 12 | 12 | 6.62 | 85 Ohms | TOP=L2:L3=L2/L4:L6=L5/L7:BOTTOM=L7 |
| PCIE_TX_N63 | TX63-DIFF1 | PAIR | 2 | 5.5 | 5 | 10 | 5 | 50 | 6 | 20 | 12 | 12 | 12 | 12 | 7.5 | 85 Ohms | TOP=L2:L3=L2/L4:L6=L5/L7:BOTTOM=L7 |
| PCIE_TX_N63 | TX63-DIFF1 | PAIR | 3 | 5.5 | 5 | 10 | 5 | 50 | 6 | 20 | 12 | 12 | 12 | 12 | 7.5 | 85 Ohms | TOP=L2:L3=L2/L4:L6=L5/L7:BOTTOM=L7 |
| PCIE_TX_N63 | TX63-DIFF1 | PAIR | 4 | 5.5 | 5 | 10 | 5 | 50 | 6 | 20 | 12 | 12 | 12 | 12 | 7.5 | 85 Ohms | TOP=L2:L3=L2/L4:L6=L5/L7:BOTTOM=L7 |
| PCIE_TX_N63 | TX63-DIFF1 | PAIR | 5 | 5.5 | 5 | 10 | 5 | 50 | 6 | 20 | 12 | 12 | 12 | 12 | 7.5 | 85 Ohms | TOP=L2:L3=L2/L4:L6=L5/L7:BOTTOM=L7 |
| PCIE_TX_N63 | TX63-DIFF1 | PAIR | 6 | 5.5 | 5 | 10 | 5 | 50 | 6 | 20 | 12 | 12 | 12 | 12 | 7.5 | 85 Ohms | TOP=L2:L3=L2/L4:L6=L5/L7:BOTTOM=L7 |
| PCIE_TX_N63 | TX63-DIFF1 | PAIR | 7 | 5.5 | 5 | 10 | 5 | 50 | 6 | 20 | 12 | 12 | 12 | 12 | 7.5 | 85 Ohms | TOP=L2:L3=L2/L4:L6=L5/L7:BOTTOM=L7 |
| PCIE_TX_N63 | TX63-DIFF1 | PAIR | 8 | 5.38 | 5 | 10 | 5 | 50 | 6 | 33 | 12 | 12 | 12 | 12 | 6.62 | 85 Ohms | TOP=L2:L3=L2/L4:L6=L5/L7:BOTTOM=L7 |
| PCIE_TX_P63 | TX63-DIFF1 | PAIR | 1 | 5.38 | 5 | 10 | 5 | 50 | 6 | 33 | 12 | 12 | 12 | 12 | 6.62 | 85 Ohms | TOP=L2:L3=L2/L4:L6=L5/L7:BOTTOM=L7 |
| PCIE_TX_P63 | TX63-DIFF1 | PAIR | 2 | 5.5 | 5 | 10 | 5 | 50 | 6 | 20 | 12 | 12 | 12 | 12 | 7.5 | 85 Ohms | TOP=L2:L3=L2/L4:L6=L5/L7:BOTTOM=L7 |
| PCIE_TX_P63 | TX63-DIFF1 | PAIR | 3 | 5.5 | 5 | 10 | 5 | 50 | 6 | 20 | 12 | 12 | 12 | 12 | 7.5 | 85 Ohms | TOP=L2:L3=L2/L4:L6=L5/L7:BOTTOM=L7 |
| PCIE_TX_P63 | TX63-DIFF1 | PAIR | 4 | 5.5 | 5 | 10 | 5 | 50 | 6 | 20 | 12 | 12 | 12 | 12 | 7.5 | 85 Ohms | TOP=L2:L3=L2/L4:L6=L5/L7:BOTTOM=L7 |
| PCIE_TX_P63 | TX63-DIFF1 | PAIR | 5 | 5.5 | 5 | 10 | 5 | 50 | 6 | 20 | 12 | 12 | 12 | 12 | 7.5 | 85 Ohms | TOP=L2:L3=L2/L4:L6=L5/L7:BOTTOM=L7 |
| PCIE_TX_P63 | TX63-DIFF1 | PAIR | 6 | 5.5 | 5 | 10 | 5 | 50 | 6 | 20 | 12 | 12 | 12 | 12 | 7.5 | 85 Ohms | TOP=L2:L3=L2/L4:L6=L5/L7:BOTTOM=L7 |
| PCIE_TX_P63 | TX63-DIFF1 | PAIR | 7 | 5.5 | 5 | 10 | 5 | 50 | 6 | 20 | 12 | 12 | 12 | 12 | 7.5 | 85 Ohms | TOP=L2:L3=L2/L4:L6=L5/L7:BOTTOM=L7 |
| PCIE_TX_P63 | TX63-DIFF1 | PAIR | 8 | 5.38 | 5 | 10 | 5 | 50 | 6 | 33 | 12 | 12 | 12 | 12 | 6.62 | 85 Ohms | TOP=L2:L3=L2/L4:L6=L5/L7:BOTTOM=L7 |
| PCIE_TX_N64 | TX64-DIFF1 | PAIR | 1 | 5.38 | 5 | 10 | 5 | 50 | 6 | 33 | 12 | 12 | 12 | 12 | 6.62 | 85 Ohms | TOP=L2:L3=L2/L4:L6=L5/L7:BOTTOM=L7 |
| PCIE_TX_N64 | TX64-DIFF1 | PAIR | 2 | 5.5 | 5 | 10 | 5 | 50 | 6 | 20 | 12 | 12 | 12 | 12 | 7.5 | 85 Ohms | TOP=L2:L3=L2/L4:L6=L5/L7:BOTTOM=L7 |
| PCIE_TX_N64 | TX64-DIFF1 | PAIR | 3 | 5.5 | 5 | 10 | 5 | 50 | 6 | 20 | 12 | 12 | 12 | 12 | 7.5 | 85 Ohms | TOP=L2:L3=L2/L4:L6=L5/L7:BOTTOM=L7 |
| PCIE_TX_N64 | TX64-DIFF1 | PAIR | 4 | 5.5 | 5 | 10 | 5 | 50 | 6 | 20 | 12 | 12 | 12 | 12 | 7.5 | 85 Ohms | TOP=L2:L3=L2/L4:L6=L5/L7:BOTTOM=L7 |
| PCIE_TX_N64 | TX64-DIFF1 | PAIR | 5 | 5.5 | 5 | 10 | 5 | 50 | 6 | 20 | 12 | 12 | 12 | 12 | 7.5 | 85 Ohms | TOP=L2:L3=L2/L4:L6=L5/L7:BOTTOM=L7 |
| PCIE_TX_N64 | TX64-DIFF1 | PAIR | 6 | 5.5 | 5 | 10 | 5 | 50 | 6 | 20 | 12 | 12 | 12 | 12 | 7.5 | 85 Ohms | TOP=L2:L3=L2/L4:L6=L5/L7:BOTTOM=L7 |
| PCIE_TX_N64 | TX64-DIFF1 | PAIR | 7 | 5.5 | 5 | 10 | 5 | 50 | 6 | 20 | 12 | 12 | 12 | 12 | 7.5 | 85 Ohms | TOP=L2:L3=L2/L4:L6=L5/L7:BOTTOM=L7 |
| PCIE_TX_N64 | TX64-DIFF1 | PAIR | 8 | 5.38 | 5 | 10 | 5 | 50 | 6 | 33 | 12 | 12 | 12 | 12 | 6.62 | 85 Ohms | TOP=L2:L3=L2/L4:L6=L5/L7:BOTTOM=L7 |
| PCIE_TX_P64 | TX64-DIFF1 | PAIR | 1 | 5.38 | 5 | 10 | 5 | 50 | 6 | 33 | 12 | 12 | 12 | 12 | 6.62 | 85 Ohms | TOP=L2:L3=L2/L4:L6=L5/L7:BOTTOM=L7 |
| PCIE_TX_P64 | TX64-DIFF1 | PAIR | 2 | 5.5 | 5 | 10 | 5 | 50 | 6 | 20 | 12 | 12 | 12 | 12 | 7.5 | 85 Ohms | TOP=L2:L3=L2/L4:L6=L5/L7:BOTTOM=L7 |
| PCIE_TX_P64 | TX64-DIFF1 | PAIR | 3 | 5.5 | 5 | 10 | 5 | 50 | 6 | 20 | 12 | 12 | 12 | 12 | 7.5 | 85 Ohms | TOP=L2:L3=L2/L4:L6=L5/L7:BOTTOM=L7 |
| PCIE_TX_P64 | TX64-DIFF1 | PAIR | 4 | 5.5 | 5 | 10 | 5 | 50 | 6 | 20 | 12 | 12 | 12 | 12 | 7.5 | 85 Ohms | TOP=L2:L3=L2/L4:L6=L5/L7:BOTTOM=L7 |
| PCIE_TX_P64 | TX64-DIFF1 | PAIR | 5 | 5.5 | 5 | 10 | 5 | 50 | 6 | 20 | 12 | 12 | 12 | 12 | 7.5 | 85 Ohms | TOP=L2:L3=L2/L4:L6=L5/L7:BOTTOM=L7 |
| PCIE_TX_P64 | TX64-DIFF1 | PAIR | 6 | 5.5 | 5 | 10 | 5 | 50 | 6 | 20 | 12 | 12 | 12 | 12 | 7.5 | 85 Ohms | TOP=L2:L3=L2/L4:L6=L5/L7:BOTTOM=L7 |
| PCIE_TX_P64 | TX64-DIFF1 | PAIR | 7 | 5.5 | 5 | 10 | 5 | 50 | 6 | 20 | 12 | 12 | 12 | 12 | 7.5 | 85 Ohms | TOP=L2:L3=L2/L4:L6=L5/L7:BOTTOM=L7 |
| PCIE_TX_P64 | TX64-DIFF1 | PAIR | 8 | 5.38 | 5 | 10 | 5 | 50 | 6 | 33 | 12 | 12 | 12 | 12 | 6.62 | 85 Ohms | TOP=L2:L3=L2/L4:L6=L5/L7:BOTTOM=L7 |
| PCIE_TX_N65 | TX65-DIFF1 | PAIR | 1 | 5.38 | 5 | 10 | 5 | 50 | 6 | 33 | 12 | 12 | 12 | 12 | 6.62 | 85 Ohms | TOP=L2:L3=L2/L4:L6=L5/L7:BOTTOM=L7 |
| PCIE_TX_N65 | TX65-DIFF1 | PAIR | 2 | 5.5 | 5 | 10 | 5 | 50 | 6 | 20 | 12 | 12 | 12 | 12 | 7.5 | 85 Ohms | TOP=L2:L3=L2/L4:L6=L5/L7:BOTTOM=L7 |
| PCIE_TX_N65 | TX65-DIFF1 | PAIR | 3 | 5.5 | 5 | 10 | 5 | 50 | 6 | 20 | 12 | 12 | 12 | 12 | 7.5 | 85 Ohms | TOP=L2:L3=L2/L4:L6=L5/L7:BOTTOM=L7 |
| PCIE_TX_N65 | TX65-DIFF1 | PAIR | 4 | 5.5 | 5 | 10 | 5 | 50 | 6 | 20 | 12 | 12 | 12 | 12 | 7.5 | 85 Ohms | TOP=L2:L3=L2/L4:L6=L5/L7:BOTTOM=L7 |
| PCIE_TX_N65 | TX65-DIFF1 | PAIR | 5 | 5.5 | 5 | 10 | 5 | 50 | 6 | 20 | 12 | 12 | 12 | 12 | 7.5 | 85 Ohms | TOP=L2:L3=L2/L4:L6=L5/L7:BOTTOM=L7 |
| PCIE_TX_N65 | TX65-DIFF1 | PAIR | 6 | 5.5 | 5 | 10 | 5 | 50 | 6 | 20 | 12 | 12 | 12 | 12 | 7.5 | 85 Ohms | TOP=L2:L3=L2/L4:L6=L5/L7:BOTTOM=L7 |
| PCIE_TX_N65 | TX65-DIFF1 | PAIR | 7 | 5.5 | 5 | 10 | 5 | 50 | 6 | 20 | 12 | 12 | 12 | 12 | 7.5 | 85 Ohms | TOP=L2:L3=L2/L4:L6=L5/L7:BOTTOM=L7 |
| PCIE_TX_N65 | TX65-DIFF1 | PAIR | 8 | 5.38 | 5 | 10 | 5 | 50 | 6 | 33 | 12 | 12 | 12 | 12 | 6.62 | 85 Ohms | TOP=L2:L3=L2/L4:L6=L5/L7:BOTTOM=L7 |
| PCIE_TX_P65 | TX65-DIFF1 | PAIR | 1 | 5.38 | 5 | 10 | 5 | 50 | 6 | 33 | 12 | 12 | 12 | 12 | 6.62 | 85 Ohms | TOP=L2:L3=L2/L4:L6=L5/L7:BOTTOM=L7 |
| PCIE_TX_P65 | TX65-DIFF1 | PAIR | 2 | 5.5 | 5 | 10 | 5 | 50 | 6 | 20 | 12 | 12 | 12 | 12 | 7.5 | 85 Ohms | TOP=L2:L3=L2/L4:L6=L5/L7:BOTTOM=L7 |
| PCIE_TX_P65 | TX65-DIFF1 | PAIR | 3 | 5.5 | 5 | 10 | 5 | 50 | 6 | 20 | 12 | 12 | 12 | 12 | 7.5 | 85 Ohms | TOP=L2:L3=L2/L4:L6=L5/L7:BOTTOM=L7 |
| PCIE_TX_P65 | TX65-DIFF1 | PAIR | 4 | 5.5 | 5 | 10 | 5 | 50 | 6 | 20 | 12 | 12 | 12 | 12 | 7.5 | 85 Ohms | TOP=L2:L3=L2/L4:L6=L5/L7:BOTTOM=L7 |
| PCIE_TX_P65 | TX65-DIFF1 | PAIR | 5 | 5.5 | 5 | 10 | 5 | 50 | 6 | 20 | 12 | 12 | 12 | 12 | 7.5 | 85 Ohms | TOP=L2:L3=L2/L4:L6=L5/L7:BOTTOM=L7 |
| PCIE_TX_P65 | TX65-DIFF1 | PAIR | 6 | 5.5 | 5 | 10 | 5 | 50 | 6 | 20 | 12 | 12 | 12 | 12 | 7.5 | 85 Ohms | TOP=L2:L3=L2/L4:L6=L5/L7:BOTTOM=L7 |
| PCIE_TX_P65 | TX65-DIFF1 | PAIR | 7 | 5.5 | 5 | 10 | 5 | 50 | 6 | 20 | 12 | 12 | 12 | 12 | 7.5 | 85 Ohms | TOP=L2:L3=L2/L4:L6=L5/L7:BOTTOM=L7 |
| PCIE_TX_P65 | TX65-DIFF1 | PAIR | 8 | 5.38 | 5 | 10 | 5 | 50 | 6 | 33 | 12 | 12 | 12 | 12 | 6.62 | 85 Ohms | TOP=L2:L3=L2/L4:L6=L5/L7:BOTTOM=L7 |
| PCIE_TX_N66 | TX66-DIFF1 | PAIR | 1 | 5.38 | 5 | 10 | 5 | 50 | 6 | 33 | 12 | 12 | 12 | 12 | 6.62 | 85 Ohms | TOP=L2:L3=L2/L4:L6=L5/L7:BOTTOM=L7 |
| PCIE_TX_N66 | TX66-DIFF1 | PAIR | 2 | 5.5 | 5 | 10 | 5 | 50 | 6 | 20 | 12 | 12 | 12 | 12 | 7.5 | 85 Ohms | TOP=L2:L3=L2/L4:L6=L5/L7:BOTTOM=L7 |
| PCIE_TX_N66 | TX66-DIFF1 | PAIR | 3 | 5.5 | 5 | 10 | 5 | 50 | 6 | 20 | 12 | 12 | 12 | 12 | 7.5 | 85 Ohms | TOP=L2:L3=L2/L4:L6=L5/L7:BOTTOM=L7 |
| PCIE_TX_N66 | TX66-DIFF1 | PAIR | 4 | 5.5 | 5 | 10 | 5 | 50 | 6 | 20 | 12 | 12 | 12 | 12 | 7.5 | 85 Ohms | TOP=L2:L3=L2/L4:L6=L5/L7:BOTTOM=L7 |
| PCIE_TX_N66 | TX66-DIFF1 | PAIR | 5 | 5.5 | 5 | 10 | 5 | 50 | 6 | 20 | 12 | 12 | 12 | 12 | 7.5 | 85 Ohms | TOP=L2:L3=L2/L4:L6=L5/L7:BOTTOM=L7 |
| PCIE_TX_N66 | TX66-DIFF1 | PAIR | 6 | 5.5 | 5 | 10 | 5 | 50 | 6 | 20 | 12 | 12 | 12 | 12 | 7.5 | 85 Ohms | TOP=L2:L3=L2/L4:L6=L5/L7:BOTTOM=L7 |
| PCIE_TX_N66 | TX66-DIFF1 | PAIR | 7 | 5.5 | 5 | 10 | 5 | 50 | 6 | 20 | 12 | 12 | 12 | 12 | 7.5 | 85 Ohms | TOP=L2:L3=L2/L4:L6=L5/L7:BOTTOM=L7 |
| PCIE_TX_N66 | TX66-DIFF1 | PAIR | 8 | 5.38 | 5 | 10 | 5 | 50 | 6 | 33 | 12 | 12 | 12 | 12 | 6.62 | 85 Ohms | TOP=L2:L3=L2/L4:L6=L5/L7:BOTTOM=L7 |
| PCIE_TX_P66 | TX66-DIFF1 | PAIR | 1 | 5.38 | 5 | 10 | 5 | 50 | 6 | 33 | 12 | 12 | 12 | 12 | 6.62 | 85 Ohms | TOP=L2:L3=L2/L4:L6=L5/L7:BOTTOM=L7 |
| PCIE_TX_P66 | TX66-DIFF1 | PAIR | 2 | 5.5 | 5 | 10 | 5 | 50 | 6 | 20 | 12 | 12 | 12 | 12 | 7.5 | 85 Ohms | TOP=L2:L3=L2/L4:L6=L5/L7:BOTTOM=L7 |
| PCIE_TX_P66 | TX66-DIFF1 | PAIR | 3 | 5.5 | 5 | 10 | 5 | 50 | 6 | 20 | 12 | 12 | 12 | 12 | 7.5 | 85 Ohms | TOP=L2:L3=L2/L4:L6=L5/L7:BOTTOM=L7 |
| PCIE_TX_P66 | TX66-DIFF1 | PAIR | 4 | 5.5 | 5 | 10 | 5 | 50 | 6 | 20 | 12 | 12 | 12 | 12 | 7.5 | 85 Ohms | TOP=L2:L3=L2/L4:L6=L5/L7:BOTTOM=L7 |
| PCIE_TX_P66 | TX66-DIFF1 | PAIR | 5 | 5.5 | 5 | 10 | 5 | 50 | 6 | 20 | 12 | 12 | 12 | 12 | 7.5 | 85 Ohms | TOP=L2:L3=L2/L4:L6=L5/L7:BOTTOM=L7 |
| PCIE_TX_P66 | TX66-DIFF1 | PAIR | 6 | 5.5 | 5 | 10 | 5 | 50 | 6 | 20 | 12 | 12 | 12 | 12 | 7.5 | 85 Ohms | TOP=L2:L3=L2/L4:L6=L5/L7:BOTTOM=L7 |
| PCIE_TX_P66 | TX66-DIFF1 | PAIR | 7 | 5.5 | 5 | 10 | 5 | 50 | 6 | 20 | 12 | 12 | 12 | 12 | 7.5 | 85 Ohms | TOP=L2:L3=L2/L4:L6=L5/L7:BOTTOM=L7 |
| PCIE_TX_P66 | TX66-DIFF1 | PAIR | 8 | 5.38 | 5 | 10 | 5 | 50 | 6 | 33 | 12 | 12 | 12 | 12 | 6.62 | 85 Ohms | TOP=L2:L3=L2/L4:L6=L5/L7:BOTTOM=L7 |
| PCIE_TX_N67 | TX67-DIFF1 | PAIR | 1 | 5.38 | 5 | 10 | 5 | 50 | 6 | 33 | 12 | 12 | 12 | 12 | 6.62 | 85 Ohms | TOP=L2:L3=L2/L4:L6=L5/L7:BOTTOM=L7 |
| PCIE_TX_N67 | TX67-DIFF1 | PAIR | 2 | 5.5 | 5 | 10 | 5 | 50 | 6 | 20 | 12 | 12 | 12 | 12 | 7.5 | 85 Ohms | TOP=L2:L3=L2/L4:L6=L5/L7:BOTTOM=L7 |
| PCIE_TX_N67 | TX67-DIFF1 | PAIR | 3 | 5.5 | 5 | 10 | 5 | 50 | 6 | 20 | 12 | 12 | 12 | 12 | 7.5 | 85 Ohms | TOP=L2:L3=L2/L4:L6=L5/L7:BOTTOM=L7 |
| PCIE_TX_N67 | TX67-DIFF1 | PAIR | 4 | 5.5 | 5 | 10 | 5 | 50 | 6 | 20 | 12 | 12 | 12 | 12 | 7.5 | 85 Ohms | TOP=L2:L3=L2/L4:L6=L5/L7:BOTTOM=L7 |
| PCIE_TX_N67 | TX67-DIFF1 | PAIR | 5 | 5.5 | 5 | 10 | 5 | 50 | 6 | 20 | 12 | 12 | 12 | 12 | 7.5 | 85 Ohms | TOP=L2:L3=L2/L4:L6=L5/L7:BOTTOM=L7 |
| PCIE_TX_N67 | TX67-DIFF1 | PAIR | 6 | 5.5 | 5 | 10 | 5 | 50 | 6 | 20 | 12 | 12 | 12 | 12 | 7.5 | 85 Ohms | TOP=L2:L3=L2/L4:L6=L5/L7:BOTTOM=L7 |
| PCIE_TX_N67 | TX67-DIFF1 | PAIR | 7 | 5.5 | 5 | 10 | 5 | 50 | 6 | 20 | 12 | 12 | 12 | 12 | 7.5 | 85 Ohms | TOP=L2:L3=L2/L4:L6=L5/L7:BOTTOM=L7 |
| PCIE_TX_N67 | TX67-DIFF1 | PAIR | 8 | 5.38 | 5 | 10 | 5 | 50 | 6 | 33 | 12 | 12 | 12 | 12 | 6.62 | 85 Ohms | TOP=L2:L3=L2/L4:L6=L5/L7:BOTTOM=L7 |
| PCIE_TX_P67 | TX67-DIFF1 | PAIR | 1 | 5.38 | 5 | 10 | 5 | 50 | 6 | 33 | 12 | 12 | 12 | 12 | 6.62 | 85 Ohms | TOP=L2:L3=L2/L4:L6=L5/L7:BOTTOM=L7 |
| PCIE_TX_P67 | TX67-DIFF1 | PAIR | 2 | 5.5 | 5 | 10 | 5 | 50 | 6 | 20 | 12 | 12 | 12 | 12 | 7.5 | 85 Ohms | TOP=L2:L3=L2/L4:L6=L5/L7:BOTTOM=L7 |
| PCIE_TX_P67 | TX67-DIFF1 | PAIR | 3 | 5.5 | 5 | 10 | 5 | 50 | 6 | 20 | 12 | 12 | 12 | 12 | 7.5 | 85 Ohms | TOP=L2:L3=L2/L4:L6=L5/L7:BOTTOM=L7 |
| PCIE_TX_P67 | TX67-DIFF1 | PAIR | 4 | 5.5 | 5 | 10 | 5 | 50 | 6 | 20 | 12 | 12 | 12 | 12 | 7.5 | 85 Ohms | TOP=L2:L3=L2/L4:L6=L5/L7:BOTTOM=L7 |
| PCIE_TX_P67 | TX67-DIFF1 | PAIR | 5 | 5.5 | 5 | 10 | 5 | 50 | 6 | 20 | 12 | 12 | 12 | 12 | 7.5 | 85 Ohms | TOP=L2:L3=L2/L4:L6=L5/L7:BOTTOM=L7 |
| PCIE_TX_P67 | TX67-DIFF1 | PAIR | 6 | 5.5 | 5 | 10 | 5 | 50 | 6 | 20 | 12 | 12 | 12 | 12 | 7.5 | 85 Ohms | TOP=L2:L3=L2/L4:L6=L5/L7:BOTTOM=L7 |
| PCIE_TX_P67 | TX67-DIFF1 | PAIR | 7 | 5.5 | 5 | 10 | 5 | 50 | 6 | 20 | 12 | 12 | 12 | 12 | 7.5 | 85 Ohms | TOP=L2:L3=L2/L4:L6=L5/L7:BOTTOM=L7 |
| PCIE_TX_P67 | TX67-DIFF1 | PAIR | 8 | 5.38 | 5 | 10 | 5 | 50 | 6 | 33 | 12 | 12 | 12 | 12 | 6.62 | 85 Ohms | TOP=L2:L3=L2/L4:L6=L5/L7:BOTTOM=L7 |
| PCIE_TX_N68 | TX68-DIFF1 | PAIR | 1 | 5.38 | 5 | 10 | 5 | 50 | 6 | 33 | 12 | 12 | 12 | 12 | 6.62 | 85 Ohms | TOP=L2:L3=L2/L4:L6=L5/L7:BOTTOM=L7 |
| PCIE_TX_N68 | TX68-DIFF1 | PAIR | 2 | 5.5 | 5 | 10 | 5 | 50 | 6 | 20 | 12 | 12 | 12 | 12 | 7.5 | 85 Ohms | TOP=L2:L3=L2/L4:L6=L5/L7:BOTTOM=L7 |
| PCIE_TX_N68 | TX68-DIFF1 | PAIR | 3 | 5.5 | 5 | 10 | 5 | 50 | 6 | 20 | 12 | 12 | 12 | 12 | 7.5 | 85 Ohms | TOP=L2:L3=L2/L4:L6=L5/L7:BOTTOM=L7 |
| PCIE_TX_N68 | TX68-DIFF1 | PAIR | 4 | 5.5 | 5 | 10 | 5 | 50 | 6 | 20 | 12 | 12 | 12 | 12 | 7.5 | 85 Ohms | TOP=L2:L3=L2/L4:L6=L5/L7:BOTTOM=L7 |
| PCIE_TX_N68 | TX68-DIFF1 | PAIR | 5 | 5.5 | 5 | 10 | 5 | 50 | 6 | 20 | 12 | 12 | 12 | 12 | 7.5 | 85 Ohms | TOP=L2:L3=L2/L4:L6=L5/L7:BOTTOM=L7 |
| PCIE_TX_N68 | TX68-DIFF1 | PAIR | 6 | 5.5 | 5 | 10 | 5 | 50 | 6 | 20 | 12 | 12 | 12 | 12 | 7.5 | 85 Ohms | TOP=L2:L3=L2/L4:L6=L5/L7:BOTTOM=L7 |
| PCIE_TX_N68 | TX68-DIFF1 | PAIR | 7 | 5.5 | 5 | 10 | 5 | 50 | 6 | 20 | 12 | 12 | 12 | 12 | 7.5 | 85 Ohms | TOP=L2:L3=L2/L4:L6=L5/L7:BOTTOM=L7 |
| PCIE_TX_N68 | TX68-DIFF1 | PAIR | 8 | 5.38 | 5 | 10 | 5 | 50 | 6 | 33 | 12 | 12 | 12 | 12 | 6.62 | 85 Ohms | TOP=L2:L3=L2/L4:L6=L5/L7:BOTTOM=L7 |
| PCIE_TX_P68 | TX68-DIFF1 | PAIR | 1 | 5.38 | 5 | 10 | 5 | 50 | 6 | 33 | 12 | 12 | 12 | 12 | 6.62 | 85 Ohms | TOP=L2:L3=L2/L4:L6=L5/L7:BOTTOM=L7 |
| PCIE_TX_P68 | TX68-DIFF1 | PAIR | 2 | 5.5 | 5 | 10 | 5 | 50 | 6 | 20 | 12 | 12 | 12 | 12 | 7.5 | 85 Ohms | TOP=L2:L3=L2/L4:L6=L5/L7:BOTTOM=L7 |
| PCIE_TX_P68 | TX68-DIFF1 | PAIR | 3 | 5.5 | 5 | 10 | 5 | 50 | 6 | 20 | 12 | 12 | 12 | 12 | 7.5 | 85 Ohms | TOP=L2:L3=L2/L4:L6=L5/L7:BOTTOM=L7 |
| PCIE_TX_P68 | TX68-DIFF1 | PAIR | 4 | 5.5 | 5 | 10 | 5 | 50 | 6 | 20 | 12 | 12 | 12 | 12 | 7.5 | 85 Ohms | TOP=L2:L3=L2/L4:L6=L5/L7:BOTTOM=L7 |
| PCIE_TX_P68 | TX68-DIFF1 | PAIR | 5 | 5.5 | 5 | 10 | 5 | 50 | 6 | 20 | 12 | 12 | 12 | 12 | 7.5 | 85 Ohms | TOP=L2:L3=L2/L4:L6=L5/L7:BOTTOM=L7 |
| PCIE_TX_P68 | TX68-DIFF1 | PAIR | 6 | 5.5 | 5 | 10 | 5 | 50 | 6 | 20 | 12 | 12 | 12 | 12 | 7.5 | 85 Ohms | TOP=L2:L3=L2/L4:L6=L5/L7:BOTTOM=L7 |
| PCIE_TX_P68 | TX68-DIFF1 | PAIR | 7 | 5.5 | 5 | 10 | 5 | 50 | 6 | 20 | 12 | 12 | 12 | 12 | 7.5 | 85 Ohms | TOP=L2:L3=L2/L4:L6=L5/L7:BOTTOM=L7 |
| PCIE_TX_P68 | TX68-DIFF1 | PAIR | 8 | 5.38 | 5 | 10 | 5 | 50 | 6 | 33 | 12 | 12 | 12 | 12 | 6.62 | 85 Ohms | TOP=L2:L3=L2/L4:L6=L5/L7:BOTTOM=L7 |
| PCIE_TX_N69 | TX69-DIFF1 | PAIR | 1 | 5.38 | 5 | 10 | 5 | 50 | 6 | 33 | 12 | 12 | 12 | 12 | 6.62 | 85 Ohms | TOP=L2:L3=L2/L4:L6=L5/L7:BOTTOM=L7 |
| PCIE_TX_N69 | TX69-DIFF1 | PAIR | 2 | 5.5 | 5 | 10 | 5 | 50 | 6 | 20 | 12 | 12 | 12 | 12 | 7.5 | 85 Ohms | TOP=L2:L3=L2/L4:L6=L5/L7:BOTTOM=L7 |
| PCIE_TX_N69 | TX69-DIFF1 | PAIR | 3 | 5.5 | 5 | 10 | 5 | 50 | 6 | 20 | 12 | 12 | 12 | 12 | 7.5 | 85 Ohms | TOP=L2:L3=L2/L4:L6=L5/L7:BOTTOM=L7 |
| PCIE_TX_N69 | TX69-DIFF1 | PAIR | 4 | 5.5 | 5 | 10 | 5 | 50 | 6 | 20 | 12 | 12 | 12 | 12 | 7.5 | 85 Ohms | TOP=L2:L3=L2/L4:L6=L5/L7:BOTTOM=L7 |
| PCIE_TX_N69 | TX69-DIFF1 | PAIR | 5 | 5.5 | 5 | 10 | 5 | 50 | 6 | 20 | 12 | 12 | 12 | 12 | 7.5 | 85 Ohms | TOP=L2:L3=L2/L4:L6=L5/L7:BOTTOM=L7 |
| PCIE_TX_N69 | TX69-DIFF1 | PAIR | 6 | 5.5 | 5 | 10 | 5 | 50 | 6 | 20 | 12 | 12 | 12 | 12 | 7.5 | 85 Ohms | TOP=L2:L3=L2/L4:L6=L5/L7:BOTTOM=L7 |
| PCIE_TX_N69 | TX69-DIFF1 | PAIR | 7 | 5.5 | 5 | 10 | 5 | 50 | 6 | 20 | 12 | 12 | 12 | 12 | 7.5 | 85 Ohms | TOP=L2:L3=L2/L4:L6=L5/L7:BOTTOM=L7 |
| PCIE_TX_N69 | TX69-DIFF1 | PAIR | 8 | 5.38 | 5 | 10 | 5 | 50 | 6 | 33 | 12 | 12 | 12 | 12 | 6.62 | 85 Ohms | TOP=L2:L3=L2/L4:L6=L5/L7:BOTTOM=L7 |
| PCIE_TX_P69 | TX69-DIFF1 | PAIR | 1 | 5.38 | 5 | 10 | 5 | 50 | 6 | 33 | 12 | 12 | 12 | 12 | 6.62 | 85 Ohms | TOP=L2:L3=L2/L4:L6=L5/L7:BOTTOM=L7 |
| PCIE_TX_P69 | TX69-DIFF1 | PAIR | 2 | 5.5 | 5 | 10 | 5 | 50 | 6 | 20 | 12 | 12 | 12 | 12 | 7.5 | 85 Ohms | TOP=L2:L3=L2/L4:L6=L5/L7:BOTTOM=L7 |
| PCIE_TX_P69 | TX69-DIFF1 | PAIR | 3 | 5.5 | 5 | 10 | 5 | 50 | 6 | 20 | 12 | 12 | 12 | 12 | 7.5 | 85 Ohms | TOP=L2:L3=L2/L4:L6=L5/L7:BOTTOM=L7 |
| PCIE_TX_P69 | TX69-DIFF1 | PAIR | 4 | 5.5 | 5 | 10 | 5 | 50 | 6 | 20 | 12 | 12 | 12 | 12 | 7.5 | 85 Ohms | TOP=L2:L3=L2/L4:L6=L5/L7:BOTTOM=L7 |
| PCIE_TX_P69 | TX69-DIFF1 | PAIR | 5 | 5.5 | 5 | 10 | 5 | 50 | 6 | 20 | 12 | 12 | 12 | 12 | 7.5 | 85 Ohms | TOP=L2:L3=L2/L4:L6=L5/L7:BOTTOM=L7 |
| PCIE_TX_P69 | TX69-DIFF1 | PAIR | 6 | 5.5 | 5 | 10 | 5 | 50 | 6 | 20 | 12 | 12 | 12 | 12 | 7.5 | 85 Ohms | TOP=L2:L3=L2/L4:L6=L5/L7:BOTTOM=L7 |
| PCIE_TX_P69 | TX69-DIFF1 | PAIR | 7 | 5.5 | 5 | 10 | 5 | 50 | 6 | 20 | 12 | 12 | 12 | 12 | 7.5 | 85 Ohms | TOP=L2:L3=L2/L4:L6=L5/L7:BOTTOM=L7 |
| PCIE_TX_P69 | TX69-DIFF1 | PAIR | 8 | 5.38 | 5 | 10 | 5 | 50 | 6 | 33 | 12 | 12 | 12 | 12 | 6.62 | 85 Ohms | TOP=L2:L3=L2/L4:L6=L5/L7:BOTTOM=L7 |
| PCIE_TX_N6 | TX6-DIFF1 | PAIR | 1 | 5.38 | 5 | 10 | 5 | 50 | 6 | 33 | 12 | 12 | 12 | 12 | 6.62 | 85 Ohms | TOP=L2:L3=L2/L4:L6=L5/L7:BOTTOM=L7 |
| PCIE_TX_N6 | TX6-DIFF1 | PAIR | 2 | 5.5 | 5 | 10 | 5 | 50 | 6 | 20 | 12 | 12 | 12 | 12 | 7.5 | 85 Ohms | TOP=L2:L3=L2/L4:L6=L5/L7:BOTTOM=L7 |
| PCIE_TX_N6 | TX6-DIFF1 | PAIR | 3 | 5.5 | 5 | 10 | 5 | 50 | 6 | 20 | 12 | 12 | 12 | 12 | 7.5 | 85 Ohms | TOP=L2:L3=L2/L4:L6=L5/L7:BOTTOM=L7 |
| PCIE_TX_N6 | TX6-DIFF1 | PAIR | 4 | 5.5 | 5 | 10 | 5 | 50 | 6 | 20 | 12 | 12 | 12 | 12 | 7.5 | 85 Ohms | TOP=L2:L3=L2/L4:L6=L5/L7:BOTTOM=L7 |
| PCIE_TX_N6 | TX6-DIFF1 | PAIR | 5 | 5.5 | 5 | 10 | 5 | 50 | 6 | 20 | 12 | 12 | 12 | 12 | 7.5 | 85 Ohms | TOP=L2:L3=L2/L4:L6=L5/L7:BOTTOM=L7 |
| PCIE_TX_N6 | TX6-DIFF1 | PAIR | 6 | 5.5 | 5 | 10 | 5 | 50 | 6 | 20 | 12 | 12 | 12 | 12 | 7.5 | 85 Ohms | TOP=L2:L3=L2/L4:L6=L5/L7:BOTTOM=L7 |
| PCIE_TX_N6 | TX6-DIFF1 | PAIR | 7 | 5.5 | 5 | 10 | 5 | 50 | 6 | 20 | 12 | 12 | 12 | 12 | 7.5 | 85 Ohms | TOP=L2:L3=L2/L4:L6=L5/L7:BOTTOM=L7 |
| PCIE_TX_N6 | TX6-DIFF1 | PAIR | 8 | 5.38 | 5 | 10 | 5 | 50 | 6 | 33 | 12 | 12 | 12 | 12 | 6.62 | 85 Ohms | TOP=L2:L3=L2/L4:L6=L5/L7:BOTTOM=L7 |
| PCIE_TX_P6 | TX6-DIFF1 | PAIR | 1 | 5.38 | 5 | 10 | 5 | 50 | 6 | 33 | 12 | 12 | 12 | 12 | 6.62 | 85 Ohms | TOP=L2:L3=L2/L4:L6=L5/L7:BOTTOM=L7 |
| PCIE_TX_P6 | TX6-DIFF1 | PAIR | 2 | 5.5 | 5 | 10 | 5 | 50 | 6 | 20 | 12 | 12 | 12 | 12 | 7.5 | 85 Ohms | TOP=L2:L3=L2/L4:L6=L5/L7:BOTTOM=L7 |
| PCIE_TX_P6 | TX6-DIFF1 | PAIR | 3 | 5.5 | 5 | 10 | 5 | 50 | 6 | 20 | 12 | 12 | 12 | 12 | 7.5 | 85 Ohms | TOP=L2:L3=L2/L4:L6=L5/L7:BOTTOM=L7 |
| PCIE_TX_P6 | TX6-DIFF1 | PAIR | 4 | 5.5 | 5 | 10 | 5 | 50 | 6 | 20 | 12 | 12 | 12 | 12 | 7.5 | 85 Ohms | TOP=L2:L3=L2/L4:L6=L5/L7:BOTTOM=L7 |
| PCIE_TX_P6 | TX6-DIFF1 | PAIR | 5 | 5.5 | 5 | 10 | 5 | 50 | 6 | 20 | 12 | 12 | 12 | 12 | 7.5 | 85 Ohms | TOP=L2:L3=L2/L4:L6=L5/L7:BOTTOM=L7 |
| PCIE_TX_P6 | TX6-DIFF1 | PAIR | 6 | 5.5 | 5 | 10 | 5 | 50 | 6 | 20 | 12 | 12 | 12 | 12 | 7.5 | 85 Ohms | TOP=L2:L3=L2/L4:L6=L5/L7:BOTTOM=L7 |
| PCIE_TX_P6 | TX6-DIFF1 | PAIR | 7 | 5.5 | 5 | 10 | 5 | 50 | 6 | 20 | 12 | 12 | 12 | 12 | 7.5 | 85 Ohms | TOP=L2:L3=L2/L4:L6=L5/L7:BOTTOM=L7 |
| PCIE_TX_P6 | TX6-DIFF1 | PAIR | 8 | 5.38 | 5 | 10 | 5 | 50 | 6 | 33 | 12 | 12 | 12 | 12 | 6.62 | 85 Ohms | TOP=L2:L3=L2/L4:L6=L5/L7:BOTTOM=L7 |
| PCIE_TX_N70 | TX70-DIFF1 | PAIR | 1 | 5.38 | 5 | 10 | 5 | 50 | 6 | 33 | 12 | 12 | 12 | 12 | 6.62 | 85 Ohms | TOP=L2:L3=L2/L4:L6=L5/L7:BOTTOM=L7 |
| PCIE_TX_N70 | TX70-DIFF1 | PAIR | 2 | 5.5 | 5 | 10 | 5 | 50 | 6 | 20 | 12 | 12 | 12 | 12 | 7.5 | 85 Ohms | TOP=L2:L3=L2/L4:L6=L5/L7:BOTTOM=L7 |
| PCIE_TX_N70 | TX70-DIFF1 | PAIR | 3 | 5.5 | 5 | 10 | 5 | 50 | 6 | 20 | 12 | 12 | 12 | 12 | 7.5 | 85 Ohms | TOP=L2:L3=L2/L4:L6=L5/L7:BOTTOM=L7 |
| PCIE_TX_N70 | TX70-DIFF1 | PAIR | 4 | 5.5 | 5 | 10 | 5 | 50 | 6 | 20 | 12 | 12 | 12 | 12 | 7.5 | 85 Ohms | TOP=L2:L3=L2/L4:L6=L5/L7:BOTTOM=L7 |
| PCIE_TX_N70 | TX70-DIFF1 | PAIR | 5 | 5.5 | 5 | 10 | 5 | 50 | 6 | 20 | 12 | 12 | 12 | 12 | 7.5 | 85 Ohms | TOP=L2:L3=L2/L4:L6=L5/L7:BOTTOM=L7 |
| PCIE_TX_N70 | TX70-DIFF1 | PAIR | 6 | 5.5 | 5 | 10 | 5 | 50 | 6 | 20 | 12 | 12 | 12 | 12 | 7.5 | 85 Ohms | TOP=L2:L3=L2/L4:L6=L5/L7:BOTTOM=L7 |
| PCIE_TX_N70 | TX70-DIFF1 | PAIR | 7 | 5.5 | 5 | 10 | 5 | 50 | 6 | 20 | 12 | 12 | 12 | 12 | 7.5 | 85 Ohms | TOP=L2:L3=L2/L4:L6=L5/L7:BOTTOM=L7 |
| PCIE_TX_N70 | TX70-DIFF1 | PAIR | 8 | 5.38 | 5 | 10 | 5 | 50 | 6 | 33 | 12 | 12 | 12 | 12 | 6.62 | 85 Ohms | TOP=L2:L3=L2/L4:L6=L5/L7:BOTTOM=L7 |
| PCIE_TX_P70 | TX70-DIFF1 | PAIR | 1 | 5.38 | 5 | 10 | 5 | 50 | 6 | 33 | 12 | 12 | 12 | 12 | 6.62 | 85 Ohms | TOP=L2:L3=L2/L4:L6=L5/L7:BOTTOM=L7 |
| PCIE_TX_P70 | TX70-DIFF1 | PAIR | 2 | 5.5 | 5 | 10 | 5 | 50 | 6 | 20 | 12 | 12 | 12 | 12 | 7.5 | 85 Ohms | TOP=L2:L3=L2/L4:L6=L5/L7:BOTTOM=L7 |
| PCIE_TX_P70 | TX70-DIFF1 | PAIR | 3 | 5.5 | 5 | 10 | 5 | 50 | 6 | 20 | 12 | 12 | 12 | 12 | 7.5 | 85 Ohms | TOP=L2:L3=L2/L4:L6=L5/L7:BOTTOM=L7 |
| PCIE_TX_P70 | TX70-DIFF1 | PAIR | 4 | 5.5 | 5 | 10 | 5 | 50 | 6 | 20 | 12 | 12 | 12 | 12 | 7.5 | 85 Ohms | TOP=L2:L3=L2/L4:L6=L5/L7:BOTTOM=L7 |
| PCIE_TX_P70 | TX70-DIFF1 | PAIR | 5 | 5.5 | 5 | 10 | 5 | 50 | 6 | 20 | 12 | 12 | 12 | 12 | 7.5 | 85 Ohms | TOP=L2:L3=L2/L4:L6=L5/L7:BOTTOM=L7 |
| PCIE_TX_P70 | TX70-DIFF1 | PAIR | 6 | 5.5 | 5 | 10 | 5 | 50 | 6 | 20 | 12 | 12 | 12 | 12 | 7.5 | 85 Ohms | TOP=L2:L3=L2/L4:L6=L5/L7:BOTTOM=L7 |
| PCIE_TX_P70 | TX70-DIFF1 | PAIR | 7 | 5.5 | 5 | 10 | 5 | 50 | 6 | 20 | 12 | 12 | 12 | 12 | 7.5 | 85 Ohms | TOP=L2:L3=L2/L4:L6=L5/L7:BOTTOM=L7 |
| PCIE_TX_P70 | TX70-DIFF1 | PAIR | 8 | 5.38 | 5 | 10 | 5 | 50 | 6 | 33 | 12 | 12 | 12 | 12 | 6.62 | 85 Ohms | TOP=L2:L3=L2/L4:L6=L5/L7:BOTTOM=L7 |
| PCIE_TX_N71 | TX71-DIFF1 | PAIR | 1 | 5.38 | 5 | 10 | 5 | 50 | 6 | 33 | 12 | 12 | 12 | 12 | 6.62 | 85 Ohms | TOP=L2:L3=L2/L4:L6=L5/L7:BOTTOM=L7 |
| PCIE_TX_N71 | TX71-DIFF1 | PAIR | 2 | 5.5 | 5 | 10 | 5 | 50 | 6 | 20 | 12 | 12 | 12 | 12 | 7.5 | 85 Ohms | TOP=L2:L3=L2/L4:L6=L5/L7:BOTTOM=L7 |
| PCIE_TX_N71 | TX71-DIFF1 | PAIR | 3 | 5.5 | 5 | 10 | 5 | 50 | 6 | 20 | 12 | 12 | 12 | 12 | 7.5 | 85 Ohms | TOP=L2:L3=L2/L4:L6=L5/L7:BOTTOM=L7 |
| PCIE_TX_N71 | TX71-DIFF1 | PAIR | 4 | 5.5 | 5 | 10 | 5 | 50 | 6 | 20 | 12 | 12 | 12 | 12 | 7.5 | 85 Ohms | TOP=L2:L3=L2/L4:L6=L5/L7:BOTTOM=L7 |
| PCIE_TX_N71 | TX71-DIFF1 | PAIR | 5 | 5.5 | 5 | 10 | 5 | 50 | 6 | 20 | 12 | 12 | 12 | 12 | 7.5 | 85 Ohms | TOP=L2:L3=L2/L4:L6=L5/L7:BOTTOM=L7 |
| PCIE_TX_N71 | TX71-DIFF1 | PAIR | 6 | 5.5 | 5 | 10 | 5 | 50 | 6 | 20 | 12 | 12 | 12 | 12 | 7.5 | 85 Ohms | TOP=L2:L3=L2/L4:L6=L5/L7:BOTTOM=L7 |
| PCIE_TX_N71 | TX71-DIFF1 | PAIR | 7 | 5.5 | 5 | 10 | 5 | 50 | 6 | 20 | 12 | 12 | 12 | 12 | 7.5 | 85 Ohms | TOP=L2:L3=L2/L4:L6=L5/L7:BOTTOM=L7 |
| PCIE_TX_N71 | TX71-DIFF1 | PAIR | 8 | 5.38 | 5 | 10 | 5 | 50 | 6 | 33 | 12 | 12 | 12 | 12 | 6.62 | 85 Ohms | TOP=L2:L3=L2/L4:L6=L5/L7:BOTTOM=L7 |
| PCIE_TX_P71 | TX71-DIFF1 | PAIR | 1 | 5.38 | 5 | 10 | 5 | 50 | 6 | 33 | 12 | 12 | 12 | 12 | 6.62 | 85 Ohms | TOP=L2:L3=L2/L4:L6=L5/L7:BOTTOM=L7 |
| PCIE_TX_P71 | TX71-DIFF1 | PAIR | 2 | 5.5 | 5 | 10 | 5 | 50 | 6 | 20 | 12 | 12 | 12 | 12 | 7.5 | 85 Ohms | TOP=L2:L3=L2/L4:L6=L5/L7:BOTTOM=L7 |
| PCIE_TX_P71 | TX71-DIFF1 | PAIR | 3 | 5.5 | 5 | 10 | 5 | 50 | 6 | 20 | 12 | 12 | 12 | 12 | 7.5 | 85 Ohms | TOP=L2:L3=L2/L4:L6=L5/L7:BOTTOM=L7 |
| PCIE_TX_P71 | TX71-DIFF1 | PAIR | 4 | 5.5 | 5 | 10 | 5 | 50 | 6 | 20 | 12 | 12 | 12 | 12 | 7.5 | 85 Ohms | TOP=L2:L3=L2/L4:L6=L5/L7:BOTTOM=L7 |
| PCIE_TX_P71 | TX71-DIFF1 | PAIR | 5 | 5.5 | 5 | 10 | 5 | 50 | 6 | 20 | 12 | 12 | 12 | 12 | 7.5 | 85 Ohms | TOP=L2:L3=L2/L4:L6=L5/L7:BOTTOM=L7 |
| PCIE_TX_P71 | TX71-DIFF1 | PAIR | 6 | 5.5 | 5 | 10 | 5 | 50 | 6 | 20 | 12 | 12 | 12 | 12 | 7.5 | 85 Ohms | TOP=L2:L3=L2/L4:L6=L5/L7:BOTTOM=L7 |
| PCIE_TX_P71 | TX71-DIFF1 | PAIR | 7 | 5.5 | 5 | 10 | 5 | 50 | 6 | 20 | 12 | 12 | 12 | 12 | 7.5 | 85 Ohms | TOP=L2:L3=L2/L4:L6=L5/L7:BOTTOM=L7 |
| PCIE_TX_P71 | TX71-DIFF1 | PAIR | 8 | 5.38 | 5 | 10 | 5 | 50 | 6 | 33 | 12 | 12 | 12 | 12 | 6.62 | 85 Ohms | TOP=L2:L3=L2/L4:L6=L5/L7:BOTTOM=L7 |
| PCIE_TX_N72 | TX72-DIFF1 | PAIR | 1 | 5.38 | 5 | 10 | 5 | 50 | 6 | 33 | 12 | 12 | 12 | 12 | 6.62 | 85 Ohms | TOP=L2:L3=L2/L4:L6=L5/L7:BOTTOM=L7 |
| PCIE_TX_N72 | TX72-DIFF1 | PAIR | 2 | 5.5 | 5 | 10 | 5 | 50 | 6 | 20 | 12 | 12 | 12 | 12 | 7.5 | 85 Ohms | TOP=L2:L3=L2/L4:L6=L5/L7:BOTTOM=L7 |
| PCIE_TX_N72 | TX72-DIFF1 | PAIR | 3 | 5.5 | 5 | 10 | 5 | 50 | 6 | 20 | 12 | 12 | 12 | 12 | 7.5 | 85 Ohms | TOP=L2:L3=L2/L4:L6=L5/L7:BOTTOM=L7 |
| PCIE_TX_N72 | TX72-DIFF1 | PAIR | 4 | 5.5 | 5 | 10 | 5 | 50 | 6 | 20 | 12 | 12 | 12 | 12 | 7.5 | 85 Ohms | TOP=L2:L3=L2/L4:L6=L5/L7:BOTTOM=L7 |
| PCIE_TX_N72 | TX72-DIFF1 | PAIR | 5 | 5.5 | 5 | 10 | 5 | 50 | 6 | 20 | 12 | 12 | 12 | 12 | 7.5 | 85 Ohms | TOP=L2:L3=L2/L4:L6=L5/L7:BOTTOM=L7 |
| PCIE_TX_N72 | TX72-DIFF1 | PAIR | 6 | 5.5 | 5 | 10 | 5 | 50 | 6 | 20 | 12 | 12 | 12 | 12 | 7.5 | 85 Ohms | TOP=L2:L3=L2/L4:L6=L5/L7:BOTTOM=L7 |
| PCIE_TX_N72 | TX72-DIFF1 | PAIR | 7 | 5.5 | 5 | 10 | 5 | 50 | 6 | 20 | 12 | 12 | 12 | 12 | 7.5 | 85 Ohms | TOP=L2:L3=L2/L4:L6=L5/L7:BOTTOM=L7 |
| PCIE_TX_N72 | TX72-DIFF1 | PAIR | 8 | 5.38 | 5 | 10 | 5 | 50 | 6 | 33 | 12 | 12 | 12 | 12 | 6.62 | 85 Ohms | TOP=L2:L3=L2/L4:L6=L5/L7:BOTTOM=L7 |
| PCIE_TX_P72 | TX72-DIFF1 | PAIR | 1 | 5.38 | 5 | 10 | 5 | 50 | 6 | 33 | 12 | 12 | 12 | 12 | 6.62 | 85 Ohms | TOP=L2:L3=L2/L4:L6=L5/L7:BOTTOM=L7 |
| PCIE_TX_P72 | TX72-DIFF1 | PAIR | 2 | 5.5 | 5 | 10 | 5 | 50 | 6 | 20 | 12 | 12 | 12 | 12 | 7.5 | 85 Ohms | TOP=L2:L3=L2/L4:L6=L5/L7:BOTTOM=L7 |
| PCIE_TX_P72 | TX72-DIFF1 | PAIR | 3 | 5.5 | 5 | 10 | 5 | 50 | 6 | 20 | 12 | 12 | 12 | 12 | 7.5 | 85 Ohms | TOP=L2:L3=L2/L4:L6=L5/L7:BOTTOM=L7 |
| PCIE_TX_P72 | TX72-DIFF1 | PAIR | 4 | 5.5 | 5 | 10 | 5 | 50 | 6 | 20 | 12 | 12 | 12 | 12 | 7.5 | 85 Ohms | TOP=L2:L3=L2/L4:L6=L5/L7:BOTTOM=L7 |
| PCIE_TX_P72 | TX72-DIFF1 | PAIR | 5 | 5.5 | 5 | 10 | 5 | 50 | 6 | 20 | 12 | 12 | 12 | 12 | 7.5 | 85 Ohms | TOP=L2:L3=L2/L4:L6=L5/L7:BOTTOM=L7 |
| PCIE_TX_P72 | TX72-DIFF1 | PAIR | 6 | 5.5 | 5 | 10 | 5 | 50 | 6 | 20 | 12 | 12 | 12 | 12 | 7.5 | 85 Ohms | TOP=L2:L3=L2/L4:L6=L5/L7:BOTTOM=L7 |
| PCIE_TX_P72 | TX72-DIFF1 | PAIR | 7 | 5.5 | 5 | 10 | 5 | 50 | 6 | 20 | 12 | 12 | 12 | 12 | 7.5 | 85 Ohms | TOP=L2:L3=L2/L4:L6=L5/L7:BOTTOM=L7 |
| PCIE_TX_P72 | TX72-DIFF1 | PAIR | 8 | 5.38 | 5 | 10 | 5 | 50 | 6 | 33 | 12 | 12 | 12 | 12 | 6.62 | 85 Ohms | TOP=L2:L3=L2/L4:L6=L5/L7:BOTTOM=L7 |
| PCIE_TX_N73 | TX73-DIFF1 | PAIR | 1 | 5.38 | 5 | 10 | 5 | 50 | 6 | 33 | 12 | 12 | 12 | 12 | 6.62 | 85 Ohms | TOP=L2:L3=L2/L4:L6=L5/L7:BOTTOM=L7 |
| PCIE_TX_N73 | TX73-DIFF1 | PAIR | 2 | 5.5 | 5 | 10 | 5 | 50 | 6 | 20 | 12 | 12 | 12 | 12 | 7.5 | 85 Ohms | TOP=L2:L3=L2/L4:L6=L5/L7:BOTTOM=L7 |
| PCIE_TX_N73 | TX73-DIFF1 | PAIR | 3 | 5.5 | 5 | 10 | 5 | 50 | 6 | 20 | 12 | 12 | 12 | 12 | 7.5 | 85 Ohms | TOP=L2:L3=L2/L4:L6=L5/L7:BOTTOM=L7 |
| PCIE_TX_N73 | TX73-DIFF1 | PAIR | 4 | 5.5 | 5 | 10 | 5 | 50 | 6 | 20 | 12 | 12 | 12 | 12 | 7.5 | 85 Ohms | TOP=L2:L3=L2/L4:L6=L5/L7:BOTTOM=L7 |
| PCIE_TX_N73 | TX73-DIFF1 | PAIR | 5 | 5.5 | 5 | 10 | 5 | 50 | 6 | 20 | 12 | 12 | 12 | 12 | 7.5 | 85 Ohms | TOP=L2:L3=L2/L4:L6=L5/L7:BOTTOM=L7 |
| PCIE_TX_N73 | TX73-DIFF1 | PAIR | 6 | 5.5 | 5 | 10 | 5 | 50 | 6 | 20 | 12 | 12 | 12 | 12 | 7.5 | 85 Ohms | TOP=L2:L3=L2/L4:L6=L5/L7:BOTTOM=L7 |
| PCIE_TX_N73 | TX73-DIFF1 | PAIR | 7 | 5.5 | 5 | 10 | 5 | 50 | 6 | 20 | 12 | 12 | 12 | 12 | 7.5 | 85 Ohms | TOP=L2:L3=L2/L4:L6=L5/L7:BOTTOM=L7 |
| PCIE_TX_N73 | TX73-DIFF1 | PAIR | 8 | 5.38 | 5 | 10 | 5 | 50 | 6 | 33 | 12 | 12 | 12 | 12 | 6.62 | 85 Ohms | TOP=L2:L3=L2/L4:L6=L5/L7:BOTTOM=L7 |
| PCIE_TX_P73 | TX73-DIFF1 | PAIR | 1 | 5.38 | 5 | 10 | 5 | 50 | 6 | 33 | 12 | 12 | 12 | 12 | 6.62 | 85 Ohms | TOP=L2:L3=L2/L4:L6=L5/L7:BOTTOM=L7 |
| PCIE_TX_P73 | TX73-DIFF1 | PAIR | 2 | 5.5 | 5 | 10 | 5 | 50 | 6 | 20 | 12 | 12 | 12 | 12 | 7.5 | 85 Ohms | TOP=L2:L3=L2/L4:L6=L5/L7:BOTTOM=L7 |
| PCIE_TX_P73 | TX73-DIFF1 | PAIR | 3 | 5.5 | 5 | 10 | 5 | 50 | 6 | 20 | 12 | 12 | 12 | 12 | 7.5 | 85 Ohms | TOP=L2:L3=L2/L4:L6=L5/L7:BOTTOM=L7 |
| PCIE_TX_P73 | TX73-DIFF1 | PAIR | 4 | 5.5 | 5 | 10 | 5 | 50 | 6 | 20 | 12 | 12 | 12 | 12 | 7.5 | 85 Ohms | TOP=L2:L3=L2/L4:L6=L5/L7:BOTTOM=L7 |
| PCIE_TX_P73 | TX73-DIFF1 | PAIR | 5 | 5.5 | 5 | 10 | 5 | 50 | 6 | 20 | 12 | 12 | 12 | 12 | 7.5 | 85 Ohms | TOP=L2:L3=L2/L4:L6=L5/L7:BOTTOM=L7 |
| PCIE_TX_P73 | TX73-DIFF1 | PAIR | 6 | 5.5 | 5 | 10 | 5 | 50 | 6 | 20 | 12 | 12 | 12 | 12 | 7.5 | 85 Ohms | TOP=L2:L3=L2/L4:L6=L5/L7:BOTTOM=L7 |
| PCIE_TX_P73 | TX73-DIFF1 | PAIR | 7 | 5.5 | 5 | 10 | 5 | 50 | 6 | 20 | 12 | 12 | 12 | 12 | 7.5 | 85 Ohms | TOP=L2:L3=L2/L4:L6=L5/L7:BOTTOM=L7 |
| PCIE_TX_P73 | TX73-DIFF1 | PAIR | 8 | 5.38 | 5 | 10 | 5 | 50 | 6 | 33 | 12 | 12 | 12 | 12 | 6.62 | 85 Ohms | TOP=L2:L3=L2/L4:L6=L5/L7:BOTTOM=L7 |
| PCIE_TX_N74 | TX74-DIFF1 | PAIR | 1 | 5.38 | 5 | 10 | 5 | 50 | 6 | 33 | 12 | 12 | 12 | 12 | 6.62 | 85 Ohms | TOP=L2:L3=L2/L4:L6=L5/L7:BOTTOM=L7 |
| PCIE_TX_N74 | TX74-DIFF1 | PAIR | 2 | 5.5 | 5 | 10 | 5 | 50 | 6 | 20 | 12 | 12 | 12 | 12 | 7.5 | 85 Ohms | TOP=L2:L3=L2/L4:L6=L5/L7:BOTTOM=L7 |
| PCIE_TX_N74 | TX74-DIFF1 | PAIR | 3 | 5.5 | 5 | 10 | 5 | 50 | 6 | 20 | 12 | 12 | 12 | 12 | 7.5 | 85 Ohms | TOP=L2:L3=L2/L4:L6=L5/L7:BOTTOM=L7 |
| PCIE_TX_N74 | TX74-DIFF1 | PAIR | 4 | 5.5 | 5 | 10 | 5 | 50 | 6 | 20 | 12 | 12 | 12 | 12 | 7.5 | 85 Ohms | TOP=L2:L3=L2/L4:L6=L5/L7:BOTTOM=L7 |
| PCIE_TX_N74 | TX74-DIFF1 | PAIR | 5 | 5.5 | 5 | 10 | 5 | 50 | 6 | 20 | 12 | 12 | 12 | 12 | 7.5 | 85 Ohms | TOP=L2:L3=L2/L4:L6=L5/L7:BOTTOM=L7 |
| PCIE_TX_N74 | TX74-DIFF1 | PAIR | 6 | 5.5 | 5 | 10 | 5 | 50 | 6 | 20 | 12 | 12 | 12 | 12 | 7.5 | 85 Ohms | TOP=L2:L3=L2/L4:L6=L5/L7:BOTTOM=L7 |
| PCIE_TX_N74 | TX74-DIFF1 | PAIR | 7 | 5.5 | 5 | 10 | 5 | 50 | 6 | 20 | 12 | 12 | 12 | 12 | 7.5 | 85 Ohms | TOP=L2:L3=L2/L4:L6=L5/L7:BOTTOM=L7 |
| PCIE_TX_N74 | TX74-DIFF1 | PAIR | 8 | 5.38 | 5 | 10 | 5 | 50 | 6 | 33 | 12 | 12 | 12 | 12 | 6.62 | 85 Ohms | TOP=L2:L3=L2/L4:L6=L5/L7:BOTTOM=L7 |
| PCIE_TX_P74 | TX74-DIFF1 | PAIR | 1 | 5.38 | 5 | 10 | 5 | 50 | 6 | 33 | 12 | 12 | 12 | 12 | 6.62 | 85 Ohms | TOP=L2:L3=L2/L4:L6=L5/L7:BOTTOM=L7 |
| PCIE_TX_P74 | TX74-DIFF1 | PAIR | 2 | 5.5 | 5 | 10 | 5 | 50 | 6 | 20 | 12 | 12 | 12 | 12 | 7.5 | 85 Ohms | TOP=L2:L3=L2/L4:L6=L5/L7:BOTTOM=L7 |
| PCIE_TX_P74 | TX74-DIFF1 | PAIR | 3 | 5.5 | 5 | 10 | 5 | 50 | 6 | 20 | 12 | 12 | 12 | 12 | 7.5 | 85 Ohms | TOP=L2:L3=L2/L4:L6=L5/L7:BOTTOM=L7 |
| PCIE_TX_P74 | TX74-DIFF1 | PAIR | 4 | 5.5 | 5 | 10 | 5 | 50 | 6 | 20 | 12 | 12 | 12 | 12 | 7.5 | 85 Ohms | TOP=L2:L3=L2/L4:L6=L5/L7:BOTTOM=L7 |
| PCIE_TX_P74 | TX74-DIFF1 | PAIR | 5 | 5.5 | 5 | 10 | 5 | 50 | 6 | 20 | 12 | 12 | 12 | 12 | 7.5 | 85 Ohms | TOP=L2:L3=L2/L4:L6=L5/L7:BOTTOM=L7 |
| PCIE_TX_P74 | TX74-DIFF1 | PAIR | 6 | 5.5 | 5 | 10 | 5 | 50 | 6 | 20 | 12 | 12 | 12 | 12 | 7.5 | 85 Ohms | TOP=L2:L3=L2/L4:L6=L5/L7:BOTTOM=L7 |
| PCIE_TX_P74 | TX74-DIFF1 | PAIR | 7 | 5.5 | 5 | 10 | 5 | 50 | 6 | 20 | 12 | 12 | 12 | 12 | 7.5 | 85 Ohms | TOP=L2:L3=L2/L4:L6=L5/L7:BOTTOM=L7 |
| PCIE_TX_P74 | TX74-DIFF1 | PAIR | 8 | 5.38 | 5 | 10 | 5 | 50 | 6 | 33 | 12 | 12 | 12 | 12 | 6.62 | 85 Ohms | TOP=L2:L3=L2/L4:L6=L5/L7:BOTTOM=L7 |
| PCIE_TX_N75 | TX75-DIFF1 | PAIR | 1 | 5.38 | 5 | 10 | 5 | 50 | 6 | 33 | 12 | 12 | 12 | 12 | 6.62 | 85 Ohms | TOP=L2:L3=L2/L4:L6=L5/L7:BOTTOM=L7 |
| PCIE_TX_N75 | TX75-DIFF1 | PAIR | 2 | 5.5 | 5 | 10 | 5 | 50 | 6 | 20 | 12 | 12 | 12 | 12 | 7.5 | 85 Ohms | TOP=L2:L3=L2/L4:L6=L5/L7:BOTTOM=L7 |
| PCIE_TX_N75 | TX75-DIFF1 | PAIR | 3 | 5.5 | 5 | 10 | 5 | 50 | 6 | 20 | 12 | 12 | 12 | 12 | 7.5 | 85 Ohms | TOP=L2:L3=L2/L4:L6=L5/L7:BOTTOM=L7 |
| PCIE_TX_N75 | TX75-DIFF1 | PAIR | 4 | 5.5 | 5 | 10 | 5 | 50 | 6 | 20 | 12 | 12 | 12 | 12 | 7.5 | 85 Ohms | TOP=L2:L3=L2/L4:L6=L5/L7:BOTTOM=L7 |
| PCIE_TX_N75 | TX75-DIFF1 | PAIR | 5 | 5.5 | 5 | 10 | 5 | 50 | 6 | 20 | 12 | 12 | 12 | 12 | 7.5 | 85 Ohms | TOP=L2:L3=L2/L4:L6=L5/L7:BOTTOM=L7 |
| PCIE_TX_N75 | TX75-DIFF1 | PAIR | 6 | 5.5 | 5 | 10 | 5 | 50 | 6 | 20 | 12 | 12 | 12 | 12 | 7.5 | 85 Ohms | TOP=L2:L3=L2/L4:L6=L5/L7:BOTTOM=L7 |
| PCIE_TX_N75 | TX75-DIFF1 | PAIR | 7 | 5.5 | 5 | 10 | 5 | 50 | 6 | 20 | 12 | 12 | 12 | 12 | 7.5 | 85 Ohms | TOP=L2:L3=L2/L4:L6=L5/L7:BOTTOM=L7 |
| PCIE_TX_N75 | TX75-DIFF1 | PAIR | 8 | 5.38 | 5 | 10 | 5 | 50 | 6 | 33 | 12 | 12 | 12 | 12 | 6.62 | 85 Ohms | TOP=L2:L3=L2/L4:L6=L5/L7:BOTTOM=L7 |
| PCIE_TX_P75 | TX75-DIFF1 | PAIR | 1 | 5.38 | 5 | 10 | 5 | 50 | 6 | 33 | 12 | 12 | 12 | 12 | 6.62 | 85 Ohms | TOP=L2:L3=L2/L4:L6=L5/L7:BOTTOM=L7 |
| PCIE_TX_P75 | TX75-DIFF1 | PAIR | 2 | 5.5 | 5 | 10 | 5 | 50 | 6 | 20 | 12 | 12 | 12 | 12 | 7.5 | 85 Ohms | TOP=L2:L3=L2/L4:L6=L5/L7:BOTTOM=L7 |
| PCIE_TX_P75 | TX75-DIFF1 | PAIR | 3 | 5.5 | 5 | 10 | 5 | 50 | 6 | 20 | 12 | 12 | 12 | 12 | 7.5 | 85 Ohms | TOP=L2:L3=L2/L4:L6=L5/L7:BOTTOM=L7 |
| PCIE_TX_P75 | TX75-DIFF1 | PAIR | 4 | 5.5 | 5 | 10 | 5 | 50 | 6 | 20 | 12 | 12 | 12 | 12 | 7.5 | 85 Ohms | TOP=L2:L3=L2/L4:L6=L5/L7:BOTTOM=L7 |
| PCIE_TX_P75 | TX75-DIFF1 | PAIR | 5 | 5.5 | 5 | 10 | 5 | 50 | 6 | 20 | 12 | 12 | 12 | 12 | 7.5 | 85 Ohms | TOP=L2:L3=L2/L4:L6=L5/L7:BOTTOM=L7 |
| PCIE_TX_P75 | TX75-DIFF1 | PAIR | 6 | 5.5 | 5 | 10 | 5 | 50 | 6 | 20 | 12 | 12 | 12 | 12 | 7.5 | 85 Ohms | TOP=L2:L3=L2/L4:L6=L5/L7:BOTTOM=L7 |
| PCIE_TX_P75 | TX75-DIFF1 | PAIR | 7 | 5.5 | 5 | 10 | 5 | 50 | 6 | 20 | 12 | 12 | 12 | 12 | 7.5 | 85 Ohms | TOP=L2:L3=L2/L4:L6=L5/L7:BOTTOM=L7 |
| PCIE_TX_P75 | TX75-DIFF1 | PAIR | 8 | 5.38 | 5 | 10 | 5 | 50 | 6 | 33 | 12 | 12 | 12 | 12 | 6.62 | 85 Ohms | TOP=L2:L3=L2/L4:L6=L5/L7:BOTTOM=L7 |
| PCIE_TX_N76 | TX76-DIFF1 | PAIR | 1 | 5.38 | 5 | 10 | 5 | 50 | 6 | 33 | 12 | 12 | 12 | 12 | 6.62 | 85 Ohms | TOP=L2:L3=L2/L4:L6=L5/L7:BOTTOM=L7 |
| PCIE_TX_N76 | TX76-DIFF1 | PAIR | 2 | 5.5 | 5 | 10 | 5 | 50 | 6 | 20 | 12 | 12 | 12 | 12 | 7.5 | 85 Ohms | TOP=L2:L3=L2/L4:L6=L5/L7:BOTTOM=L7 |
| PCIE_TX_N76 | TX76-DIFF1 | PAIR | 3 | 5.5 | 5 | 10 | 5 | 50 | 6 | 20 | 12 | 12 | 12 | 12 | 7.5 | 85 Ohms | TOP=L2:L3=L2/L4:L6=L5/L7:BOTTOM=L7 |
| PCIE_TX_N76 | TX76-DIFF1 | PAIR | 4 | 5.5 | 5 | 10 | 5 | 50 | 6 | 20 | 12 | 12 | 12 | 12 | 7.5 | 85 Ohms | TOP=L2:L3=L2/L4:L6=L5/L7:BOTTOM=L7 |
| PCIE_TX_N76 | TX76-DIFF1 | PAIR | 5 | 5.5 | 5 | 10 | 5 | 50 | 6 | 20 | 12 | 12 | 12 | 12 | 7.5 | 85 Ohms | TOP=L2:L3=L2/L4:L6=L5/L7:BOTTOM=L7 |
| PCIE_TX_N76 | TX76-DIFF1 | PAIR | 6 | 5.5 | 5 | 10 | 5 | 50 | 6 | 20 | 12 | 12 | 12 | 12 | 7.5 | 85 Ohms | TOP=L2:L3=L2/L4:L6=L5/L7:BOTTOM=L7 |
| PCIE_TX_N76 | TX76-DIFF1 | PAIR | 7 | 5.5 | 5 | 10 | 5 | 50 | 6 | 20 | 12 | 12 | 12 | 12 | 7.5 | 85 Ohms | TOP=L2:L3=L2/L4:L6=L5/L7:BOTTOM=L7 |
| PCIE_TX_N76 | TX76-DIFF1 | PAIR | 8 | 5.38 | 5 | 10 | 5 | 50 | 6 | 33 | 12 | 12 | 12 | 12 | 6.62 | 85 Ohms | TOP=L2:L3=L2/L4:L6=L5/L7:BOTTOM=L7 |
| PCIE_TX_P76 | TX76-DIFF1 | PAIR | 1 | 5.38 | 5 | 10 | 5 | 50 | 6 | 33 | 12 | 12 | 12 | 12 | 6.62 | 85 Ohms | TOP=L2:L3=L2/L4:L6=L5/L7:BOTTOM=L7 |
| PCIE_TX_P76 | TX76-DIFF1 | PAIR | 2 | 5.5 | 5 | 10 | 5 | 50 | 6 | 20 | 12 | 12 | 12 | 12 | 7.5 | 85 Ohms | TOP=L2:L3=L2/L4:L6=L5/L7:BOTTOM=L7 |
| PCIE_TX_P76 | TX76-DIFF1 | PAIR | 3 | 5.5 | 5 | 10 | 5 | 50 | 6 | 20 | 12 | 12 | 12 | 12 | 7.5 | 85 Ohms | TOP=L2:L3=L2/L4:L6=L5/L7:BOTTOM=L7 |
| PCIE_TX_P76 | TX76-DIFF1 | PAIR | 4 | 5.5 | 5 | 10 | 5 | 50 | 6 | 20 | 12 | 12 | 12 | 12 | 7.5 | 85 Ohms | TOP=L2:L3=L2/L4:L6=L5/L7:BOTTOM=L7 |
| PCIE_TX_P76 | TX76-DIFF1 | PAIR | 5 | 5.5 | 5 | 10 | 5 | 50 | 6 | 20 | 12 | 12 | 12 | 12 | 7.5 | 85 Ohms | TOP=L2:L3=L2/L4:L6=L5/L7:BOTTOM=L7 |
| PCIE_TX_P76 | TX76-DIFF1 | PAIR | 6 | 5.5 | 5 | 10 | 5 | 50 | 6 | 20 | 12 | 12 | 12 | 12 | 7.5 | 85 Ohms | TOP=L2:L3=L2/L4:L6=L5/L7:BOTTOM=L7 |
| PCIE_TX_P76 | TX76-DIFF1 | PAIR | 7 | 5.5 | 5 | 10 | 5 | 50 | 6 | 20 | 12 | 12 | 12 | 12 | 7.5 | 85 Ohms | TOP=L2:L3=L2/L4:L6=L5/L7:BOTTOM=L7 |
| PCIE_TX_P76 | TX76-DIFF1 | PAIR | 8 | 5.38 | 5 | 10 | 5 | 50 | 6 | 33 | 12 | 12 | 12 | 12 | 6.62 | 85 Ohms | TOP=L2:L3=L2/L4:L6=L5/L7:BOTTOM=L7 |
| PCIE_TX_N78 | TX78-DIFF1 | PAIR | 1 | 5.38 | 5 | 10 | 5 | 50 | 6 | 33 | 12 | 12 | 12 | 12 | 6.62 | 85 Ohms | TOP=L2:L3=L2/L4:L6=L5/L7:BOTTOM=L7 |
| PCIE_TX_N78 | TX78-DIFF1 | PAIR | 2 | 5.5 | 5 | 10 | 5 | 50 | 6 | 20 | 12 | 12 | 12 | 12 | 7.5 | 85 Ohms | TOP=L2:L3=L2/L4:L6=L5/L7:BOTTOM=L7 |
| PCIE_TX_N78 | TX78-DIFF1 | PAIR | 3 | 5.5 | 5 | 10 | 5 | 50 | 6 | 20 | 12 | 12 | 12 | 12 | 7.5 | 85 Ohms | TOP=L2:L3=L2/L4:L6=L5/L7:BOTTOM=L7 |
| PCIE_TX_N78 | TX78-DIFF1 | PAIR | 4 | 5.5 | 5 | 10 | 5 | 50 | 6 | 20 | 12 | 12 | 12 | 12 | 7.5 | 85 Ohms | TOP=L2:L3=L2/L4:L6=L5/L7:BOTTOM=L7 |
| PCIE_TX_N78 | TX78-DIFF1 | PAIR | 5 | 5.5 | 5 | 10 | 5 | 50 | 6 | 20 | 12 | 12 | 12 | 12 | 7.5 | 85 Ohms | TOP=L2:L3=L2/L4:L6=L5/L7:BOTTOM=L7 |
| PCIE_TX_N78 | TX78-DIFF1 | PAIR | 6 | 5.5 | 5 | 10 | 5 | 50 | 6 | 20 | 12 | 12 | 12 | 12 | 7.5 | 85 Ohms | TOP=L2:L3=L2/L4:L6=L5/L7:BOTTOM=L7 |
| PCIE_TX_N78 | TX78-DIFF1 | PAIR | 7 | 5.5 | 5 | 10 | 5 | 50 | 6 | 20 | 12 | 12 | 12 | 12 | 7.5 | 85 Ohms | TOP=L2:L3=L2/L4:L6=L5/L7:BOTTOM=L7 |
| PCIE_TX_N78 | TX78-DIFF1 | PAIR | 8 | 5.38 | 5 | 10 | 5 | 50 | 6 | 33 | 12 | 12 | 12 | 12 | 6.62 | 85 Ohms | TOP=L2:L3=L2/L4:L6=L5/L7:BOTTOM=L7 |
| PCIE_TX_P78 | TX78-DIFF1 | PAIR | 1 | 5.38 | 5 | 10 | 5 | 50 | 6 | 33 | 12 | 12 | 12 | 12 | 6.62 | 85 Ohms | TOP=L2:L3=L2/L4:L6=L5/L7:BOTTOM=L7 |
| PCIE_TX_P78 | TX78-DIFF1 | PAIR | 2 | 5.5 | 5 | 10 | 5 | 50 | 6 | 20 | 12 | 12 | 12 | 12 | 7.5 | 85 Ohms | TOP=L2:L3=L2/L4:L6=L5/L7:BOTTOM=L7 |
| PCIE_TX_P78 | TX78-DIFF1 | PAIR | 3 | 5.5 | 5 | 10 | 5 | 50 | 6 | 20 | 12 | 12 | 12 | 12 | 7.5 | 85 Ohms | TOP=L2:L3=L2/L4:L6=L5/L7:BOTTOM=L7 |
| PCIE_TX_P78 | TX78-DIFF1 | PAIR | 4 | 5.5 | 5 | 10 | 5 | 50 | 6 | 20 | 12 | 12 | 12 | 12 | 7.5 | 85 Ohms | TOP=L2:L3=L2/L4:L6=L5/L7:BOTTOM=L7 |
| PCIE_TX_P78 | TX78-DIFF1 | PAIR | 5 | 5.5 | 5 | 10 | 5 | 50 | 6 | 20 | 12 | 12 | 12 | 12 | 7.5 | 85 Ohms | TOP=L2:L3=L2/L4:L6=L5/L7:BOTTOM=L7 |
| PCIE_TX_P78 | TX78-DIFF1 | PAIR | 6 | 5.5 | 5 | 10 | 5 | 50 | 6 | 20 | 12 | 12 | 12 | 12 | 7.5 | 85 Ohms | TOP=L2:L3=L2/L4:L6=L5/L7:BOTTOM=L7 |
| PCIE_TX_P78 | TX78-DIFF1 | PAIR | 7 | 5.5 | 5 | 10 | 5 | 50 | 6 | 20 | 12 | 12 | 12 | 12 | 7.5 | 85 Ohms | TOP=L2:L3=L2/L4:L6=L5/L7:BOTTOM=L7 |
| PCIE_TX_P78 | TX78-DIFF1 | PAIR | 8 | 5.38 | 5 | 10 | 5 | 50 | 6 | 33 | 12 | 12 | 12 | 12 | 6.62 | 85 Ohms | TOP=L2:L3=L2/L4:L6=L5/L7:BOTTOM=L7 |
| PCIE_TX_N7 | TX7-DIFF1 | PAIR | 1 | 5.38 | 5 | 10 | 5 | 50 | 6 | 33 | 12 | 12 | 12 | 12 | 6.62 | 85 Ohms | TOP=L2:L3=L2/L4:L6=L5/L7:BOTTOM=L7 |
| PCIE_TX_N7 | TX7-DIFF1 | PAIR | 2 | 5.5 | 5 | 10 | 5 | 50 | 6 | 20 | 12 | 12 | 12 | 12 | 7.5 | 85 Ohms | TOP=L2:L3=L2/L4:L6=L5/L7:BOTTOM=L7 |
| PCIE_TX_N7 | TX7-DIFF1 | PAIR | 3 | 5.5 | 5 | 10 | 5 | 50 | 6 | 20 | 12 | 12 | 12 | 12 | 7.5 | 85 Ohms | TOP=L2:L3=L2/L4:L6=L5/L7:BOTTOM=L7 |
| PCIE_TX_N7 | TX7-DIFF1 | PAIR | 4 | 5.5 | 5 | 10 | 5 | 50 | 6 | 20 | 12 | 12 | 12 | 12 | 7.5 | 85 Ohms | TOP=L2:L3=L2/L4:L6=L5/L7:BOTTOM=L7 |
| PCIE_TX_N7 | TX7-DIFF1 | PAIR | 5 | 5.5 | 5 | 10 | 5 | 50 | 6 | 20 | 12 | 12 | 12 | 12 | 7.5 | 85 Ohms | TOP=L2:L3=L2/L4:L6=L5/L7:BOTTOM=L7 |
| PCIE_TX_N7 | TX7-DIFF1 | PAIR | 6 | 5.5 | 5 | 10 | 5 | 50 | 6 | 20 | 12 | 12 | 12 | 12 | 7.5 | 85 Ohms | TOP=L2:L3=L2/L4:L6=L5/L7:BOTTOM=L7 |
| PCIE_TX_N7 | TX7-DIFF1 | PAIR | 7 | 5.5 | 5 | 10 | 5 | 50 | 6 | 20 | 12 | 12 | 12 | 12 | 7.5 | 85 Ohms | TOP=L2:L3=L2/L4:L6=L5/L7:BOTTOM=L7 |
| PCIE_TX_N7 | TX7-DIFF1 | PAIR | 8 | 5.38 | 5 | 10 | 5 | 50 | 6 | 33 | 12 | 12 | 12 | 12 | 6.62 | 85 Ohms | TOP=L2:L3=L2/L4:L6=L5/L7:BOTTOM=L7 |
| PCIE_TX_P7 | TX7-DIFF1 | PAIR | 1 | 5.38 | 5 | 10 | 5 | 50 | 6 | 33 | 12 | 12 | 12 | 12 | 6.62 | 85 Ohms | TOP=L2:L3=L2/L4:L6=L5/L7:BOTTOM=L7 |
| PCIE_TX_P7 | TX7-DIFF1 | PAIR | 2 | 5.5 | 5 | 10 | 5 | 50 | 6 | 20 | 12 | 12 | 12 | 12 | 7.5 | 85 Ohms | TOP=L2:L3=L2/L4:L6=L5/L7:BOTTOM=L7 |
| PCIE_TX_P7 | TX7-DIFF1 | PAIR | 3 | 5.5 | 5 | 10 | 5 | 50 | 6 | 20 | 12 | 12 | 12 | 12 | 7.5 | 85 Ohms | TOP=L2:L3=L2/L4:L6=L5/L7:BOTTOM=L7 |
| PCIE_TX_P7 | TX7-DIFF1 | PAIR | 4 | 5.5 | 5 | 10 | 5 | 50 | 6 | 20 | 12 | 12 | 12 | 12 | 7.5 | 85 Ohms | TOP=L2:L3=L2/L4:L6=L5/L7:BOTTOM=L7 |
| PCIE_TX_P7 | TX7-DIFF1 | PAIR | 5 | 5.5 | 5 | 10 | 5 | 50 | 6 | 20 | 12 | 12 | 12 | 12 | 7.5 | 85 Ohms | TOP=L2:L3=L2/L4:L6=L5/L7:BOTTOM=L7 |
| PCIE_TX_P7 | TX7-DIFF1 | PAIR | 6 | 5.5 | 5 | 10 | 5 | 50 | 6 | 20 | 12 | 12 | 12 | 12 | 7.5 | 85 Ohms | TOP=L2:L3=L2/L4:L6=L5/L7:BOTTOM=L7 |
| PCIE_TX_P7 | TX7-DIFF1 | PAIR | 7 | 5.5 | 5 | 10 | 5 | 50 | 6 | 20 | 12 | 12 | 12 | 12 | 7.5 | 85 Ohms | TOP=L2:L3=L2/L4:L6=L5/L7:BOTTOM=L7 |
| PCIE_TX_P7 | TX7-DIFF1 | PAIR | 8 | 5.38 | 5 | 10 | 5 | 50 | 6 | 33 | 12 | 12 | 12 | 12 | 6.62 | 85 Ohms | TOP=L2:L3=L2/L4:L6=L5/L7:BOTTOM=L7 |
| PCIE_TX_N80 | TX80-DIFF1 | PAIR | 1 | 5.38 | 5 | 10 | 5 | 50 | 6 | 33 | 12 | 12 | 12 | 12 | 6.62 | 85 Ohms | TOP=L2:L3=L2/L4:L6=L5/L7:BOTTOM=L7 |
| PCIE_TX_N80 | TX80-DIFF1 | PAIR | 2 | 5.5 | 5 | 10 | 5 | 50 | 6 | 20 | 12 | 12 | 12 | 12 | 7.5 | 85 Ohms | TOP=L2:L3=L2/L4:L6=L5/L7:BOTTOM=L7 |
| PCIE_TX_N80 | TX80-DIFF1 | PAIR | 3 | 5.5 | 5 | 10 | 5 | 50 | 6 | 20 | 12 | 12 | 12 | 12 | 7.5 | 85 Ohms | TOP=L2:L3=L2/L4:L6=L5/L7:BOTTOM=L7 |
| PCIE_TX_N80 | TX80-DIFF1 | PAIR | 4 | 5.5 | 5 | 10 | 5 | 50 | 6 | 20 | 12 | 12 | 12 | 12 | 7.5 | 85 Ohms | TOP=L2:L3=L2/L4:L6=L5/L7:BOTTOM=L7 |
| PCIE_TX_N80 | TX80-DIFF1 | PAIR | 5 | 5.5 | 5 | 10 | 5 | 50 | 6 | 20 | 12 | 12 | 12 | 12 | 7.5 | 85 Ohms | TOP=L2:L3=L2/L4:L6=L5/L7:BOTTOM=L7 |
| PCIE_TX_N80 | TX80-DIFF1 | PAIR | 6 | 5.5 | 5 | 10 | 5 | 50 | 6 | 20 | 12 | 12 | 12 | 12 | 7.5 | 85 Ohms | TOP=L2:L3=L2/L4:L6=L5/L7:BOTTOM=L7 |
| PCIE_TX_N80 | TX80-DIFF1 | PAIR | 7 | 5.5 | 5 | 10 | 5 | 50 | 6 | 20 | 12 | 12 | 12 | 12 | 7.5 | 85 Ohms | TOP=L2:L3=L2/L4:L6=L5/L7:BOTTOM=L7 |
| PCIE_TX_N80 | TX80-DIFF1 | PAIR | 8 | 5.38 | 5 | 10 | 5 | 50 | 6 | 33 | 12 | 12 | 12 | 12 | 6.62 | 85 Ohms | TOP=L2:L3=L2/L4:L6=L5/L7:BOTTOM=L7 |
| PCIE_TX_P80 | TX80-DIFF1 | PAIR | 1 | 5.38 | 5 | 10 | 5 | 50 | 6 | 33 | 12 | 12 | 12 | 12 | 6.62 | 85 Ohms | TOP=L2:L3=L2/L4:L6=L5/L7:BOTTOM=L7 |
| PCIE_TX_P80 | TX80-DIFF1 | PAIR | 2 | 5.5 | 5 | 10 | 5 | 50 | 6 | 20 | 12 | 12 | 12 | 12 | 7.5 | 85 Ohms | TOP=L2:L3=L2/L4:L6=L5/L7:BOTTOM=L7 |
| PCIE_TX_P80 | TX80-DIFF1 | PAIR | 3 | 5.5 | 5 | 10 | 5 | 50 | 6 | 20 | 12 | 12 | 12 | 12 | 7.5 | 85 Ohms | TOP=L2:L3=L2/L4:L6=L5/L7:BOTTOM=L7 |
| PCIE_TX_P80 | TX80-DIFF1 | PAIR | 4 | 5.5 | 5 | 10 | 5 | 50 | 6 | 20 | 12 | 12 | 12 | 12 | 7.5 | 85 Ohms | TOP=L2:L3=L2/L4:L6=L5/L7:BOTTOM=L7 |
| PCIE_TX_P80 | TX80-DIFF1 | PAIR | 5 | 5.5 | 5 | 10 | 5 | 50 | 6 | 20 | 12 | 12 | 12 | 12 | 7.5 | 85 Ohms | TOP=L2:L3=L2/L4:L6=L5/L7:BOTTOM=L7 |
| PCIE_TX_P80 | TX80-DIFF1 | PAIR | 6 | 5.5 | 5 | 10 | 5 | 50 | 6 | 20 | 12 | 12 | 12 | 12 | 7.5 | 85 Ohms | TOP=L2:L3=L2/L4:L6=L5/L7:BOTTOM=L7 |
| PCIE_TX_P80 | TX80-DIFF1 | PAIR | 7 | 5.5 | 5 | 10 | 5 | 50 | 6 | 20 | 12 | 12 | 12 | 12 | 7.5 | 85 Ohms | TOP=L2:L3=L2/L4:L6=L5/L7:BOTTOM=L7 |
| PCIE_TX_P80 | TX80-DIFF1 | PAIR | 8 | 5.38 | 5 | 10 | 5 | 50 | 6 | 33 | 12 | 12 | 12 | 12 | 6.62 | 85 Ohms | TOP=L2:L3=L2/L4:L6=L5/L7:BOTTOM=L7 |
| PCIE_TX_N81 | TX81-DIFF1 | PAIR | 1 | 5.38 | 5 | 10 | 5 | 50 | 6 | 33 | 12 | 12 | 12 | 12 | 6.62 | 85 Ohms | TOP=L2:L3=L2/L4:L6=L5/L7:BOTTOM=L7 |
| PCIE_TX_N81 | TX81-DIFF1 | PAIR | 2 | 5.5 | 5 | 10 | 5 | 50 | 6 | 20 | 12 | 12 | 12 | 12 | 7.5 | 85 Ohms | TOP=L2:L3=L2/L4:L6=L5/L7:BOTTOM=L7 |
| PCIE_TX_N81 | TX81-DIFF1 | PAIR | 3 | 5.5 | 5 | 10 | 5 | 50 | 6 | 20 | 12 | 12 | 12 | 12 | 7.5 | 85 Ohms | TOP=L2:L3=L2/L4:L6=L5/L7:BOTTOM=L7 |
| PCIE_TX_N81 | TX81-DIFF1 | PAIR | 4 | 5.5 | 5 | 10 | 5 | 50 | 6 | 20 | 12 | 12 | 12 | 12 | 7.5 | 85 Ohms | TOP=L2:L3=L2/L4:L6=L5/L7:BOTTOM=L7 |
| PCIE_TX_N81 | TX81-DIFF1 | PAIR | 5 | 5.5 | 5 | 10 | 5 | 50 | 6 | 20 | 12 | 12 | 12 | 12 | 7.5 | 85 Ohms | TOP=L2:L3=L2/L4:L6=L5/L7:BOTTOM=L7 |
| PCIE_TX_N81 | TX81-DIFF1 | PAIR | 6 | 5.5 | 5 | 10 | 5 | 50 | 6 | 20 | 12 | 12 | 12 | 12 | 7.5 | 85 Ohms | TOP=L2:L3=L2/L4:L6=L5/L7:BOTTOM=L7 |
| PCIE_TX_N81 | TX81-DIFF1 | PAIR | 7 | 5.5 | 5 | 10 | 5 | 50 | 6 | 20 | 12 | 12 | 12 | 12 | 7.5 | 85 Ohms | TOP=L2:L3=L2/L4:L6=L5/L7:BOTTOM=L7 |
| PCIE_TX_N81 | TX81-DIFF1 | PAIR | 8 | 5.38 | 5 | 10 | 5 | 50 | 6 | 33 | 12 | 12 | 12 | 12 | 6.62 | 85 Ohms | TOP=L2:L3=L2/L4:L6=L5/L7:BOTTOM=L7 |
| PCIE_TX_P81 | TX81-DIFF1 | PAIR | 1 | 5.38 | 5 | 10 | 5 | 50 | 6 | 33 | 12 | 12 | 12 | 12 | 6.62 | 85 Ohms | TOP=L2:L3=L2/L4:L6=L5/L7:BOTTOM=L7 |
| PCIE_TX_P81 | TX81-DIFF1 | PAIR | 2 | 5.5 | 5 | 10 | 5 | 50 | 6 | 20 | 12 | 12 | 12 | 12 | 7.5 | 85 Ohms | TOP=L2:L3=L2/L4:L6=L5/L7:BOTTOM=L7 |
| PCIE_TX_P81 | TX81-DIFF1 | PAIR | 3 | 5.5 | 5 | 10 | 5 | 50 | 6 | 20 | 12 | 12 | 12 | 12 | 7.5 | 85 Ohms | TOP=L2:L3=L2/L4:L6=L5/L7:BOTTOM=L7 |
| PCIE_TX_P81 | TX81-DIFF1 | PAIR | 4 | 5.5 | 5 | 10 | 5 | 50 | 6 | 20 | 12 | 12 | 12 | 12 | 7.5 | 85 Ohms | TOP=L2:L3=L2/L4:L6=L5/L7:BOTTOM=L7 |
| PCIE_TX_P81 | TX81-DIFF1 | PAIR | 5 | 5.5 | 5 | 10 | 5 | 50 | 6 | 20 | 12 | 12 | 12 | 12 | 7.5 | 85 Ohms | TOP=L2:L3=L2/L4:L6=L5/L7:BOTTOM=L7 |
| PCIE_TX_P81 | TX81-DIFF1 | PAIR | 6 | 5.5 | 5 | 10 | 5 | 50 | 6 | 20 | 12 | 12 | 12 | 12 | 7.5 | 85 Ohms | TOP=L2:L3=L2/L4:L6=L5/L7:BOTTOM=L7 |
| PCIE_TX_P81 | TX81-DIFF1 | PAIR | 7 | 5.5 | 5 | 10 | 5 | 50 | 6 | 20 | 12 | 12 | 12 | 12 | 7.5 | 85 Ohms | TOP=L2:L3=L2/L4:L6=L5/L7:BOTTOM=L7 |
| PCIE_TX_P81 | TX81-DIFF1 | PAIR | 8 | 5.38 | 5 | 10 | 5 | 50 | 6 | 33 | 12 | 12 | 12 | 12 | 6.62 | 85 Ohms | TOP=L2:L3=L2/L4:L6=L5/L7:BOTTOM=L7 |
| PCIE_TX_N82 | TX82-DIFF1 | PAIR | 1 | 5.38 | 5 | 10 | 5 | 50 | 6 | 33 | 12 | 12 | 12 | 12 | 6.62 | 85 Ohms | TOP=L2:L3=L2/L4:L6=L5/L7:BOTTOM=L7 |
| PCIE_TX_N82 | TX82-DIFF1 | PAIR | 2 | 5.5 | 5 | 10 | 5 | 50 | 6 | 20 | 12 | 12 | 12 | 12 | 7.5 | 85 Ohms | TOP=L2:L3=L2/L4:L6=L5/L7:BOTTOM=L7 |
| PCIE_TX_N82 | TX82-DIFF1 | PAIR | 3 | 5.5 | 5 | 10 | 5 | 50 | 6 | 20 | 12 | 12 | 12 | 12 | 7.5 | 85 Ohms | TOP=L2:L3=L2/L4:L6=L5/L7:BOTTOM=L7 |
| PCIE_TX_N82 | TX82-DIFF1 | PAIR | 4 | 5.5 | 5 | 10 | 5 | 50 | 6 | 20 | 12 | 12 | 12 | 12 | 7.5 | 85 Ohms | TOP=L2:L3=L2/L4:L6=L5/L7:BOTTOM=L7 |
| PCIE_TX_N82 | TX82-DIFF1 | PAIR | 5 | 5.5 | 5 | 10 | 5 | 50 | 6 | 20 | 12 | 12 | 12 | 12 | 7.5 | 85 Ohms | TOP=L2:L3=L2/L4:L6=L5/L7:BOTTOM=L7 |
| PCIE_TX_N82 | TX82-DIFF1 | PAIR | 6 | 5.5 | 5 | 10 | 5 | 50 | 6 | 20 | 12 | 12 | 12 | 12 | 7.5 | 85 Ohms | TOP=L2:L3=L2/L4:L6=L5/L7:BOTTOM=L7 |
| PCIE_TX_N82 | TX82-DIFF1 | PAIR | 7 | 5.5 | 5 | 10 | 5 | 50 | 6 | 20 | 12 | 12 | 12 | 12 | 7.5 | 85 Ohms | TOP=L2:L3=L2/L4:L6=L5/L7:BOTTOM=L7 |
| PCIE_TX_N82 | TX82-DIFF1 | PAIR | 8 | 5.38 | 5 | 10 | 5 | 50 | 6 | 33 | 12 | 12 | 12 | 12 | 6.62 | 85 Ohms | TOP=L2:L3=L2/L4:L6=L5/L7:BOTTOM=L7 |
| PCIE_TX_P82 | TX82-DIFF1 | PAIR | 1 | 5.38 | 5 | 10 | 5 | 50 | 6 | 33 | 12 | 12 | 12 | 12 | 6.62 | 85 Ohms | TOP=L2:L3=L2/L4:L6=L5/L7:BOTTOM=L7 |
| PCIE_TX_P82 | TX82-DIFF1 | PAIR | 2 | 5.5 | 5 | 10 | 5 | 50 | 6 | 20 | 12 | 12 | 12 | 12 | 7.5 | 85 Ohms | TOP=L2:L3=L2/L4:L6=L5/L7:BOTTOM=L7 |
| PCIE_TX_P82 | TX82-DIFF1 | PAIR | 3 | 5.5 | 5 | 10 | 5 | 50 | 6 | 20 | 12 | 12 | 12 | 12 | 7.5 | 85 Ohms | TOP=L2:L3=L2/L4:L6=L5/L7:BOTTOM=L7 |
| PCIE_TX_P82 | TX82-DIFF1 | PAIR | 4 | 5.5 | 5 | 10 | 5 | 50 | 6 | 20 | 12 | 12 | 12 | 12 | 7.5 | 85 Ohms | TOP=L2:L3=L2/L4:L6=L5/L7:BOTTOM=L7 |
| PCIE_TX_P82 | TX82-DIFF1 | PAIR | 5 | 5.5 | 5 | 10 | 5 | 50 | 6 | 20 | 12 | 12 | 12 | 12 | 7.5 | 85 Ohms | TOP=L2:L3=L2/L4:L6=L5/L7:BOTTOM=L7 |
| PCIE_TX_P82 | TX82-DIFF1 | PAIR | 6 | 5.5 | 5 | 10 | 5 | 50 | 6 | 20 | 12 | 12 | 12 | 12 | 7.5 | 85 Ohms | TOP=L2:L3=L2/L4:L6=L5/L7:BOTTOM=L7 |
| PCIE_TX_P82 | TX82-DIFF1 | PAIR | 7 | 5.5 | 5 | 10 | 5 | 50 | 6 | 20 | 12 | 12 | 12 | 12 | 7.5 | 85 Ohms | TOP=L2:L3=L2/L4:L6=L5/L7:BOTTOM=L7 |
| PCIE_TX_P82 | TX82-DIFF1 | PAIR | 8 | 5.38 | 5 | 10 | 5 | 50 | 6 | 33 | 12 | 12 | 12 | 12 | 6.62 | 85 Ohms | TOP=L2:L3=L2/L4:L6=L5/L7:BOTTOM=L7 |
| PCIE_TX_N83 | TX83-DIFF1 | PAIR | 1 | 5.38 | 5 | 10 | 5 | 50 | 6 | 33 | 12 | 12 | 12 | 12 | 6.62 | 85 Ohms | TOP=L2:L3=L2/L4:L6=L5/L7:BOTTOM=L7 |
| PCIE_TX_N83 | TX83-DIFF1 | PAIR | 2 | 5.5 | 5 | 10 | 5 | 50 | 6 | 20 | 12 | 12 | 12 | 12 | 7.5 | 85 Ohms | TOP=L2:L3=L2/L4:L6=L5/L7:BOTTOM=L7 |
| PCIE_TX_N83 | TX83-DIFF1 | PAIR | 3 | 5.5 | 5 | 10 | 5 | 50 | 6 | 20 | 12 | 12 | 12 | 12 | 7.5 | 85 Ohms | TOP=L2:L3=L2/L4:L6=L5/L7:BOTTOM=L7 |
| PCIE_TX_N83 | TX83-DIFF1 | PAIR | 4 | 5.5 | 5 | 10 | 5 | 50 | 6 | 20 | 12 | 12 | 12 | 12 | 7.5 | 85 Ohms | TOP=L2:L3=L2/L4:L6=L5/L7:BOTTOM=L7 |
| PCIE_TX_N83 | TX83-DIFF1 | PAIR | 5 | 5.5 | 5 | 10 | 5 | 50 | 6 | 20 | 12 | 12 | 12 | 12 | 7.5 | 85 Ohms | TOP=L2:L3=L2/L4:L6=L5/L7:BOTTOM=L7 |
| PCIE_TX_N83 | TX83-DIFF1 | PAIR | 6 | 5.5 | 5 | 10 | 5 | 50 | 6 | 20 | 12 | 12 | 12 | 12 | 7.5 | 85 Ohms | TOP=L2:L3=L2/L4:L6=L5/L7:BOTTOM=L7 |
| PCIE_TX_N83 | TX83-DIFF1 | PAIR | 7 | 5.5 | 5 | 10 | 5 | 50 | 6 | 20 | 12 | 12 | 12 | 12 | 7.5 | 85 Ohms | TOP=L2:L3=L2/L4:L6=L5/L7:BOTTOM=L7 |
| PCIE_TX_N83 | TX83-DIFF1 | PAIR | 8 | 5.38 | 5 | 10 | 5 | 50 | 6 | 33 | 12 | 12 | 12 | 12 | 6.62 | 85 Ohms | TOP=L2:L3=L2/L4:L6=L5/L7:BOTTOM=L7 |
| PCIE_TX_P83 | TX83-DIFF1 | PAIR | 1 | 5.38 | 5 | 10 | 5 | 50 | 6 | 33 | 12 | 12 | 12 | 12 | 6.62 | 85 Ohms | TOP=L2:L3=L2/L4:L6=L5/L7:BOTTOM=L7 |
| PCIE_TX_P83 | TX83-DIFF1 | PAIR | 2 | 5.5 | 5 | 10 | 5 | 50 | 6 | 20 | 12 | 12 | 12 | 12 | 7.5 | 85 Ohms | TOP=L2:L3=L2/L4:L6=L5/L7:BOTTOM=L7 |
| PCIE_TX_P83 | TX83-DIFF1 | PAIR | 3 | 5.5 | 5 | 10 | 5 | 50 | 6 | 20 | 12 | 12 | 12 | 12 | 7.5 | 85 Ohms | TOP=L2:L3=L2/L4:L6=L5/L7:BOTTOM=L7 |
| PCIE_TX_P83 | TX83-DIFF1 | PAIR | 4 | 5.5 | 5 | 10 | 5 | 50 | 6 | 20 | 12 | 12 | 12 | 12 | 7.5 | 85 Ohms | TOP=L2:L3=L2/L4:L6=L5/L7:BOTTOM=L7 |
| PCIE_TX_P83 | TX83-DIFF1 | PAIR | 5 | 5.5 | 5 | 10 | 5 | 50 | 6 | 20 | 12 | 12 | 12 | 12 | 7.5 | 85 Ohms | TOP=L2:L3=L2/L4:L6=L5/L7:BOTTOM=L7 |
| PCIE_TX_P83 | TX83-DIFF1 | PAIR | 6 | 5.5 | 5 | 10 | 5 | 50 | 6 | 20 | 12 | 12 | 12 | 12 | 7.5 | 85 Ohms | TOP=L2:L3=L2/L4:L6=L5/L7:BOTTOM=L7 |
| PCIE_TX_P83 | TX83-DIFF1 | PAIR | 7 | 5.5 | 5 | 10 | 5 | 50 | 6 | 20 | 12 | 12 | 12 | 12 | 7.5 | 85 Ohms | TOP=L2:L3=L2/L4:L6=L5/L7:BOTTOM=L7 |
| PCIE_TX_P83 | TX83-DIFF1 | PAIR | 8 | 5.38 | 5 | 10 | 5 | 50 | 6 | 33 | 12 | 12 | 12 | 12 | 6.62 | 85 Ohms | TOP=L2:L3=L2/L4:L6=L5/L7:BOTTOM=L7 |
| PCIE_TX_N84 | TX84-DIFF1 | PAIR | 1 | 5.38 | 5 | 10 | 5 | 50 | 6 | 33 | 12 | 12 | 12 | 12 | 6.62 | 85 Ohms | TOP=L2:L3=L2/L4:L6=L5/L7:BOTTOM=L7 |
| PCIE_TX_N84 | TX84-DIFF1 | PAIR | 2 | 5.5 | 5 | 10 | 5 | 50 | 6 | 20 | 12 | 12 | 12 | 12 | 7.5 | 85 Ohms | TOP=L2:L3=L2/L4:L6=L5/L7:BOTTOM=L7 |
| PCIE_TX_N84 | TX84-DIFF1 | PAIR | 3 | 5.5 | 5 | 10 | 5 | 50 | 6 | 20 | 12 | 12 | 12 | 12 | 7.5 | 85 Ohms | TOP=L2:L3=L2/L4:L6=L5/L7:BOTTOM=L7 |
| PCIE_TX_N84 | TX84-DIFF1 | PAIR | 4 | 5.5 | 5 | 10 | 5 | 50 | 6 | 20 | 12 | 12 | 12 | 12 | 7.5 | 85 Ohms | TOP=L2:L3=L2/L4:L6=L5/L7:BOTTOM=L7 |
| PCIE_TX_N84 | TX84-DIFF1 | PAIR | 5 | 5.5 | 5 | 10 | 5 | 50 | 6 | 20 | 12 | 12 | 12 | 12 | 7.5 | 85 Ohms | TOP=L2:L3=L2/L4:L6=L5/L7:BOTTOM=L7 |
| PCIE_TX_N84 | TX84-DIFF1 | PAIR | 6 | 5.5 | 5 | 10 | 5 | 50 | 6 | 20 | 12 | 12 | 12 | 12 | 7.5 | 85 Ohms | TOP=L2:L3=L2/L4:L6=L5/L7:BOTTOM=L7 |
| PCIE_TX_N84 | TX84-DIFF1 | PAIR | 7 | 5.5 | 5 | 10 | 5 | 50 | 6 | 20 | 12 | 12 | 12 | 12 | 7.5 | 85 Ohms | TOP=L2:L3=L2/L4:L6=L5/L7:BOTTOM=L7 |
| PCIE_TX_N84 | TX84-DIFF1 | PAIR | 8 | 5.38 | 5 | 10 | 5 | 50 | 6 | 33 | 12 | 12 | 12 | 12 | 6.62 | 85 Ohms | TOP=L2:L3=L2/L4:L6=L5/L7:BOTTOM=L7 |
| PCIE_TX_P84 | TX84-DIFF1 | PAIR | 1 | 5.38 | 5 | 10 | 5 | 50 | 6 | 33 | 12 | 12 | 12 | 12 | 6.62 | 85 Ohms | TOP=L2:L3=L2/L4:L6=L5/L7:BOTTOM=L7 |
| PCIE_TX_P84 | TX84-DIFF1 | PAIR | 2 | 5.5 | 5 | 10 | 5 | 50 | 6 | 20 | 12 | 12 | 12 | 12 | 7.5 | 85 Ohms | TOP=L2:L3=L2/L4:L6=L5/L7:BOTTOM=L7 |
| PCIE_TX_P84 | TX84-DIFF1 | PAIR | 3 | 5.5 | 5 | 10 | 5 | 50 | 6 | 20 | 12 | 12 | 12 | 12 | 7.5 | 85 Ohms | TOP=L2:L3=L2/L4:L6=L5/L7:BOTTOM=L7 |
| PCIE_TX_P84 | TX84-DIFF1 | PAIR | 4 | 5.5 | 5 | 10 | 5 | 50 | 6 | 20 | 12 | 12 | 12 | 12 | 7.5 | 85 Ohms | TOP=L2:L3=L2/L4:L6=L5/L7:BOTTOM=L7 |
| PCIE_TX_P84 | TX84-DIFF1 | PAIR | 5 | 5.5 | 5 | 10 | 5 | 50 | 6 | 20 | 12 | 12 | 12 | 12 | 7.5 | 85 Ohms | TOP=L2:L3=L2/L4:L6=L5/L7:BOTTOM=L7 |
| PCIE_TX_P84 | TX84-DIFF1 | PAIR | 6 | 5.5 | 5 | 10 | 5 | 50 | 6 | 20 | 12 | 12 | 12 | 12 | 7.5 | 85 Ohms | TOP=L2:L3=L2/L4:L6=L5/L7:BOTTOM=L7 |
| PCIE_TX_P84 | TX84-DIFF1 | PAIR | 7 | 5.5 | 5 | 10 | 5 | 50 | 6 | 20 | 12 | 12 | 12 | 12 | 7.5 | 85 Ohms | TOP=L2:L3=L2/L4:L6=L5/L7:BOTTOM=L7 |
| PCIE_TX_P84 | TX84-DIFF1 | PAIR | 8 | 5.38 | 5 | 10 | 5 | 50 | 6 | 33 | 12 | 12 | 12 | 12 | 6.62 | 85 Ohms | TOP=L2:L3=L2/L4:L6=L5/L7:BOTTOM=L7 |
| PCIE_TX_N85 | TX85-DIFF1 | PAIR | 1 | 5.38 | 5 | 10 | 5 | 50 | 6 | 33 | 12 | 12 | 12 | 12 | 6.62 | 85 Ohms | TOP=L2:L3=L2/L4:L6=L5/L7:BOTTOM=L7 |
| PCIE_TX_N85 | TX85-DIFF1 | PAIR | 2 | 5.5 | 5 | 10 | 5 | 50 | 6 | 20 | 12 | 12 | 12 | 12 | 7.5 | 85 Ohms | TOP=L2:L3=L2/L4:L6=L5/L7:BOTTOM=L7 |
| PCIE_TX_N85 | TX85-DIFF1 | PAIR | 3 | 5.5 | 5 | 10 | 5 | 50 | 6 | 20 | 12 | 12 | 12 | 12 | 7.5 | 85 Ohms | TOP=L2:L3=L2/L4:L6=L5/L7:BOTTOM=L7 |
| PCIE_TX_N85 | TX85-DIFF1 | PAIR | 4 | 5.5 | 5 | 10 | 5 | 50 | 6 | 20 | 12 | 12 | 12 | 12 | 7.5 | 85 Ohms | TOP=L2:L3=L2/L4:L6=L5/L7:BOTTOM=L7 |
| PCIE_TX_N85 | TX85-DIFF1 | PAIR | 5 | 5.5 | 5 | 10 | 5 | 50 | 6 | 20 | 12 | 12 | 12 | 12 | 7.5 | 85 Ohms | TOP=L2:L3=L2/L4:L6=L5/L7:BOTTOM=L7 |
| PCIE_TX_N85 | TX85-DIFF1 | PAIR | 6 | 5.5 | 5 | 10 | 5 | 50 | 6 | 20 | 12 | 12 | 12 | 12 | 7.5 | 85 Ohms | TOP=L2:L3=L2/L4:L6=L5/L7:BOTTOM=L7 |
| PCIE_TX_N85 | TX85-DIFF1 | PAIR | 7 | 5.5 | 5 | 10 | 5 | 50 | 6 | 20 | 12 | 12 | 12 | 12 | 7.5 | 85 Ohms | TOP=L2:L3=L2/L4:L6=L5/L7:BOTTOM=L7 |
| PCIE_TX_N85 | TX85-DIFF1 | PAIR | 8 | 5.38 | 5 | 10 | 5 | 50 | 6 | 33 | 12 | 12 | 12 | 12 | 6.62 | 85 Ohms | TOP=L2:L3=L2/L4:L6=L5/L7:BOTTOM=L7 |
| PCIE_TX_P85 | TX85-DIFF1 | PAIR | 1 | 5.38 | 5 | 10 | 5 | 50 | 6 | 33 | 12 | 12 | 12 | 12 | 6.62 | 85 Ohms | TOP=L2:L3=L2/L4:L6=L5/L7:BOTTOM=L7 |
| PCIE_TX_P85 | TX85-DIFF1 | PAIR | 2 | 5.5 | 5 | 10 | 5 | 50 | 6 | 20 | 12 | 12 | 12 | 12 | 7.5 | 85 Ohms | TOP=L2:L3=L2/L4:L6=L5/L7:BOTTOM=L7 |
| PCIE_TX_P85 | TX85-DIFF1 | PAIR | 3 | 5.5 | 5 | 10 | 5 | 50 | 6 | 20 | 12 | 12 | 12 | 12 | 7.5 | 85 Ohms | TOP=L2:L3=L2/L4:L6=L5/L7:BOTTOM=L7 |
| PCIE_TX_P85 | TX85-DIFF1 | PAIR | 4 | 5.5 | 5 | 10 | 5 | 50 | 6 | 20 | 12 | 12 | 12 | 12 | 7.5 | 85 Ohms | TOP=L2:L3=L2/L4:L6=L5/L7:BOTTOM=L7 |
| PCIE_TX_P85 | TX85-DIFF1 | PAIR | 5 | 5.5 | 5 | 10 | 5 | 50 | 6 | 20 | 12 | 12 | 12 | 12 | 7.5 | 85 Ohms | TOP=L2:L3=L2/L4:L6=L5/L7:BOTTOM=L7 |
| PCIE_TX_P85 | TX85-DIFF1 | PAIR | 6 | 5.5 | 5 | 10 | 5 | 50 | 6 | 20 | 12 | 12 | 12 | 12 | 7.5 | 85 Ohms | TOP=L2:L3=L2/L4:L6=L5/L7:BOTTOM=L7 |
| PCIE_TX_P85 | TX85-DIFF1 | PAIR | 7 | 5.5 | 5 | 10 | 5 | 50 | 6 | 20 | 12 | 12 | 12 | 12 | 7.5 | 85 Ohms | TOP=L2:L3=L2/L4:L6=L5/L7:BOTTOM=L7 |
| PCIE_TX_P85 | TX85-DIFF1 | PAIR | 8 | 5.38 | 5 | 10 | 5 | 50 | 6 | 33 | 12 | 12 | 12 | 12 | 6.62 | 85 Ohms | TOP=L2:L3=L2/L4:L6=L5/L7:BOTTOM=L7 |
| PCIE_TX_N86 | TX86-DIFF1 | PAIR | 1 | 5.38 | 5 | 10 | 5 | 50 | 6 | 33 | 12 | 12 | 12 | 12 | 6.62 | 85 Ohms | TOP=L2:L3=L2/L4:L6=L5/L7:BOTTOM=L7 |
| PCIE_TX_N86 | TX86-DIFF1 | PAIR | 2 | 5.5 | 5 | 10 | 5 | 50 | 6 | 20 | 12 | 12 | 12 | 12 | 7.5 | 85 Ohms | TOP=L2:L3=L2/L4:L6=L5/L7:BOTTOM=L7 |
| PCIE_TX_N86 | TX86-DIFF1 | PAIR | 3 | 5.5 | 5 | 10 | 5 | 50 | 6 | 20 | 12 | 12 | 12 | 12 | 7.5 | 85 Ohms | TOP=L2:L3=L2/L4:L6=L5/L7:BOTTOM=L7 |
| PCIE_TX_N86 | TX86-DIFF1 | PAIR | 4 | 5.5 | 5 | 10 | 5 | 50 | 6 | 20 | 12 | 12 | 12 | 12 | 7.5 | 85 Ohms | TOP=L2:L3=L2/L4:L6=L5/L7:BOTTOM=L7 |
| PCIE_TX_N86 | TX86-DIFF1 | PAIR | 5 | 5.5 | 5 | 10 | 5 | 50 | 6 | 20 | 12 | 12 | 12 | 12 | 7.5 | 85 Ohms | TOP=L2:L3=L2/L4:L6=L5/L7:BOTTOM=L7 |
| PCIE_TX_N86 | TX86-DIFF1 | PAIR | 6 | 5.5 | 5 | 10 | 5 | 50 | 6 | 20 | 12 | 12 | 12 | 12 | 7.5 | 85 Ohms | TOP=L2:L3=L2/L4:L6=L5/L7:BOTTOM=L7 |
| PCIE_TX_N86 | TX86-DIFF1 | PAIR | 7 | 5.5 | 5 | 10 | 5 | 50 | 6 | 20 | 12 | 12 | 12 | 12 | 7.5 | 85 Ohms | TOP=L2:L3=L2/L4:L6=L5/L7:BOTTOM=L7 |
| PCIE_TX_N86 | TX86-DIFF1 | PAIR | 8 | 5.38 | 5 | 10 | 5 | 50 | 6 | 33 | 12 | 12 | 12 | 12 | 6.62 | 85 Ohms | TOP=L2:L3=L2/L4:L6=L5/L7:BOTTOM=L7 |
| PCIE_TX_P86 | TX86-DIFF1 | PAIR | 1 | 5.38 | 5 | 10 | 5 | 50 | 6 | 33 | 12 | 12 | 12 | 12 | 6.62 | 85 Ohms | TOP=L2:L3=L2/L4:L6=L5/L7:BOTTOM=L7 |
| PCIE_TX_P86 | TX86-DIFF1 | PAIR | 2 | 5.5 | 5 | 10 | 5 | 50 | 6 | 20 | 12 | 12 | 12 | 12 | 7.5 | 85 Ohms | TOP=L2:L3=L2/L4:L6=L5/L7:BOTTOM=L7 |
| PCIE_TX_P86 | TX86-DIFF1 | PAIR | 3 | 5.5 | 5 | 10 | 5 | 50 | 6 | 20 | 12 | 12 | 12 | 12 | 7.5 | 85 Ohms | TOP=L2:L3=L2/L4:L6=L5/L7:BOTTOM=L7 |
| PCIE_TX_P86 | TX86-DIFF1 | PAIR | 4 | 5.5 | 5 | 10 | 5 | 50 | 6 | 20 | 12 | 12 | 12 | 12 | 7.5 | 85 Ohms | TOP=L2:L3=L2/L4:L6=L5/L7:BOTTOM=L7 |
| PCIE_TX_P86 | TX86-DIFF1 | PAIR | 5 | 5.5 | 5 | 10 | 5 | 50 | 6 | 20 | 12 | 12 | 12 | 12 | 7.5 | 85 Ohms | TOP=L2:L3=L2/L4:L6=L5/L7:BOTTOM=L7 |
| PCIE_TX_P86 | TX86-DIFF1 | PAIR | 6 | 5.5 | 5 | 10 | 5 | 50 | 6 | 20 | 12 | 12 | 12 | 12 | 7.5 | 85 Ohms | TOP=L2:L3=L2/L4:L6=L5/L7:BOTTOM=L7 |
| PCIE_TX_P86 | TX86-DIFF1 | PAIR | 7 | 5.5 | 5 | 10 | 5 | 50 | 6 | 20 | 12 | 12 | 12 | 12 | 7.5 | 85 Ohms | TOP=L2:L3=L2/L4:L6=L5/L7:BOTTOM=L7 |
| PCIE_TX_P86 | TX86-DIFF1 | PAIR | 8 | 5.38 | 5 | 10 | 5 | 50 | 6 | 33 | 12 | 12 | 12 | 12 | 6.62 | 85 Ohms | TOP=L2:L3=L2/L4:L6=L5/L7:BOTTOM=L7 |
| PCIE_TX_N87 | TX87-DIFF1 | PAIR | 1 | 5.38 | 5 | 10 | 5 | 50 | 6 | 33 | 12 | 12 | 12 | 12 | 6.62 | 85 Ohms | TOP=L2:L3=L2/L4:L6=L5/L7:BOTTOM=L7 |
| PCIE_TX_N87 | TX87-DIFF1 | PAIR | 2 | 5.5 | 5 | 10 | 5 | 50 | 6 | 20 | 12 | 12 | 12 | 12 | 7.5 | 85 Ohms | TOP=L2:L3=L2/L4:L6=L5/L7:BOTTOM=L7 |
| PCIE_TX_N87 | TX87-DIFF1 | PAIR | 3 | 5.5 | 5 | 10 | 5 | 50 | 6 | 20 | 12 | 12 | 12 | 12 | 7.5 | 85 Ohms | TOP=L2:L3=L2/L4:L6=L5/L7:BOTTOM=L7 |
| PCIE_TX_N87 | TX87-DIFF1 | PAIR | 4 | 5.5 | 5 | 10 | 5 | 50 | 6 | 20 | 12 | 12 | 12 | 12 | 7.5 | 85 Ohms | TOP=L2:L3=L2/L4:L6=L5/L7:BOTTOM=L7 |
| PCIE_TX_N87 | TX87-DIFF1 | PAIR | 5 | 5.5 | 5 | 10 | 5 | 50 | 6 | 20 | 12 | 12 | 12 | 12 | 7.5 | 85 Ohms | TOP=L2:L3=L2/L4:L6=L5/L7:BOTTOM=L7 |
| PCIE_TX_N87 | TX87-DIFF1 | PAIR | 6 | 5.5 | 5 | 10 | 5 | 50 | 6 | 20 | 12 | 12 | 12 | 12 | 7.5 | 85 Ohms | TOP=L2:L3=L2/L4:L6=L5/L7:BOTTOM=L7 |
| PCIE_TX_N87 | TX87-DIFF1 | PAIR | 7 | 5.5 | 5 | 10 | 5 | 50 | 6 | 20 | 12 | 12 | 12 | 12 | 7.5 | 85 Ohms | TOP=L2:L3=L2/L4:L6=L5/L7:BOTTOM=L7 |
| PCIE_TX_N87 | TX87-DIFF1 | PAIR | 8 | 5.38 | 5 | 10 | 5 | 50 | 6 | 33 | 12 | 12 | 12 | 12 | 6.62 | 85 Ohms | TOP=L2:L3=L2/L4:L6=L5/L7:BOTTOM=L7 |
| PCIE_TX_P87 | TX87-DIFF1 | PAIR | 1 | 5.38 | 5 | 10 | 5 | 50 | 6 | 33 | 12 | 12 | 12 | 12 | 6.62 | 85 Ohms | TOP=L2:L3=L2/L4:L6=L5/L7:BOTTOM=L7 |
| PCIE_TX_P87 | TX87-DIFF1 | PAIR | 2 | 5.5 | 5 | 10 | 5 | 50 | 6 | 20 | 12 | 12 | 12 | 12 | 7.5 | 85 Ohms | TOP=L2:L3=L2/L4:L6=L5/L7:BOTTOM=L7 |
| PCIE_TX_P87 | TX87-DIFF1 | PAIR | 3 | 5.5 | 5 | 10 | 5 | 50 | 6 | 20 | 12 | 12 | 12 | 12 | 7.5 | 85 Ohms | TOP=L2:L3=L2/L4:L6=L5/L7:BOTTOM=L7 |
| PCIE_TX_P87 | TX87-DIFF1 | PAIR | 4 | 5.5 | 5 | 10 | 5 | 50 | 6 | 20 | 12 | 12 | 12 | 12 | 7.5 | 85 Ohms | TOP=L2:L3=L2/L4:L6=L5/L7:BOTTOM=L7 |
| PCIE_TX_P87 | TX87-DIFF1 | PAIR | 5 | 5.5 | 5 | 10 | 5 | 50 | 6 | 20 | 12 | 12 | 12 | 12 | 7.5 | 85 Ohms | TOP=L2:L3=L2/L4:L6=L5/L7:BOTTOM=L7 |
| PCIE_TX_P87 | TX87-DIFF1 | PAIR | 6 | 5.5 | 5 | 10 | 5 | 50 | 6 | 20 | 12 | 12 | 12 | 12 | 7.5 | 85 Ohms | TOP=L2:L3=L2/L4:L6=L5/L7:BOTTOM=L7 |
| PCIE_TX_P87 | TX87-DIFF1 | PAIR | 7 | 5.5 | 5 | 10 | 5 | 50 | 6 | 20 | 12 | 12 | 12 | 12 | 7.5 | 85 Ohms | TOP=L2:L3=L2/L4:L6=L5/L7:BOTTOM=L7 |
| PCIE_TX_P87 | TX87-DIFF1 | PAIR | 8 | 5.38 | 5 | 10 | 5 | 50 | 6 | 33 | 12 | 12 | 12 | 12 | 6.62 | 85 Ohms | TOP=L2:L3=L2/L4:L6=L5/L7:BOTTOM=L7 |
| PCIE_TX_N88 | TX88-DIFF1 | PAIR | 1 | 5.38 | 5 | 10 | 5 | 50 | 6 | 33 | 12 | 12 | 12 | 12 | 6.62 | 85 Ohms | TOP=L2:L3=L2/L4:L6=L5/L7:BOTTOM=L7 |
| PCIE_TX_N88 | TX88-DIFF1 | PAIR | 2 | 5.5 | 5 | 10 | 5 | 50 | 6 | 20 | 12 | 12 | 12 | 12 | 7.5 | 85 Ohms | TOP=L2:L3=L2/L4:L6=L5/L7:BOTTOM=L7 |
| PCIE_TX_N88 | TX88-DIFF1 | PAIR | 3 | 5.5 | 5 | 10 | 5 | 50 | 6 | 20 | 12 | 12 | 12 | 12 | 7.5 | 85 Ohms | TOP=L2:L3=L2/L4:L6=L5/L7:BOTTOM=L7 |
| PCIE_TX_N88 | TX88-DIFF1 | PAIR | 4 | 5.5 | 5 | 10 | 5 | 50 | 6 | 20 | 12 | 12 | 12 | 12 | 7.5 | 85 Ohms | TOP=L2:L3=L2/L4:L6=L5/L7:BOTTOM=L7 |
| PCIE_TX_N88 | TX88-DIFF1 | PAIR | 5 | 5.5 | 5 | 10 | 5 | 50 | 6 | 20 | 12 | 12 | 12 | 12 | 7.5 | 85 Ohms | TOP=L2:L3=L2/L4:L6=L5/L7:BOTTOM=L7 |
| PCIE_TX_N88 | TX88-DIFF1 | PAIR | 6 | 5.5 | 5 | 10 | 5 | 50 | 6 | 20 | 12 | 12 | 12 | 12 | 7.5 | 85 Ohms | TOP=L2:L3=L2/L4:L6=L5/L7:BOTTOM=L7 |
| PCIE_TX_N88 | TX88-DIFF1 | PAIR | 7 | 5.5 | 5 | 10 | 5 | 50 | 6 | 20 | 12 | 12 | 12 | 12 | 7.5 | 85 Ohms | TOP=L2:L3=L2/L4:L6=L5/L7:BOTTOM=L7 |
| PCIE_TX_N88 | TX88-DIFF1 | PAIR | 8 | 5.38 | 5 | 10 | 5 | 50 | 6 | 33 | 12 | 12 | 12 | 12 | 6.62 | 85 Ohms | TOP=L2:L3=L2/L4:L6=L5/L7:BOTTOM=L7 |
| PCIE_TX_P88 | TX88-DIFF1 | PAIR | 1 | 5.38 | 5 | 10 | 5 | 50 | 6 | 33 | 12 | 12 | 12 | 12 | 6.62 | 85 Ohms | TOP=L2:L3=L2/L4:L6=L5/L7:BOTTOM=L7 |
| PCIE_TX_P88 | TX88-DIFF1 | PAIR | 2 | 5.5 | 5 | 10 | 5 | 50 | 6 | 20 | 12 | 12 | 12 | 12 | 7.5 | 85 Ohms | TOP=L2:L3=L2/L4:L6=L5/L7:BOTTOM=L7 |
| PCIE_TX_P88 | TX88-DIFF1 | PAIR | 3 | 5.5 | 5 | 10 | 5 | 50 | 6 | 20 | 12 | 12 | 12 | 12 | 7.5 | 85 Ohms | TOP=L2:L3=L2/L4:L6=L5/L7:BOTTOM=L7 |
| PCIE_TX_P88 | TX88-DIFF1 | PAIR | 4 | 5.5 | 5 | 10 | 5 | 50 | 6 | 20 | 12 | 12 | 12 | 12 | 7.5 | 85 Ohms | TOP=L2:L3=L2/L4:L6=L5/L7:BOTTOM=L7 |
| PCIE_TX_P88 | TX88-DIFF1 | PAIR | 5 | 5.5 | 5 | 10 | 5 | 50 | 6 | 20 | 12 | 12 | 12 | 12 | 7.5 | 85 Ohms | TOP=L2:L3=L2/L4:L6=L5/L7:BOTTOM=L7 |
| PCIE_TX_P88 | TX88-DIFF1 | PAIR | 6 | 5.5 | 5 | 10 | 5 | 50 | 6 | 20 | 12 | 12 | 12 | 12 | 7.5 | 85 Ohms | TOP=L2:L3=L2/L4:L6=L5/L7:BOTTOM=L7 |
| PCIE_TX_P88 | TX88-DIFF1 | PAIR | 7 | 5.5 | 5 | 10 | 5 | 50 | 6 | 20 | 12 | 12 | 12 | 12 | 7.5 | 85 Ohms | TOP=L2:L3=L2/L4:L6=L5/L7:BOTTOM=L7 |
| PCIE_TX_P88 | TX88-DIFF1 | PAIR | 8 | 5.38 | 5 | 10 | 5 | 50 | 6 | 33 | 12 | 12 | 12 | 12 | 6.62 | 85 Ohms | TOP=L2:L3=L2/L4:L6=L5/L7:BOTTOM=L7 |
| PCIE_TX_N89 | TX89-DIFF1 | PAIR | 1 | 5.38 | 5 | 10 | 5 | 50 | 6 | 33 | 12 | 12 | 12 | 12 | 6.62 | 85 Ohms | TOP=L2:L3=L2/L4:L6=L5/L7:BOTTOM=L7 |
| PCIE_TX_N89 | TX89-DIFF1 | PAIR | 2 | 5.5 | 5 | 10 | 5 | 50 | 6 | 20 | 12 | 12 | 12 | 12 | 7.5 | 85 Ohms | TOP=L2:L3=L2/L4:L6=L5/L7:BOTTOM=L7 |
| PCIE_TX_N89 | TX89-DIFF1 | PAIR | 3 | 5.5 | 5 | 10 | 5 | 50 | 6 | 20 | 12 | 12 | 12 | 12 | 7.5 | 85 Ohms | TOP=L2:L3=L2/L4:L6=L5/L7:BOTTOM=L7 |
| PCIE_TX_N89 | TX89-DIFF1 | PAIR | 4 | 5.5 | 5 | 10 | 5 | 50 | 6 | 20 | 12 | 12 | 12 | 12 | 7.5 | 85 Ohms | TOP=L2:L3=L2/L4:L6=L5/L7:BOTTOM=L7 |
| PCIE_TX_N89 | TX89-DIFF1 | PAIR | 5 | 5.5 | 5 | 10 | 5 | 50 | 6 | 20 | 12 | 12 | 12 | 12 | 7.5 | 85 Ohms | TOP=L2:L3=L2/L4:L6=L5/L7:BOTTOM=L7 |
| PCIE_TX_N89 | TX89-DIFF1 | PAIR | 6 | 5.5 | 5 | 10 | 5 | 50 | 6 | 20 | 12 | 12 | 12 | 12 | 7.5 | 85 Ohms | TOP=L2:L3=L2/L4:L6=L5/L7:BOTTOM=L7 |
| PCIE_TX_N89 | TX89-DIFF1 | PAIR | 7 | 5.5 | 5 | 10 | 5 | 50 | 6 | 20 | 12 | 12 | 12 | 12 | 7.5 | 85 Ohms | TOP=L2:L3=L2/L4:L6=L5/L7:BOTTOM=L7 |
| PCIE_TX_N89 | TX89-DIFF1 | PAIR | 8 | 5.38 | 5 | 10 | 5 | 50 | 6 | 33 | 12 | 12 | 12 | 12 | 6.62 | 85 Ohms | TOP=L2:L3=L2/L4:L6=L5/L7:BOTTOM=L7 |
| PCIE_TX_P89 | TX89-DIFF1 | PAIR | 1 | 5.38 | 5 | 10 | 5 | 50 | 6 | 33 | 12 | 12 | 12 | 12 | 6.62 | 85 Ohms | TOP=L2:L3=L2/L4:L6=L5/L7:BOTTOM=L7 |
| PCIE_TX_P89 | TX89-DIFF1 | PAIR | 2 | 5.5 | 5 | 10 | 5 | 50 | 6 | 20 | 12 | 12 | 12 | 12 | 7.5 | 85 Ohms | TOP=L2:L3=L2/L4:L6=L5/L7:BOTTOM=L7 |
| PCIE_TX_P89 | TX89-DIFF1 | PAIR | 3 | 5.5 | 5 | 10 | 5 | 50 | 6 | 20 | 12 | 12 | 12 | 12 | 7.5 | 85 Ohms | TOP=L2:L3=L2/L4:L6=L5/L7:BOTTOM=L7 |
| PCIE_TX_P89 | TX89-DIFF1 | PAIR | 4 | 5.5 | 5 | 10 | 5 | 50 | 6 | 20 | 12 | 12 | 12 | 12 | 7.5 | 85 Ohms | TOP=L2:L3=L2/L4:L6=L5/L7:BOTTOM=L7 |
| PCIE_TX_P89 | TX89-DIFF1 | PAIR | 5 | 5.5 | 5 | 10 | 5 | 50 | 6 | 20 | 12 | 12 | 12 | 12 | 7.5 | 85 Ohms | TOP=L2:L3=L2/L4:L6=L5/L7:BOTTOM=L7 |
| PCIE_TX_P89 | TX89-DIFF1 | PAIR | 6 | 5.5 | 5 | 10 | 5 | 50 | 6 | 20 | 12 | 12 | 12 | 12 | 7.5 | 85 Ohms | TOP=L2:L3=L2/L4:L6=L5/L7:BOTTOM=L7 |
| PCIE_TX_P89 | TX89-DIFF1 | PAIR | 7 | 5.5 | 5 | 10 | 5 | 50 | 6 | 20 | 12 | 12 | 12 | 12 | 7.5 | 85 Ohms | TOP=L2:L3=L2/L4:L6=L5/L7:BOTTOM=L7 |
| PCIE_TX_P89 | TX89-DIFF1 | PAIR | 8 | 5.38 | 5 | 10 | 5 | 50 | 6 | 33 | 12 | 12 | 12 | 12 | 6.62 | 85 Ohms | TOP=L2:L3=L2/L4:L6=L5/L7:BOTTOM=L7 |
| PCIE_TX_N8 | TX8-DIFF1 | PAIR | 1 | 5.38 | 5 | 10 | 5 | 50 | 6 | 33 | 12 | 12 | 12 | 12 | 6.62 | 85 Ohms | TOP=L2:L3=L2/L4:L6=L5/L7:BOTTOM=L7 |
| PCIE_TX_N8 | TX8-DIFF1 | PAIR | 2 | 5.5 | 5 | 10 | 5 | 50 | 6 | 20 | 12 | 12 | 12 | 12 | 7.5 | 85 Ohms | TOP=L2:L3=L2/L4:L6=L5/L7:BOTTOM=L7 |
| PCIE_TX_N8 | TX8-DIFF1 | PAIR | 3 | 5.5 | 5 | 10 | 5 | 50 | 6 | 20 | 12 | 12 | 12 | 12 | 7.5 | 85 Ohms | TOP=L2:L3=L2/L4:L6=L5/L7:BOTTOM=L7 |
| PCIE_TX_N8 | TX8-DIFF1 | PAIR | 4 | 5.5 | 5 | 10 | 5 | 50 | 6 | 20 | 12 | 12 | 12 | 12 | 7.5 | 85 Ohms | TOP=L2:L3=L2/L4:L6=L5/L7:BOTTOM=L7 |
| PCIE_TX_N8 | TX8-DIFF1 | PAIR | 5 | 5.5 | 5 | 10 | 5 | 50 | 6 | 20 | 12 | 12 | 12 | 12 | 7.5 | 85 Ohms | TOP=L2:L3=L2/L4:L6=L5/L7:BOTTOM=L7 |
| PCIE_TX_N8 | TX8-DIFF1 | PAIR | 6 | 5.5 | 5 | 10 | 5 | 50 | 6 | 20 | 12 | 12 | 12 | 12 | 7.5 | 85 Ohms | TOP=L2:L3=L2/L4:L6=L5/L7:BOTTOM=L7 |
| PCIE_TX_N8 | TX8-DIFF1 | PAIR | 7 | 5.5 | 5 | 10 | 5 | 50 | 6 | 20 | 12 | 12 | 12 | 12 | 7.5 | 85 Ohms | TOP=L2:L3=L2/L4:L6=L5/L7:BOTTOM=L7 |
| PCIE_TX_N8 | TX8-DIFF1 | PAIR | 8 | 5.38 | 5 | 10 | 5 | 50 | 6 | 33 | 12 | 12 | 12 | 12 | 6.62 | 85 Ohms | TOP=L2:L3=L2/L4:L6=L5/L7:BOTTOM=L7 |
| PCIE_TX_P8 | TX8-DIFF1 | PAIR | 1 | 5.38 | 5 | 10 | 5 | 50 | 6 | 33 | 12 | 12 | 12 | 12 | 6.62 | 85 Ohms | TOP=L2:L3=L2/L4:L6=L5/L7:BOTTOM=L7 |
| PCIE_TX_P8 | TX8-DIFF1 | PAIR | 2 | 5.5 | 5 | 10 | 5 | 50 | 6 | 20 | 12 | 12 | 12 | 12 | 7.5 | 85 Ohms | TOP=L2:L3=L2/L4:L6=L5/L7:BOTTOM=L7 |
| PCIE_TX_P8 | TX8-DIFF1 | PAIR | 3 | 5.5 | 5 | 10 | 5 | 50 | 6 | 20 | 12 | 12 | 12 | 12 | 7.5 | 85 Ohms | TOP=L2:L3=L2/L4:L6=L5/L7:BOTTOM=L7 |
| PCIE_TX_P8 | TX8-DIFF1 | PAIR | 4 | 5.5 | 5 | 10 | 5 | 50 | 6 | 20 | 12 | 12 | 12 | 12 | 7.5 | 85 Ohms | TOP=L2:L3=L2/L4:L6=L5/L7:BOTTOM=L7 |
| PCIE_TX_P8 | TX8-DIFF1 | PAIR | 5 | 5.5 | 5 | 10 | 5 | 50 | 6 | 20 | 12 | 12 | 12 | 12 | 7.5 | 85 Ohms | TOP=L2:L3=L2/L4:L6=L5/L7:BOTTOM=L7 |
| PCIE_TX_P8 | TX8-DIFF1 | PAIR | 6 | 5.5 | 5 | 10 | 5 | 50 | 6 | 20 | 12 | 12 | 12 | 12 | 7.5 | 85 Ohms | TOP=L2:L3=L2/L4:L6=L5/L7:BOTTOM=L7 |
| PCIE_TX_P8 | TX8-DIFF1 | PAIR | 7 | 5.5 | 5 | 10 | 5 | 50 | 6 | 20 | 12 | 12 | 12 | 12 | 7.5 | 85 Ohms | TOP=L2:L3=L2/L4:L6=L5/L7:BOTTOM=L7 |
| PCIE_TX_P8 | TX8-DIFF1 | PAIR | 8 | 5.38 | 5 | 10 | 5 | 50 | 6 | 33 | 12 | 12 | 12 | 12 | 6.62 | 85 Ohms | TOP=L2:L3=L2/L4:L6=L5/L7:BOTTOM=L7 |
| PCIE_TX_N90 | TX90-DIFF1 | PAIR | 1 | 5.38 | 5 | 10 | 5 | 50 | 6 | 33 | 12 | 12 | 12 | 12 | 6.62 | 85 Ohms | TOP=L2:L3=L2/L4:L6=L5/L7:BOTTOM=L7 |
| PCIE_TX_N90 | TX90-DIFF1 | PAIR | 2 | 5.5 | 5 | 10 | 5 | 50 | 6 | 20 | 12 | 12 | 12 | 12 | 7.5 | 85 Ohms | TOP=L2:L3=L2/L4:L6=L5/L7:BOTTOM=L7 |
| PCIE_TX_N90 | TX90-DIFF1 | PAIR | 3 | 5.5 | 5 | 10 | 5 | 50 | 6 | 20 | 12 | 12 | 12 | 12 | 7.5 | 85 Ohms | TOP=L2:L3=L2/L4:L6=L5/L7:BOTTOM=L7 |
| PCIE_TX_N90 | TX90-DIFF1 | PAIR | 4 | 5.5 | 5 | 10 | 5 | 50 | 6 | 20 | 12 | 12 | 12 | 12 | 7.5 | 85 Ohms | TOP=L2:L3=L2/L4:L6=L5/L7:BOTTOM=L7 |
| PCIE_TX_N90 | TX90-DIFF1 | PAIR | 5 | 5.5 | 5 | 10 | 5 | 50 | 6 | 20 | 12 | 12 | 12 | 12 | 7.5 | 85 Ohms | TOP=L2:L3=L2/L4:L6=L5/L7:BOTTOM=L7 |
| PCIE_TX_N90 | TX90-DIFF1 | PAIR | 6 | 5.5 | 5 | 10 | 5 | 50 | 6 | 20 | 12 | 12 | 12 | 12 | 7.5 | 85 Ohms | TOP=L2:L3=L2/L4:L6=L5/L7:BOTTOM=L7 |
| PCIE_TX_N90 | TX90-DIFF1 | PAIR | 7 | 5.5 | 5 | 10 | 5 | 50 | 6 | 20 | 12 | 12 | 12 | 12 | 7.5 | 85 Ohms | TOP=L2:L3=L2/L4:L6=L5/L7:BOTTOM=L7 |
| PCIE_TX_N90 | TX90-DIFF1 | PAIR | 8 | 5.38 | 5 | 10 | 5 | 50 | 6 | 33 | 12 | 12 | 12 | 12 | 6.62 | 85 Ohms | TOP=L2:L3=L2/L4:L6=L5/L7:BOTTOM=L7 |
| PCIE_TX_P90 | TX90-DIFF1 | PAIR | 1 | 5.38 | 5 | 10 | 5 | 50 | 6 | 33 | 12 | 12 | 12 | 12 | 6.62 | 85 Ohms | TOP=L2:L3=L2/L4:L6=L5/L7:BOTTOM=L7 |
| PCIE_TX_P90 | TX90-DIFF1 | PAIR | 2 | 5.5 | 5 | 10 | 5 | 50 | 6 | 20 | 12 | 12 | 12 | 12 | 7.5 | 85 Ohms | TOP=L2:L3=L2/L4:L6=L5/L7:BOTTOM=L7 |
| PCIE_TX_P90 | TX90-DIFF1 | PAIR | 3 | 5.5 | 5 | 10 | 5 | 50 | 6 | 20 | 12 | 12 | 12 | 12 | 7.5 | 85 Ohms | TOP=L2:L3=L2/L4:L6=L5/L7:BOTTOM=L7 |
| PCIE_TX_P90 | TX90-DIFF1 | PAIR | 4 | 5.5 | 5 | 10 | 5 | 50 | 6 | 20 | 12 | 12 | 12 | 12 | 7.5 | 85 Ohms | TOP=L2:L3=L2/L4:L6=L5/L7:BOTTOM=L7 |
| PCIE_TX_P90 | TX90-DIFF1 | PAIR | 5 | 5.5 | 5 | 10 | 5 | 50 | 6 | 20 | 12 | 12 | 12 | 12 | 7.5 | 85 Ohms | TOP=L2:L3=L2/L4:L6=L5/L7:BOTTOM=L7 |
| PCIE_TX_P90 | TX90-DIFF1 | PAIR | 6 | 5.5 | 5 | 10 | 5 | 50 | 6 | 20 | 12 | 12 | 12 | 12 | 7.5 | 85 Ohms | TOP=L2:L3=L2/L4:L6=L5/L7:BOTTOM=L7 |
| PCIE_TX_P90 | TX90-DIFF1 | PAIR | 7 | 5.5 | 5 | 10 | 5 | 50 | 6 | 20 | 12 | 12 | 12 | 12 | 7.5 | 85 Ohms | TOP=L2:L3=L2/L4:L6=L5/L7:BOTTOM=L7 |
| PCIE_TX_P90 | TX90-DIFF1 | PAIR | 8 | 5.38 | 5 | 10 | 5 | 50 | 6 | 33 | 12 | 12 | 12 | 12 | 6.62 | 85 Ohms | TOP=L2:L3=L2/L4:L6=L5/L7:BOTTOM=L7 |
| PCIE_TX_N91 | TX91-DIFF1 | PAIR | 1 | 5.38 | 5 | 10 | 5 | 50 | 6 | 33 | 12 | 12 | 12 | 12 | 6.62 | 85 Ohms | TOP=L2:L3=L2/L4:L6=L5/L7:BOTTOM=L7 |
| PCIE_TX_N91 | TX91-DIFF1 | PAIR | 2 | 5.5 | 5 | 10 | 5 | 50 | 6 | 20 | 12 | 12 | 12 | 12 | 7.5 | 85 Ohms | TOP=L2:L3=L2/L4:L6=L5/L7:BOTTOM=L7 |
| PCIE_TX_N91 | TX91-DIFF1 | PAIR | 3 | 5.5 | 5 | 10 | 5 | 50 | 6 | 20 | 12 | 12 | 12 | 12 | 7.5 | 85 Ohms | TOP=L2:L3=L2/L4:L6=L5/L7:BOTTOM=L7 |
| PCIE_TX_N91 | TX91-DIFF1 | PAIR | 4 | 5.5 | 5 | 10 | 5 | 50 | 6 | 20 | 12 | 12 | 12 | 12 | 7.5 | 85 Ohms | TOP=L2:L3=L2/L4:L6=L5/L7:BOTTOM=L7 |
| PCIE_TX_N91 | TX91-DIFF1 | PAIR | 5 | 5.5 | 5 | 10 | 5 | 50 | 6 | 20 | 12 | 12 | 12 | 12 | 7.5 | 85 Ohms | TOP=L2:L3=L2/L4:L6=L5/L7:BOTTOM=L7 |
| PCIE_TX_N91 | TX91-DIFF1 | PAIR | 6 | 5.5 | 5 | 10 | 5 | 50 | 6 | 20 | 12 | 12 | 12 | 12 | 7.5 | 85 Ohms | TOP=L2:L3=L2/L4:L6=L5/L7:BOTTOM=L7 |
| PCIE_TX_N91 | TX91-DIFF1 | PAIR | 7 | 5.5 | 5 | 10 | 5 | 50 | 6 | 20 | 12 | 12 | 12 | 12 | 7.5 | 85 Ohms | TOP=L2:L3=L2/L4:L6=L5/L7:BOTTOM=L7 |
| PCIE_TX_N91 | TX91-DIFF1 | PAIR | 8 | 5.38 | 5 | 10 | 5 | 50 | 6 | 33 | 12 | 12 | 12 | 12 | 6.62 | 85 Ohms | TOP=L2:L3=L2/L4:L6=L5/L7:BOTTOM=L7 |
| PCIE_TX_P91 | TX91-DIFF1 | PAIR | 1 | 5.38 | 5 | 10 | 5 | 50 | 6 | 33 | 12 | 12 | 12 | 12 | 6.62 | 85 Ohms | TOP=L2:L3=L2/L4:L6=L5/L7:BOTTOM=L7 |
| PCIE_TX_P91 | TX91-DIFF1 | PAIR | 2 | 5.5 | 5 | 10 | 5 | 50 | 6 | 20 | 12 | 12 | 12 | 12 | 7.5 | 85 Ohms | TOP=L2:L3=L2/L4:L6=L5/L7:BOTTOM=L7 |
| PCIE_TX_P91 | TX91-DIFF1 | PAIR | 3 | 5.5 | 5 | 10 | 5 | 50 | 6 | 20 | 12 | 12 | 12 | 12 | 7.5 | 85 Ohms | TOP=L2:L3=L2/L4:L6=L5/L7:BOTTOM=L7 |
| PCIE_TX_P91 | TX91-DIFF1 | PAIR | 4 | 5.5 | 5 | 10 | 5 | 50 | 6 | 20 | 12 | 12 | 12 | 12 | 7.5 | 85 Ohms | TOP=L2:L3=L2/L4:L6=L5/L7:BOTTOM=L7 |
| PCIE_TX_P91 | TX91-DIFF1 | PAIR | 5 | 5.5 | 5 | 10 | 5 | 50 | 6 | 20 | 12 | 12 | 12 | 12 | 7.5 | 85 Ohms | TOP=L2:L3=L2/L4:L6=L5/L7:BOTTOM=L7 |
| PCIE_TX_P91 | TX91-DIFF1 | PAIR | 6 | 5.5 | 5 | 10 | 5 | 50 | 6 | 20 | 12 | 12 | 12 | 12 | 7.5 | 85 Ohms | TOP=L2:L3=L2/L4:L6=L5/L7:BOTTOM=L7 |
| PCIE_TX_P91 | TX91-DIFF1 | PAIR | 7 | 5.5 | 5 | 10 | 5 | 50 | 6 | 20 | 12 | 12 | 12 | 12 | 7.5 | 85 Ohms | TOP=L2:L3=L2/L4:L6=L5/L7:BOTTOM=L7 |
| PCIE_TX_P91 | TX91-DIFF1 | PAIR | 8 | 5.38 | 5 | 10 | 5 | 50 | 6 | 33 | 12 | 12 | 12 | 12 | 6.62 | 85 Ohms | TOP=L2:L3=L2/L4:L6=L5/L7:BOTTOM=L7 |
| PCIE_TX_N92 | TX92-DIFF1 | PAIR | 1 | 5.38 | 5 | 10 | 5 | 50 | 6 | 33 | 12 | 12 | 12 | 12 | 6.62 | 85 Ohms | TOP=L2:L3=L2/L4:L6=L5/L7:BOTTOM=L7 |
| PCIE_TX_N92 | TX92-DIFF1 | PAIR | 2 | 5.5 | 5 | 10 | 5 | 50 | 6 | 20 | 12 | 12 | 12 | 12 | 7.5 | 85 Ohms | TOP=L2:L3=L2/L4:L6=L5/L7:BOTTOM=L7 |
| PCIE_TX_N92 | TX92-DIFF1 | PAIR | 3 | 5.5 | 5 | 10 | 5 | 50 | 6 | 20 | 12 | 12 | 12 | 12 | 7.5 | 85 Ohms | TOP=L2:L3=L2/L4:L6=L5/L7:BOTTOM=L7 |
| PCIE_TX_N92 | TX92-DIFF1 | PAIR | 4 | 5.5 | 5 | 10 | 5 | 50 | 6 | 20 | 12 | 12 | 12 | 12 | 7.5 | 85 Ohms | TOP=L2:L3=L2/L4:L6=L5/L7:BOTTOM=L7 |
| PCIE_TX_N92 | TX92-DIFF1 | PAIR | 5 | 5.5 | 5 | 10 | 5 | 50 | 6 | 20 | 12 | 12 | 12 | 12 | 7.5 | 85 Ohms | TOP=L2:L3=L2/L4:L6=L5/L7:BOTTOM=L7 |
| PCIE_TX_N92 | TX92-DIFF1 | PAIR | 6 | 5.5 | 5 | 10 | 5 | 50 | 6 | 20 | 12 | 12 | 12 | 12 | 7.5 | 85 Ohms | TOP=L2:L3=L2/L4:L6=L5/L7:BOTTOM=L7 |
| PCIE_TX_N92 | TX92-DIFF1 | PAIR | 7 | 5.5 | 5 | 10 | 5 | 50 | 6 | 20 | 12 | 12 | 12 | 12 | 7.5 | 85 Ohms | TOP=L2:L3=L2/L4:L6=L5/L7:BOTTOM=L7 |
| PCIE_TX_N92 | TX92-DIFF1 | PAIR | 8 | 5.38 | 5 | 10 | 5 | 50 | 6 | 33 | 12 | 12 | 12 | 12 | 6.62 | 85 Ohms | TOP=L2:L3=L2/L4:L6=L5/L7:BOTTOM=L7 |
| PCIE_TX_P92 | TX92-DIFF1 | PAIR | 1 | 5.38 | 5 | 10 | 5 | 50 | 6 | 33 | 12 | 12 | 12 | 12 | 6.62 | 85 Ohms | TOP=L2:L3=L2/L4:L6=L5/L7:BOTTOM=L7 |
| PCIE_TX_P92 | TX92-DIFF1 | PAIR | 2 | 5.5 | 5 | 10 | 5 | 50 | 6 | 20 | 12 | 12 | 12 | 12 | 7.5 | 85 Ohms | TOP=L2:L3=L2/L4:L6=L5/L7:BOTTOM=L7 |
| PCIE_TX_P92 | TX92-DIFF1 | PAIR | 3 | 5.5 | 5 | 10 | 5 | 50 | 6 | 20 | 12 | 12 | 12 | 12 | 7.5 | 85 Ohms | TOP=L2:L3=L2/L4:L6=L5/L7:BOTTOM=L7 |
| PCIE_TX_P92 | TX92-DIFF1 | PAIR | 4 | 5.5 | 5 | 10 | 5 | 50 | 6 | 20 | 12 | 12 | 12 | 12 | 7.5 | 85 Ohms | TOP=L2:L3=L2/L4:L6=L5/L7:BOTTOM=L7 |
| PCIE_TX_P92 | TX92-DIFF1 | PAIR | 5 | 5.5 | 5 | 10 | 5 | 50 | 6 | 20 | 12 | 12 | 12 | 12 | 7.5 | 85 Ohms | TOP=L2:L3=L2/L4:L6=L5/L7:BOTTOM=L7 |
| PCIE_TX_P92 | TX92-DIFF1 | PAIR | 6 | 5.5 | 5 | 10 | 5 | 50 | 6 | 20 | 12 | 12 | 12 | 12 | 7.5 | 85 Ohms | TOP=L2:L3=L2/L4:L6=L5/L7:BOTTOM=L7 |
| PCIE_TX_P92 | TX92-DIFF1 | PAIR | 7 | 5.5 | 5 | 10 | 5 | 50 | 6 | 20 | 12 | 12 | 12 | 12 | 7.5 | 85 Ohms | TOP=L2:L3=L2/L4:L6=L5/L7:BOTTOM=L7 |
| PCIE_TX_P92 | TX92-DIFF1 | PAIR | 8 | 5.38 | 5 | 10 | 5 | 50 | 6 | 33 | 12 | 12 | 12 | 12 | 6.62 | 85 Ohms | TOP=L2:L3=L2/L4:L6=L5/L7:BOTTOM=L7 |
| PCIE_TX_N93 | TX93-DIFF1 | PAIR | 1 | 5.38 | 5 | 10 | 5 | 50 | 6 | 33 | 12 | 12 | 12 | 12 | 6.62 | 85 Ohms | TOP=L2:L3=L2/L4:L6=L5/L7:BOTTOM=L7 |
| PCIE_TX_N93 | TX93-DIFF1 | PAIR | 2 | 5.5 | 5 | 10 | 5 | 50 | 6 | 20 | 12 | 12 | 12 | 12 | 7.5 | 85 Ohms | TOP=L2:L3=L2/L4:L6=L5/L7:BOTTOM=L7 |
| PCIE_TX_N93 | TX93-DIFF1 | PAIR | 3 | 5.5 | 5 | 10 | 5 | 50 | 6 | 20 | 12 | 12 | 12 | 12 | 7.5 | 85 Ohms | TOP=L2:L3=L2/L4:L6=L5/L7:BOTTOM=L7 |
| PCIE_TX_N93 | TX93-DIFF1 | PAIR | 4 | 5.5 | 5 | 10 | 5 | 50 | 6 | 20 | 12 | 12 | 12 | 12 | 7.5 | 85 Ohms | TOP=L2:L3=L2/L4:L6=L5/L7:BOTTOM=L7 |
| PCIE_TX_N93 | TX93-DIFF1 | PAIR | 5 | 5.5 | 5 | 10 | 5 | 50 | 6 | 20 | 12 | 12 | 12 | 12 | 7.5 | 85 Ohms | TOP=L2:L3=L2/L4:L6=L5/L7:BOTTOM=L7 |
| PCIE_TX_N93 | TX93-DIFF1 | PAIR | 6 | 5.5 | 5 | 10 | 5 | 50 | 6 | 20 | 12 | 12 | 12 | 12 | 7.5 | 85 Ohms | TOP=L2:L3=L2/L4:L6=L5/L7:BOTTOM=L7 |
| PCIE_TX_N93 | TX93-DIFF1 | PAIR | 7 | 5.5 | 5 | 10 | 5 | 50 | 6 | 20 | 12 | 12 | 12 | 12 | 7.5 | 85 Ohms | TOP=L2:L3=L2/L4:L6=L5/L7:BOTTOM=L7 |
| PCIE_TX_N93 | TX93-DIFF1 | PAIR | 8 | 5.38 | 5 | 10 | 5 | 50 | 6 | 33 | 12 | 12 | 12 | 12 | 6.62 | 85 Ohms | TOP=L2:L3=L2/L4:L6=L5/L7:BOTTOM=L7 |
| PCIE_TX_P93 | TX93-DIFF1 | PAIR | 1 | 5.38 | 5 | 10 | 5 | 50 | 6 | 33 | 12 | 12 | 12 | 12 | 6.62 | 85 Ohms | TOP=L2:L3=L2/L4:L6=L5/L7:BOTTOM=L7 |
| PCIE_TX_P93 | TX93-DIFF1 | PAIR | 2 | 5.5 | 5 | 10 | 5 | 50 | 6 | 20 | 12 | 12 | 12 | 12 | 7.5 | 85 Ohms | TOP=L2:L3=L2/L4:L6=L5/L7:BOTTOM=L7 |
| PCIE_TX_P93 | TX93-DIFF1 | PAIR | 3 | 5.5 | 5 | 10 | 5 | 50 | 6 | 20 | 12 | 12 | 12 | 12 | 7.5 | 85 Ohms | TOP=L2:L3=L2/L4:L6=L5/L7:BOTTOM=L7 |
| PCIE_TX_P93 | TX93-DIFF1 | PAIR | 4 | 5.5 | 5 | 10 | 5 | 50 | 6 | 20 | 12 | 12 | 12 | 12 | 7.5 | 85 Ohms | TOP=L2:L3=L2/L4:L6=L5/L7:BOTTOM=L7 |
| PCIE_TX_P93 | TX93-DIFF1 | PAIR | 5 | 5.5 | 5 | 10 | 5 | 50 | 6 | 20 | 12 | 12 | 12 | 12 | 7.5 | 85 Ohms | TOP=L2:L3=L2/L4:L6=L5/L7:BOTTOM=L7 |
| PCIE_TX_P93 | TX93-DIFF1 | PAIR | 6 | 5.5 | 5 | 10 | 5 | 50 | 6 | 20 | 12 | 12 | 12 | 12 | 7.5 | 85 Ohms | TOP=L2:L3=L2/L4:L6=L5/L7:BOTTOM=L7 |
| PCIE_TX_P93 | TX93-DIFF1 | PAIR | 7 | 5.5 | 5 | 10 | 5 | 50 | 6 | 20 | 12 | 12 | 12 | 12 | 7.5 | 85 Ohms | TOP=L2:L3=L2/L4:L6=L5/L7:BOTTOM=L7 |
| PCIE_TX_P93 | TX93-DIFF1 | PAIR | 8 | 5.38 | 5 | 10 | 5 | 50 | 6 | 33 | 12 | 12 | 12 | 12 | 6.62 | 85 Ohms | TOP=L2:L3=L2/L4:L6=L5/L7:BOTTOM=L7 |
| PCIE_TX_N94 | TX94-DIFF1 | PAIR | 1 | 5.38 | 5 | 10 | 5 | 50 | 6 | 33 | 12 | 12 | 12 | 12 | 6.62 | 85 Ohms | TOP=L2:L3=L2/L4:L6=L5/L7:BOTTOM=L7 |
| PCIE_TX_N94 | TX94-DIFF1 | PAIR | 2 | 5.5 | 5 | 10 | 5 | 50 | 6 | 20 | 12 | 12 | 12 | 12 | 7.5 | 85 Ohms | TOP=L2:L3=L2/L4:L6=L5/L7:BOTTOM=L7 |
| PCIE_TX_N94 | TX94-DIFF1 | PAIR | 3 | 5.5 | 5 | 10 | 5 | 50 | 6 | 20 | 12 | 12 | 12 | 12 | 7.5 | 85 Ohms | TOP=L2:L3=L2/L4:L6=L5/L7:BOTTOM=L7 |
| PCIE_TX_N94 | TX94-DIFF1 | PAIR | 4 | 5.5 | 5 | 10 | 5 | 50 | 6 | 20 | 12 | 12 | 12 | 12 | 7.5 | 85 Ohms | TOP=L2:L3=L2/L4:L6=L5/L7:BOTTOM=L7 |
| PCIE_TX_N94 | TX94-DIFF1 | PAIR | 5 | 5.5 | 5 | 10 | 5 | 50 | 6 | 20 | 12 | 12 | 12 | 12 | 7.5 | 85 Ohms | TOP=L2:L3=L2/L4:L6=L5/L7:BOTTOM=L7 |
| PCIE_TX_N94 | TX94-DIFF1 | PAIR | 6 | 5.5 | 5 | 10 | 5 | 50 | 6 | 20 | 12 | 12 | 12 | 12 | 7.5 | 85 Ohms | TOP=L2:L3=L2/L4:L6=L5/L7:BOTTOM=L7 |
| PCIE_TX_N94 | TX94-DIFF1 | PAIR | 7 | 5.5 | 5 | 10 | 5 | 50 | 6 | 20 | 12 | 12 | 12 | 12 | 7.5 | 85 Ohms | TOP=L2:L3=L2/L4:L6=L5/L7:BOTTOM=L7 |
| PCIE_TX_N94 | TX94-DIFF1 | PAIR | 8 | 5.38 | 5 | 10 | 5 | 50 | 6 | 33 | 12 | 12 | 12 | 12 | 6.62 | 85 Ohms | TOP=L2:L3=L2/L4:L6=L5/L7:BOTTOM=L7 |
| PCIE_TX_P94 | TX94-DIFF1 | PAIR | 1 | 5.38 | 5 | 10 | 5 | 50 | 6 | 33 | 12 | 12 | 12 | 12 | 6.62 | 85 Ohms | TOP=L2:L3=L2/L4:L6=L5/L7:BOTTOM=L7 |
| PCIE_TX_P94 | TX94-DIFF1 | PAIR | 2 | 5.5 | 5 | 10 | 5 | 50 | 6 | 20 | 12 | 12 | 12 | 12 | 7.5 | 85 Ohms | TOP=L2:L3=L2/L4:L6=L5/L7:BOTTOM=L7 |
| PCIE_TX_P94 | TX94-DIFF1 | PAIR | 3 | 5.5 | 5 | 10 | 5 | 50 | 6 | 20 | 12 | 12 | 12 | 12 | 7.5 | 85 Ohms | TOP=L2:L3=L2/L4:L6=L5/L7:BOTTOM=L7 |
| PCIE_TX_P94 | TX94-DIFF1 | PAIR | 4 | 5.5 | 5 | 10 | 5 | 50 | 6 | 20 | 12 | 12 | 12 | 12 | 7.5 | 85 Ohms | TOP=L2:L3=L2/L4:L6=L5/L7:BOTTOM=L7 |
| PCIE_TX_P94 | TX94-DIFF1 | PAIR | 5 | 5.5 | 5 | 10 | 5 | 50 | 6 | 20 | 12 | 12 | 12 | 12 | 7.5 | 85 Ohms | TOP=L2:L3=L2/L4:L6=L5/L7:BOTTOM=L7 |
| PCIE_TX_P94 | TX94-DIFF1 | PAIR | 6 | 5.5 | 5 | 10 | 5 | 50 | 6 | 20 | 12 | 12 | 12 | 12 | 7.5 | 85 Ohms | TOP=L2:L3=L2/L4:L6=L5/L7:BOTTOM=L7 |
| PCIE_TX_P94 | TX94-DIFF1 | PAIR | 7 | 5.5 | 5 | 10 | 5 | 50 | 6 | 20 | 12 | 12 | 12 | 12 | 7.5 | 85 Ohms | TOP=L2:L3=L2/L4:L6=L5/L7:BOTTOM=L7 |
| PCIE_TX_P94 | TX94-DIFF1 | PAIR | 8 | 5.38 | 5 | 10 | 5 | 50 | 6 | 33 | 12 | 12 | 12 | 12 | 6.62 | 85 Ohms | TOP=L2:L3=L2/L4:L6=L5/L7:BOTTOM=L7 |
| PCIE_TX_N95 | TX95-DIFF1 | PAIR | 1 | 5.38 | 5 | 10 | 5 | 50 | 6 | 33 | 12 | 12 | 12 | 12 | 6.62 | 85 Ohms | TOP=L2:L3=L2/L4:L6=L5/L7:BOTTOM=L7 |
| PCIE_TX_N95 | TX95-DIFF1 | PAIR | 2 | 5.5 | 5 | 10 | 5 | 50 | 6 | 20 | 12 | 12 | 12 | 12 | 7.5 | 85 Ohms | TOP=L2:L3=L2/L4:L6=L5/L7:BOTTOM=L7 |
| PCIE_TX_N95 | TX95-DIFF1 | PAIR | 3 | 5.5 | 5 | 10 | 5 | 50 | 6 | 20 | 12 | 12 | 12 | 12 | 7.5 | 85 Ohms | TOP=L2:L3=L2/L4:L6=L5/L7:BOTTOM=L7 |
| PCIE_TX_N95 | TX95-DIFF1 | PAIR | 4 | 5.5 | 5 | 10 | 5 | 50 | 6 | 20 | 12 | 12 | 12 | 12 | 7.5 | 85 Ohms | TOP=L2:L3=L2/L4:L6=L5/L7:BOTTOM=L7 |
| PCIE_TX_N95 | TX95-DIFF1 | PAIR | 5 | 5.5 | 5 | 10 | 5 | 50 | 6 | 20 | 12 | 12 | 12 | 12 | 7.5 | 85 Ohms | TOP=L2:L3=L2/L4:L6=L5/L7:BOTTOM=L7 |
| PCIE_TX_N95 | TX95-DIFF1 | PAIR | 6 | 5.5 | 5 | 10 | 5 | 50 | 6 | 20 | 12 | 12 | 12 | 12 | 7.5 | 85 Ohms | TOP=L2:L3=L2/L4:L6=L5/L7:BOTTOM=L7 |
| PCIE_TX_N95 | TX95-DIFF1 | PAIR | 7 | 5.5 | 5 | 10 | 5 | 50 | 6 | 20 | 12 | 12 | 12 | 12 | 7.5 | 85 Ohms | TOP=L2:L3=L2/L4:L6=L5/L7:BOTTOM=L7 |
| PCIE_TX_N95 | TX95-DIFF1 | PAIR | 8 | 5.38 | 5 | 10 | 5 | 50 | 6 | 33 | 12 | 12 | 12 | 12 | 6.62 | 85 Ohms | TOP=L2:L3=L2/L4:L6=L5/L7:BOTTOM=L7 |
| PCIE_TX_P95 | TX95-DIFF1 | PAIR | 1 | 5.38 | 5 | 10 | 5 | 50 | 6 | 33 | 12 | 12 | 12 | 12 | 6.62 | 85 Ohms | TOP=L2:L3=L2/L4:L6=L5/L7:BOTTOM=L7 |
| PCIE_TX_P95 | TX95-DIFF1 | PAIR | 2 | 5.5 | 5 | 10 | 5 | 50 | 6 | 20 | 12 | 12 | 12 | 12 | 7.5 | 85 Ohms | TOP=L2:L3=L2/L4:L6=L5/L7:BOTTOM=L7 |
| PCIE_TX_P95 | TX95-DIFF1 | PAIR | 3 | 5.5 | 5 | 10 | 5 | 50 | 6 | 20 | 12 | 12 | 12 | 12 | 7.5 | 85 Ohms | TOP=L2:L3=L2/L4:L6=L5/L7:BOTTOM=L7 |
| PCIE_TX_P95 | TX95-DIFF1 | PAIR | 4 | 5.5 | 5 | 10 | 5 | 50 | 6 | 20 | 12 | 12 | 12 | 12 | 7.5 | 85 Ohms | TOP=L2:L3=L2/L4:L6=L5/L7:BOTTOM=L7 |
| PCIE_TX_P95 | TX95-DIFF1 | PAIR | 5 | 5.5 | 5 | 10 | 5 | 50 | 6 | 20 | 12 | 12 | 12 | 12 | 7.5 | 85 Ohms | TOP=L2:L3=L2/L4:L6=L5/L7:BOTTOM=L7 |
| PCIE_TX_P95 | TX95-DIFF1 | PAIR | 6 | 5.5 | 5 | 10 | 5 | 50 | 6 | 20 | 12 | 12 | 12 | 12 | 7.5 | 85 Ohms | TOP=L2:L3=L2/L4:L6=L5/L7:BOTTOM=L7 |
| PCIE_TX_P95 | TX95-DIFF1 | PAIR | 7 | 5.5 | 5 | 10 | 5 | 50 | 6 | 20 | 12 | 12 | 12 | 12 | 7.5 | 85 Ohms | TOP=L2:L3=L2/L4:L6=L5/L7:BOTTOM=L7 |
| PCIE_TX_P95 | TX95-DIFF1 | PAIR | 8 | 5.38 | 5 | 10 | 5 | 50 | 6 | 33 | 12 | 12 | 12 | 12 | 6.62 | 85 Ohms | TOP=L2:L3=L2/L4:L6=L5/L7:BOTTOM=L7 |
| PCIE_TX_N9 | TX9-DIFF1 | PAIR | 1 | 5.38 | 5 | 10 | 5 | 50 | 6 | 33 | 12 | 12 | 12 | 12 | 6.62 | 85 Ohms | TOP=L2:L3=L2/L4:L6=L5/L7:BOTTOM=L7 |
| PCIE_TX_N9 | TX9-DIFF1 | PAIR | 2 | 5.5 | 5 | 10 | 5 | 50 | 6 | 20 | 12 | 12 | 12 | 12 | 7.5 | 85 Ohms | TOP=L2:L3=L2/L4:L6=L5/L7:BOTTOM=L7 |
| PCIE_TX_N9 | TX9-DIFF1 | PAIR | 3 | 5.5 | 5 | 10 | 5 | 50 | 6 | 20 | 12 | 12 | 12 | 12 | 7.5 | 85 Ohms | TOP=L2:L3=L2/L4:L6=L5/L7:BOTTOM=L7 |
| PCIE_TX_N9 | TX9-DIFF1 | PAIR | 4 | 5.5 | 5 | 10 | 5 | 50 | 6 | 20 | 12 | 12 | 12 | 12 | 7.5 | 85 Ohms | TOP=L2:L3=L2/L4:L6=L5/L7:BOTTOM=L7 |
| PCIE_TX_N9 | TX9-DIFF1 | PAIR | 5 | 5.5 | 5 | 10 | 5 | 50 | 6 | 20 | 12 | 12 | 12 | 12 | 7.5 | 85 Ohms | TOP=L2:L3=L2/L4:L6=L5/L7:BOTTOM=L7 |
| PCIE_TX_N9 | TX9-DIFF1 | PAIR | 6 | 5.5 | 5 | 10 | 5 | 50 | 6 | 20 | 12 | 12 | 12 | 12 | 7.5 | 85 Ohms | TOP=L2:L3=L2/L4:L6=L5/L7:BOTTOM=L7 |
| PCIE_TX_N9 | TX9-DIFF1 | PAIR | 7 | 5.5 | 5 | 10 | 5 | 50 | 6 | 20 | 12 | 12 | 12 | 12 | 7.5 | 85 Ohms | TOP=L2:L3=L2/L4:L6=L5/L7:BOTTOM=L7 |
| PCIE_TX_N9 | TX9-DIFF1 | PAIR | 8 | 5.38 | 5 | 10 | 5 | 50 | 6 | 33 | 12 | 12 | 12 | 12 | 6.62 | 85 Ohms | TOP=L2:L3=L2/L4:L6=L5/L7:BOTTOM=L7 |
| PCIE_TX_P9 | TX9-DIFF1 | PAIR | 1 | 5.38 | 5 | 10 | 5 | 50 | 6 | 33 | 12 | 12 | 12 | 12 | 6.62 | 85 Ohms | TOP=L2:L3=L2/L4:L6=L5/L7:BOTTOM=L7 |
| PCIE_TX_P9 | TX9-DIFF1 | PAIR | 2 | 5.5 | 5 | 10 | 5 | 50 | 6 | 20 | 12 | 12 | 12 | 12 | 7.5 | 85 Ohms | TOP=L2:L3=L2/L4:L6=L5/L7:BOTTOM=L7 |
| PCIE_TX_P9 | TX9-DIFF1 | PAIR | 3 | 5.5 | 5 | 10 | 5 | 50 | 6 | 20 | 12 | 12 | 12 | 12 | 7.5 | 85 Ohms | TOP=L2:L3=L2/L4:L6=L5/L7:BOTTOM=L7 |
| PCIE_TX_P9 | TX9-DIFF1 | PAIR | 4 | 5.5 | 5 | 10 | 5 | 50 | 6 | 20 | 12 | 12 | 12 | 12 | 7.5 | 85 Ohms | TOP=L2:L3=L2/L4:L6=L5/L7:BOTTOM=L7 |
| PCIE_TX_P9 | TX9-DIFF1 | PAIR | 5 | 5.5 | 5 | 10 | 5 | 50 | 6 | 20 | 12 | 12 | 12 | 12 | 7.5 | 85 Ohms | TOP=L2:L3=L2/L4:L6=L5/L7:BOTTOM=L7 |
| PCIE_TX_P9 | TX9-DIFF1 | PAIR | 6 | 5.5 | 5 | 10 | 5 | 50 | 6 | 20 | 12 | 12 | 12 | 12 | 7.5 | 85 Ohms | TOP=L2:L3=L2/L4:L6=L5/L7:BOTTOM=L7 |
| PCIE_TX_P9 | TX9-DIFF1 | PAIR | 7 | 5.5 | 5 | 10 | 5 | 50 | 6 | 20 | 12 | 12 | 12 | 12 | 7.5 | 85 Ohms | TOP=L2:L3=L2/L4:L6=L5/L7:BOTTOM=L7 |
| PCIE_TX_P9 | TX9-DIFF1 | PAIR | 8 | 5.38 | 5 | 10 | 5 | 50 | 6 | 33 | 12 | 12 | 12 | 12 | 6.62 | 85 Ohms | TOP=L2:L3=L2/L4:L6=L5/L7:BOTTOM=L7 |
| PCIE_TX_CAP_N0 | TXC0-DIFF1 | PAIR | 1 | 5.38 | 5 | 10 | 5 | 50 | 6 | 33 | 12 | 12 | 12 | 12 | 6.62 | 85 Ohms | TOP=L2:L3=L2/L4:L6=L5/L7:BOTTOM=L7 |
| PCIE_TX_CAP_N0 | TXC0-DIFF1 | PAIR | 2 | 5.5 | 5 | 10 | 5 | 50 | 6 | 20 | 12 | 12 | 12 | 12 | 7.5 | 85 Ohms | TOP=L2:L3=L2/L4:L6=L5/L7:BOTTOM=L7 |
| PCIE_TX_CAP_N0 | TXC0-DIFF1 | PAIR | 3 | 5.5 | 5 | 10 | 5 | 50 | 6 | 20 | 12 | 12 | 12 | 12 | 7.5 | 85 Ohms | TOP=L2:L3=L2/L4:L6=L5/L7:BOTTOM=L7 |
| PCIE_TX_CAP_N0 | TXC0-DIFF1 | PAIR | 4 | 5.5 | 5 | 10 | 5 | 50 | 6 | 20 | 12 | 12 | 12 | 12 | 7.5 | 85 Ohms | TOP=L2:L3=L2/L4:L6=L5/L7:BOTTOM=L7 |
| PCIE_TX_CAP_N0 | TXC0-DIFF1 | PAIR | 5 | 5.5 | 5 | 10 | 5 | 50 | 6 | 20 | 12 | 12 | 12 | 12 | 7.5 | 85 Ohms | TOP=L2:L3=L2/L4:L6=L5/L7:BOTTOM=L7 |
| PCIE_TX_CAP_N0 | TXC0-DIFF1 | PAIR | 6 | 5.5 | 5 | 10 | 5 | 50 | 6 | 20 | 12 | 12 | 12 | 12 | 7.5 | 85 Ohms | TOP=L2:L3=L2/L4:L6=L5/L7:BOTTOM=L7 |
| PCIE_TX_CAP_N0 | TXC0-DIFF1 | PAIR | 7 | 5.5 | 5 | 10 | 5 | 50 | 6 | 20 | 12 | 12 | 12 | 12 | 7.5 | 85 Ohms | TOP=L2:L3=L2/L4:L6=L5/L7:BOTTOM=L7 |
| PCIE_TX_CAP_N0 | TXC0-DIFF1 | PAIR | 8 | 5.38 | 5 | 10 | 5 | 50 | 6 | 33 | 12 | 12 | 12 | 12 | 6.62 | 85 Ohms | TOP=L2:L3=L2/L4:L6=L5/L7:BOTTOM=L7 |
| PCIE_TX_CAP_P0 | TXC0-DIFF1 | PAIR | 1 | 5.38 | 5 | 10 | 5 | 50 | 6 | 33 | 12 | 12 | 12 | 12 | 6.62 | 85 Ohms | TOP=L2:L3=L2/L4:L6=L5/L7:BOTTOM=L7 |
| PCIE_TX_CAP_P0 | TXC0-DIFF1 | PAIR | 2 | 5.5 | 5 | 10 | 5 | 50 | 6 | 20 | 12 | 12 | 12 | 12 | 7.5 | 85 Ohms | TOP=L2:L3=L2/L4:L6=L5/L7:BOTTOM=L7 |
| PCIE_TX_CAP_P0 | TXC0-DIFF1 | PAIR | 3 | 5.5 | 5 | 10 | 5 | 50 | 6 | 20 | 12 | 12 | 12 | 12 | 7.5 | 85 Ohms | TOP=L2:L3=L2/L4:L6=L5/L7:BOTTOM=L7 |
| PCIE_TX_CAP_P0 | TXC0-DIFF1 | PAIR | 4 | 5.5 | 5 | 10 | 5 | 50 | 6 | 20 | 12 | 12 | 12 | 12 | 7.5 | 85 Ohms | TOP=L2:L3=L2/L4:L6=L5/L7:BOTTOM=L7 |
| PCIE_TX_CAP_P0 | TXC0-DIFF1 | PAIR | 5 | 5.5 | 5 | 10 | 5 | 50 | 6 | 20 | 12 | 12 | 12 | 12 | 7.5 | 85 Ohms | TOP=L2:L3=L2/L4:L6=L5/L7:BOTTOM=L7 |
| PCIE_TX_CAP_P0 | TXC0-DIFF1 | PAIR | 6 | 5.5 | 5 | 10 | 5 | 50 | 6 | 20 | 12 | 12 | 12 | 12 | 7.5 | 85 Ohms | TOP=L2:L3=L2/L4:L6=L5/L7:BOTTOM=L7 |
| PCIE_TX_CAP_P0 | TXC0-DIFF1 | PAIR | 7 | 5.5 | 5 | 10 | 5 | 50 | 6 | 20 | 12 | 12 | 12 | 12 | 7.5 | 85 Ohms | TOP=L2:L3=L2/L4:L6=L5/L7:BOTTOM=L7 |
| PCIE_TX_CAP_P0 | TXC0-DIFF1 | PAIR | 8 | 5.38 | 5 | 10 | 5 | 50 | 6 | 33 | 12 | 12 | 12 | 12 | 6.62 | 85 Ohms | TOP=L2:L3=L2/L4:L6=L5/L7:BOTTOM=L7 |
| PCIE_TX_CAP_N10 | TXC10-DIFF1 | PAIR | 1 | 5.38 | 5 | 10 | 5 | 50 | 6 | 33 | 12 | 12 | 12 | 12 | 6.62 | 85 Ohms | TOP=L2:L3=L2/L4:L6=L5/L7:BOTTOM=L7 |
| PCIE_TX_CAP_N10 | TXC10-DIFF1 | PAIR | 2 | 5.5 | 5 | 10 | 5 | 50 | 6 | 20 | 12 | 12 | 12 | 12 | 7.5 | 85 Ohms | TOP=L2:L3=L2/L4:L6=L5/L7:BOTTOM=L7 |
| PCIE_TX_CAP_N10 | TXC10-DIFF1 | PAIR | 3 | 5.5 | 5 | 10 | 5 | 50 | 6 | 20 | 12 | 12 | 12 | 12 | 7.5 | 85 Ohms | TOP=L2:L3=L2/L4:L6=L5/L7:BOTTOM=L7 |
| PCIE_TX_CAP_N10 | TXC10-DIFF1 | PAIR | 4 | 5.5 | 5 | 10 | 5 | 50 | 6 | 20 | 12 | 12 | 12 | 12 | 7.5 | 85 Ohms | TOP=L2:L3=L2/L4:L6=L5/L7:BOTTOM=L7 |
| PCIE_TX_CAP_N10 | TXC10-DIFF1 | PAIR | 5 | 5.5 | 5 | 10 | 5 | 50 | 6 | 20 | 12 | 12 | 12 | 12 | 7.5 | 85 Ohms | TOP=L2:L3=L2/L4:L6=L5/L7:BOTTOM=L7 |
| PCIE_TX_CAP_N10 | TXC10-DIFF1 | PAIR | 6 | 5.5 | 5 | 10 | 5 | 50 | 6 | 20 | 12 | 12 | 12 | 12 | 7.5 | 85 Ohms | TOP=L2:L3=L2/L4:L6=L5/L7:BOTTOM=L7 |
| PCIE_TX_CAP_N10 | TXC10-DIFF1 | PAIR | 7 | 5.5 | 5 | 10 | 5 | 50 | 6 | 20 | 12 | 12 | 12 | 12 | 7.5 | 85 Ohms | TOP=L2:L3=L2/L4:L6=L5/L7:BOTTOM=L7 |
| PCIE_TX_CAP_N10 | TXC10-DIFF1 | PAIR | 8 | 5.38 | 5 | 10 | 5 | 50 | 6 | 33 | 12 | 12 | 12 | 12 | 6.62 | 85 Ohms | TOP=L2:L3=L2/L4:L6=L5/L7:BOTTOM=L7 |
| PCIE_TX_CAP_P10 | TXC10-DIFF1 | PAIR | 1 | 5.38 | 5 | 10 | 5 | 50 | 6 | 33 | 12 | 12 | 12 | 12 | 6.62 | 85 Ohms | TOP=L2:L3=L2/L4:L6=L5/L7:BOTTOM=L7 |
| PCIE_TX_CAP_P10 | TXC10-DIFF1 | PAIR | 2 | 5.5 | 5 | 10 | 5 | 50 | 6 | 20 | 12 | 12 | 12 | 12 | 7.5 | 85 Ohms | TOP=L2:L3=L2/L4:L6=L5/L7:BOTTOM=L7 |
| PCIE_TX_CAP_P10 | TXC10-DIFF1 | PAIR | 3 | 5.5 | 5 | 10 | 5 | 50 | 6 | 20 | 12 | 12 | 12 | 12 | 7.5 | 85 Ohms | TOP=L2:L3=L2/L4:L6=L5/L7:BOTTOM=L7 |
| PCIE_TX_CAP_P10 | TXC10-DIFF1 | PAIR | 4 | 5.5 | 5 | 10 | 5 | 50 | 6 | 20 | 12 | 12 | 12 | 12 | 7.5 | 85 Ohms | TOP=L2:L3=L2/L4:L6=L5/L7:BOTTOM=L7 |
| PCIE_TX_CAP_P10 | TXC10-DIFF1 | PAIR | 5 | 5.5 | 5 | 10 | 5 | 50 | 6 | 20 | 12 | 12 | 12 | 12 | 7.5 | 85 Ohms | TOP=L2:L3=L2/L4:L6=L5/L7:BOTTOM=L7 |
| PCIE_TX_CAP_P10 | TXC10-DIFF1 | PAIR | 6 | 5.5 | 5 | 10 | 5 | 50 | 6 | 20 | 12 | 12 | 12 | 12 | 7.5 | 85 Ohms | TOP=L2:L3=L2/L4:L6=L5/L7:BOTTOM=L7 |
| PCIE_TX_CAP_P10 | TXC10-DIFF1 | PAIR | 7 | 5.5 | 5 | 10 | 5 | 50 | 6 | 20 | 12 | 12 | 12 | 12 | 7.5 | 85 Ohms | TOP=L2:L3=L2/L4:L6=L5/L7:BOTTOM=L7 |
| PCIE_TX_CAP_P10 | TXC10-DIFF1 | PAIR | 8 | 5.38 | 5 | 10 | 5 | 50 | 6 | 33 | 12 | 12 | 12 | 12 | 6.62 | 85 Ohms | TOP=L2:L3=L2/L4:L6=L5/L7:BOTTOM=L7 |
| PCIE_TX_CAP_N11 | TXC11-DIFF1 | PAIR | 1 | 5.38 | 5 | 10 | 5 | 50 | 6 | 33 | 12 | 12 | 12 | 12 | 6.62 | 85 Ohms | TOP=L2:L3=L2/L4:L6=L5/L7:BOTTOM=L7 |
| PCIE_TX_CAP_N11 | TXC11-DIFF1 | PAIR | 2 | 5.5 | 5 | 10 | 5 | 50 | 6 | 20 | 12 | 12 | 12 | 12 | 7.5 | 85 Ohms | TOP=L2:L3=L2/L4:L6=L5/L7:BOTTOM=L7 |
| PCIE_TX_CAP_N11 | TXC11-DIFF1 | PAIR | 3 | 5.5 | 5 | 10 | 5 | 50 | 6 | 20 | 12 | 12 | 12 | 12 | 7.5 | 85 Ohms | TOP=L2:L3=L2/L4:L6=L5/L7:BOTTOM=L7 |
| PCIE_TX_CAP_N11 | TXC11-DIFF1 | PAIR | 4 | 5.5 | 5 | 10 | 5 | 50 | 6 | 20 | 12 | 12 | 12 | 12 | 7.5 | 85 Ohms | TOP=L2:L3=L2/L4:L6=L5/L7:BOTTOM=L7 |
| PCIE_TX_CAP_N11 | TXC11-DIFF1 | PAIR | 5 | 5.5 | 5 | 10 | 5 | 50 | 6 | 20 | 12 | 12 | 12 | 12 | 7.5 | 85 Ohms | TOP=L2:L3=L2/L4:L6=L5/L7:BOTTOM=L7 |
| PCIE_TX_CAP_N11 | TXC11-DIFF1 | PAIR | 6 | 5.5 | 5 | 10 | 5 | 50 | 6 | 20 | 12 | 12 | 12 | 12 | 7.5 | 85 Ohms | TOP=L2:L3=L2/L4:L6=L5/L7:BOTTOM=L7 |
| PCIE_TX_CAP_N11 | TXC11-DIFF1 | PAIR | 7 | 5.5 | 5 | 10 | 5 | 50 | 6 | 20 | 12 | 12 | 12 | 12 | 7.5 | 85 Ohms | TOP=L2:L3=L2/L4:L6=L5/L7:BOTTOM=L7 |
| PCIE_TX_CAP_N11 | TXC11-DIFF1 | PAIR | 8 | 5.38 | 5 | 10 | 5 | 50 | 6 | 33 | 12 | 12 | 12 | 12 | 6.62 | 85 Ohms | TOP=L2:L3=L2/L4:L6=L5/L7:BOTTOM=L7 |
| PCIE_TX_CAP_P11 | TXC11-DIFF1 | PAIR | 1 | 5.38 | 5 | 10 | 5 | 50 | 6 | 33 | 12 | 12 | 12 | 12 | 6.62 | 85 Ohms | TOP=L2:L3=L2/L4:L6=L5/L7:BOTTOM=L7 |
| PCIE_TX_CAP_P11 | TXC11-DIFF1 | PAIR | 2 | 5.5 | 5 | 10 | 5 | 50 | 6 | 20 | 12 | 12 | 12 | 12 | 7.5 | 85 Ohms | TOP=L2:L3=L2/L4:L6=L5/L7:BOTTOM=L7 |
| PCIE_TX_CAP_P11 | TXC11-DIFF1 | PAIR | 3 | 5.5 | 5 | 10 | 5 | 50 | 6 | 20 | 12 | 12 | 12 | 12 | 7.5 | 85 Ohms | TOP=L2:L3=L2/L4:L6=L5/L7:BOTTOM=L7 |
| PCIE_TX_CAP_P11 | TXC11-DIFF1 | PAIR | 4 | 5.5 | 5 | 10 | 5 | 50 | 6 | 20 | 12 | 12 | 12 | 12 | 7.5 | 85 Ohms | TOP=L2:L3=L2/L4:L6=L5/L7:BOTTOM=L7 |
| PCIE_TX_CAP_P11 | TXC11-DIFF1 | PAIR | 5 | 5.5 | 5 | 10 | 5 | 50 | 6 | 20 | 12 | 12 | 12 | 12 | 7.5 | 85 Ohms | TOP=L2:L3=L2/L4:L6=L5/L7:BOTTOM=L7 |
| PCIE_TX_CAP_P11 | TXC11-DIFF1 | PAIR | 6 | 5.5 | 5 | 10 | 5 | 50 | 6 | 20 | 12 | 12 | 12 | 12 | 7.5 | 85 Ohms | TOP=L2:L3=L2/L4:L6=L5/L7:BOTTOM=L7 |
| PCIE_TX_CAP_P11 | TXC11-DIFF1 | PAIR | 7 | 5.5 | 5 | 10 | 5 | 50 | 6 | 20 | 12 | 12 | 12 | 12 | 7.5 | 85 Ohms | TOP=L2:L3=L2/L4:L6=L5/L7:BOTTOM=L7 |
| PCIE_TX_CAP_P11 | TXC11-DIFF1 | PAIR | 8 | 5.38 | 5 | 10 | 5 | 50 | 6 | 33 | 12 | 12 | 12 | 12 | 6.62 | 85 Ohms | TOP=L2:L3=L2/L4:L6=L5/L7:BOTTOM=L7 |
| PCIE_TX_CAP_N12 | TXC12-DIFF1 | PAIR | 1 | 5.38 | 5 | 10 | 5 | 50 | 6 | 33 | 12 | 12 | 12 | 12 | 6.62 | 85 Ohms | TOP=L2:L3=L2/L4:L6=L5/L7:BOTTOM=L7 |
| PCIE_TX_CAP_N12 | TXC12-DIFF1 | PAIR | 2 | 5.5 | 5 | 10 | 5 | 50 | 6 | 20 | 12 | 12 | 12 | 12 | 7.5 | 85 Ohms | TOP=L2:L3=L2/L4:L6=L5/L7:BOTTOM=L7 |
| PCIE_TX_CAP_N12 | TXC12-DIFF1 | PAIR | 3 | 5.5 | 5 | 10 | 5 | 50 | 6 | 20 | 12 | 12 | 12 | 12 | 7.5 | 85 Ohms | TOP=L2:L3=L2/L4:L6=L5/L7:BOTTOM=L7 |
| PCIE_TX_CAP_N12 | TXC12-DIFF1 | PAIR | 4 | 5.5 | 5 | 10 | 5 | 50 | 6 | 20 | 12 | 12 | 12 | 12 | 7.5 | 85 Ohms | TOP=L2:L3=L2/L4:L6=L5/L7:BOTTOM=L7 |
| PCIE_TX_CAP_N12 | TXC12-DIFF1 | PAIR | 5 | 5.5 | 5 | 10 | 5 | 50 | 6 | 20 | 12 | 12 | 12 | 12 | 7.5 | 85 Ohms | TOP=L2:L3=L2/L4:L6=L5/L7:BOTTOM=L7 |
| PCIE_TX_CAP_N12 | TXC12-DIFF1 | PAIR | 6 | 5.5 | 5 | 10 | 5 | 50 | 6 | 20 | 12 | 12 | 12 | 12 | 7.5 | 85 Ohms | TOP=L2:L3=L2/L4:L6=L5/L7:BOTTOM=L7 |
| PCIE_TX_CAP_N12 | TXC12-DIFF1 | PAIR | 7 | 5.5 | 5 | 10 | 5 | 50 | 6 | 20 | 12 | 12 | 12 | 12 | 7.5 | 85 Ohms | TOP=L2:L3=L2/L4:L6=L5/L7:BOTTOM=L7 |
| PCIE_TX_CAP_N12 | TXC12-DIFF1 | PAIR | 8 | 5.38 | 5 | 10 | 5 | 50 | 6 | 33 | 12 | 12 | 12 | 12 | 6.62 | 85 Ohms | TOP=L2:L3=L2/L4:L6=L5/L7:BOTTOM=L7 |
| PCIE_TX_CAP_P12 | TXC12-DIFF1 | PAIR | 1 | 5.38 | 5 | 10 | 5 | 50 | 6 | 33 | 12 | 12 | 12 | 12 | 6.62 | 85 Ohms | TOP=L2:L3=L2/L4:L6=L5/L7:BOTTOM=L7 |
| PCIE_TX_CAP_P12 | TXC12-DIFF1 | PAIR | 2 | 5.5 | 5 | 10 | 5 | 50 | 6 | 20 | 12 | 12 | 12 | 12 | 7.5 | 85 Ohms | TOP=L2:L3=L2/L4:L6=L5/L7:BOTTOM=L7 |
| PCIE_TX_CAP_P12 | TXC12-DIFF1 | PAIR | 3 | 5.5 | 5 | 10 | 5 | 50 | 6 | 20 | 12 | 12 | 12 | 12 | 7.5 | 85 Ohms | TOP=L2:L3=L2/L4:L6=L5/L7:BOTTOM=L7 |
| PCIE_TX_CAP_P12 | TXC12-DIFF1 | PAIR | 4 | 5.5 | 5 | 10 | 5 | 50 | 6 | 20 | 12 | 12 | 12 | 12 | 7.5 | 85 Ohms | TOP=L2:L3=L2/L4:L6=L5/L7:BOTTOM=L7 |
| PCIE_TX_CAP_P12 | TXC12-DIFF1 | PAIR | 5 | 5.5 | 5 | 10 | 5 | 50 | 6 | 20 | 12 | 12 | 12 | 12 | 7.5 | 85 Ohms | TOP=L2:L3=L2/L4:L6=L5/L7:BOTTOM=L7 |
| PCIE_TX_CAP_P12 | TXC12-DIFF1 | PAIR | 6 | 5.5 | 5 | 10 | 5 | 50 | 6 | 20 | 12 | 12 | 12 | 12 | 7.5 | 85 Ohms | TOP=L2:L3=L2/L4:L6=L5/L7:BOTTOM=L7 |
| PCIE_TX_CAP_P12 | TXC12-DIFF1 | PAIR | 7 | 5.5 | 5 | 10 | 5 | 50 | 6 | 20 | 12 | 12 | 12 | 12 | 7.5 | 85 Ohms | TOP=L2:L3=L2/L4:L6=L5/L7:BOTTOM=L7 |
| PCIE_TX_CAP_P12 | TXC12-DIFF1 | PAIR | 8 | 5.38 | 5 | 10 | 5 | 50 | 6 | 33 | 12 | 12 | 12 | 12 | 6.62 | 85 Ohms | TOP=L2:L3=L2/L4:L6=L5/L7:BOTTOM=L7 |
| PCIE_TX_CAP_N13 | TXC13-DIFF1 | PAIR | 1 | 5.38 | 5 | 10 | 5 | 50 | 6 | 33 | 12 | 12 | 12 | 12 | 6.62 | 85 Ohms | TOP=L2:L3=L2/L4:L6=L5/L7:BOTTOM=L7 |
| PCIE_TX_CAP_N13 | TXC13-DIFF1 | PAIR | 2 | 5.5 | 5 | 10 | 5 | 50 | 6 | 20 | 12 | 12 | 12 | 12 | 7.5 | 85 Ohms | TOP=L2:L3=L2/L4:L6=L5/L7:BOTTOM=L7 |
| PCIE_TX_CAP_N13 | TXC13-DIFF1 | PAIR | 3 | 5.5 | 5 | 10 | 5 | 50 | 6 | 20 | 12 | 12 | 12 | 12 | 7.5 | 85 Ohms | TOP=L2:L3=L2/L4:L6=L5/L7:BOTTOM=L7 |
| PCIE_TX_CAP_N13 | TXC13-DIFF1 | PAIR | 4 | 5.5 | 5 | 10 | 5 | 50 | 6 | 20 | 12 | 12 | 12 | 12 | 7.5 | 85 Ohms | TOP=L2:L3=L2/L4:L6=L5/L7:BOTTOM=L7 |
| PCIE_TX_CAP_N13 | TXC13-DIFF1 | PAIR | 5 | 5.5 | 5 | 10 | 5 | 50 | 6 | 20 | 12 | 12 | 12 | 12 | 7.5 | 85 Ohms | TOP=L2:L3=L2/L4:L6=L5/L7:BOTTOM=L7 |
| PCIE_TX_CAP_N13 | TXC13-DIFF1 | PAIR | 6 | 5.5 | 5 | 10 | 5 | 50 | 6 | 20 | 12 | 12 | 12 | 12 | 7.5 | 85 Ohms | TOP=L2:L3=L2/L4:L6=L5/L7:BOTTOM=L7 |
| PCIE_TX_CAP_N13 | TXC13-DIFF1 | PAIR | 7 | 5.5 | 5 | 10 | 5 | 50 | 6 | 20 | 12 | 12 | 12 | 12 | 7.5 | 85 Ohms | TOP=L2:L3=L2/L4:L6=L5/L7:BOTTOM=L7 |
| PCIE_TX_CAP_N13 | TXC13-DIFF1 | PAIR | 8 | 5.38 | 5 | 10 | 5 | 50 | 6 | 33 | 12 | 12 | 12 | 12 | 6.62 | 85 Ohms | TOP=L2:L3=L2/L4:L6=L5/L7:BOTTOM=L7 |
| PCIE_TX_CAP_P13 | TXC13-DIFF1 | PAIR | 1 | 5.38 | 5 | 10 | 5 | 50 | 6 | 33 | 12 | 12 | 12 | 12 | 6.62 | 85 Ohms | TOP=L2:L3=L2/L4:L6=L5/L7:BOTTOM=L7 |
| PCIE_TX_CAP_P13 | TXC13-DIFF1 | PAIR | 2 | 5.5 | 5 | 10 | 5 | 50 | 6 | 20 | 12 | 12 | 12 | 12 | 7.5 | 85 Ohms | TOP=L2:L3=L2/L4:L6=L5/L7:BOTTOM=L7 |
| PCIE_TX_CAP_P13 | TXC13-DIFF1 | PAIR | 3 | 5.5 | 5 | 10 | 5 | 50 | 6 | 20 | 12 | 12 | 12 | 12 | 7.5 | 85 Ohms | TOP=L2:L3=L2/L4:L6=L5/L7:BOTTOM=L7 |
| PCIE_TX_CAP_P13 | TXC13-DIFF1 | PAIR | 4 | 5.5 | 5 | 10 | 5 | 50 | 6 | 20 | 12 | 12 | 12 | 12 | 7.5 | 85 Ohms | TOP=L2:L3=L2/L4:L6=L5/L7:BOTTOM=L7 |
| PCIE_TX_CAP_P13 | TXC13-DIFF1 | PAIR | 5 | 5.5 | 5 | 10 | 5 | 50 | 6 | 20 | 12 | 12 | 12 | 12 | 7.5 | 85 Ohms | TOP=L2:L3=L2/L4:L6=L5/L7:BOTTOM=L7 |
| PCIE_TX_CAP_P13 | TXC13-DIFF1 | PAIR | 6 | 5.5 | 5 | 10 | 5 | 50 | 6 | 20 | 12 | 12 | 12 | 12 | 7.5 | 85 Ohms | TOP=L2:L3=L2/L4:L6=L5/L7:BOTTOM=L7 |
| PCIE_TX_CAP_P13 | TXC13-DIFF1 | PAIR | 7 | 5.5 | 5 | 10 | 5 | 50 | 6 | 20 | 12 | 12 | 12 | 12 | 7.5 | 85 Ohms | TOP=L2:L3=L2/L4:L6=L5/L7:BOTTOM=L7 |
| PCIE_TX_CAP_P13 | TXC13-DIFF1 | PAIR | 8 | 5.38 | 5 | 10 | 5 | 50 | 6 | 33 | 12 | 12 | 12 | 12 | 6.62 | 85 Ohms | TOP=L2:L3=L2/L4:L6=L5/L7:BOTTOM=L7 |
| PCIE_TX_CAP_N14 | TXC14-DIFF1 | PAIR | 1 | 5.38 | 5 | 10 | 5 | 50 | 6 | 33 | 12 | 12 | 12 | 12 | 6.62 | 85 Ohms | TOP=L2:L3=L2/L4:L6=L5/L7:BOTTOM=L7 |
| PCIE_TX_CAP_N14 | TXC14-DIFF1 | PAIR | 2 | 5.5 | 5 | 10 | 5 | 50 | 6 | 20 | 12 | 12 | 12 | 12 | 7.5 | 85 Ohms | TOP=L2:L3=L2/L4:L6=L5/L7:BOTTOM=L7 |
| PCIE_TX_CAP_N14 | TXC14-DIFF1 | PAIR | 3 | 5.5 | 5 | 10 | 5 | 50 | 6 | 20 | 12 | 12 | 12 | 12 | 7.5 | 85 Ohms | TOP=L2:L3=L2/L4:L6=L5/L7:BOTTOM=L7 |
| PCIE_TX_CAP_N14 | TXC14-DIFF1 | PAIR | 4 | 5.5 | 5 | 10 | 5 | 50 | 6 | 20 | 12 | 12 | 12 | 12 | 7.5 | 85 Ohms | TOP=L2:L3=L2/L4:L6=L5/L7:BOTTOM=L7 |
| PCIE_TX_CAP_N14 | TXC14-DIFF1 | PAIR | 5 | 5.5 | 5 | 10 | 5 | 50 | 6 | 20 | 12 | 12 | 12 | 12 | 7.5 | 85 Ohms | TOP=L2:L3=L2/L4:L6=L5/L7:BOTTOM=L7 |
| PCIE_TX_CAP_N14 | TXC14-DIFF1 | PAIR | 6 | 5.5 | 5 | 10 | 5 | 50 | 6 | 20 | 12 | 12 | 12 | 12 | 7.5 | 85 Ohms | TOP=L2:L3=L2/L4:L6=L5/L7:BOTTOM=L7 |
| PCIE_TX_CAP_N14 | TXC14-DIFF1 | PAIR | 7 | 5.5 | 5 | 10 | 5 | 50 | 6 | 20 | 12 | 12 | 12 | 12 | 7.5 | 85 Ohms | TOP=L2:L3=L2/L4:L6=L5/L7:BOTTOM=L7 |
| PCIE_TX_CAP_N14 | TXC14-DIFF1 | PAIR | 8 | 5.38 | 5 | 10 | 5 | 50 | 6 | 33 | 12 | 12 | 12 | 12 | 6.62 | 85 Ohms | TOP=L2:L3=L2/L4:L6=L5/L7:BOTTOM=L7 |
| PCIE_TX_CAP_P14 | TXC14-DIFF1 | PAIR | 1 | 5.38 | 5 | 10 | 5 | 50 | 6 | 33 | 12 | 12 | 12 | 12 | 6.62 | 85 Ohms | TOP=L2:L3=L2/L4:L6=L5/L7:BOTTOM=L7 |
| PCIE_TX_CAP_P14 | TXC14-DIFF1 | PAIR | 2 | 5.5 | 5 | 10 | 5 | 50 | 6 | 20 | 12 | 12 | 12 | 12 | 7.5 | 85 Ohms | TOP=L2:L3=L2/L4:L6=L5/L7:BOTTOM=L7 |
| PCIE_TX_CAP_P14 | TXC14-DIFF1 | PAIR | 3 | 5.5 | 5 | 10 | 5 | 50 | 6 | 20 | 12 | 12 | 12 | 12 | 7.5 | 85 Ohms | TOP=L2:L3=L2/L4:L6=L5/L7:BOTTOM=L7 |
| PCIE_TX_CAP_P14 | TXC14-DIFF1 | PAIR | 4 | 5.5 | 5 | 10 | 5 | 50 | 6 | 20 | 12 | 12 | 12 | 12 | 7.5 | 85 Ohms | TOP=L2:L3=L2/L4:L6=L5/L7:BOTTOM=L7 |
| PCIE_TX_CAP_P14 | TXC14-DIFF1 | PAIR | 5 | 5.5 | 5 | 10 | 5 | 50 | 6 | 20 | 12 | 12 | 12 | 12 | 7.5 | 85 Ohms | TOP=L2:L3=L2/L4:L6=L5/L7:BOTTOM=L7 |
| PCIE_TX_CAP_P14 | TXC14-DIFF1 | PAIR | 6 | 5.5 | 5 | 10 | 5 | 50 | 6 | 20 | 12 | 12 | 12 | 12 | 7.5 | 85 Ohms | TOP=L2:L3=L2/L4:L6=L5/L7:BOTTOM=L7 |
| PCIE_TX_CAP_P14 | TXC14-DIFF1 | PAIR | 7 | 5.5 | 5 | 10 | 5 | 50 | 6 | 20 | 12 | 12 | 12 | 12 | 7.5 | 85 Ohms | TOP=L2:L3=L2/L4:L6=L5/L7:BOTTOM=L7 |
| PCIE_TX_CAP_P14 | TXC14-DIFF1 | PAIR | 8 | 5.38 | 5 | 10 | 5 | 50 | 6 | 33 | 12 | 12 | 12 | 12 | 6.62 | 85 Ohms | TOP=L2:L3=L2/L4:L6=L5/L7:BOTTOM=L7 |
| PCIE_TX_CAP_N15 | TXC15-DIFF1 | PAIR | 1 | 5.38 | 5 | 10 | 5 | 50 | 6 | 33 | 12 | 12 | 12 | 12 | 6.62 | 85 Ohms | TOP=L2:L3=L2/L4:L6=L5/L7:BOTTOM=L7 |
| PCIE_TX_CAP_N15 | TXC15-DIFF1 | PAIR | 2 | 5.5 | 5 | 10 | 5 | 50 | 6 | 20 | 12 | 12 | 12 | 12 | 7.5 | 85 Ohms | TOP=L2:L3=L2/L4:L6=L5/L7:BOTTOM=L7 |
| PCIE_TX_CAP_N15 | TXC15-DIFF1 | PAIR | 3 | 5.5 | 5 | 10 | 5 | 50 | 6 | 20 | 12 | 12 | 12 | 12 | 7.5 | 85 Ohms | TOP=L2:L3=L2/L4:L6=L5/L7:BOTTOM=L7 |
| PCIE_TX_CAP_N15 | TXC15-DIFF1 | PAIR | 4 | 5.5 | 5 | 10 | 5 | 50 | 6 | 20 | 12 | 12 | 12 | 12 | 7.5 | 85 Ohms | TOP=L2:L3=L2/L4:L6=L5/L7:BOTTOM=L7 |
| PCIE_TX_CAP_N15 | TXC15-DIFF1 | PAIR | 5 | 5.5 | 5 | 10 | 5 | 50 | 6 | 20 | 12 | 12 | 12 | 12 | 7.5 | 85 Ohms | TOP=L2:L3=L2/L4:L6=L5/L7:BOTTOM=L7 |
| PCIE_TX_CAP_N15 | TXC15-DIFF1 | PAIR | 6 | 5.5 | 5 | 10 | 5 | 50 | 6 | 20 | 12 | 12 | 12 | 12 | 7.5 | 85 Ohms | TOP=L2:L3=L2/L4:L6=L5/L7:BOTTOM=L7 |
| PCIE_TX_CAP_N15 | TXC15-DIFF1 | PAIR | 7 | 5.5 | 5 | 10 | 5 | 50 | 6 | 20 | 12 | 12 | 12 | 12 | 7.5 | 85 Ohms | TOP=L2:L3=L2/L4:L6=L5/L7:BOTTOM=L7 |
| PCIE_TX_CAP_N15 | TXC15-DIFF1 | PAIR | 8 | 5.38 | 5 | 10 | 5 | 50 | 6 | 33 | 12 | 12 | 12 | 12 | 6.62 | 85 Ohms | TOP=L2:L3=L2/L4:L6=L5/L7:BOTTOM=L7 |
| PCIE_TX_CAP_P15 | TXC15-DIFF1 | PAIR | 1 | 5.38 | 5 | 10 | 5 | 50 | 6 | 33 | 12 | 12 | 12 | 12 | 6.62 | 85 Ohms | TOP=L2:L3=L2/L4:L6=L5/L7:BOTTOM=L7 |
| PCIE_TX_CAP_P15 | TXC15-DIFF1 | PAIR | 2 | 5.5 | 5 | 10 | 5 | 50 | 6 | 20 | 12 | 12 | 12 | 12 | 7.5 | 85 Ohms | TOP=L2:L3=L2/L4:L6=L5/L7:BOTTOM=L7 |
| PCIE_TX_CAP_P15 | TXC15-DIFF1 | PAIR | 3 | 5.5 | 5 | 10 | 5 | 50 | 6 | 20 | 12 | 12 | 12 | 12 | 7.5 | 85 Ohms | TOP=L2:L3=L2/L4:L6=L5/L7:BOTTOM=L7 |
| PCIE_TX_CAP_P15 | TXC15-DIFF1 | PAIR | 4 | 5.5 | 5 | 10 | 5 | 50 | 6 | 20 | 12 | 12 | 12 | 12 | 7.5 | 85 Ohms | TOP=L2:L3=L2/L4:L6=L5/L7:BOTTOM=L7 |
| PCIE_TX_CAP_P15 | TXC15-DIFF1 | PAIR | 5 | 5.5 | 5 | 10 | 5 | 50 | 6 | 20 | 12 | 12 | 12 | 12 | 7.5 | 85 Ohms | TOP=L2:L3=L2/L4:L6=L5/L7:BOTTOM=L7 |
| PCIE_TX_CAP_P15 | TXC15-DIFF1 | PAIR | 6 | 5.5 | 5 | 10 | 5 | 50 | 6 | 20 | 12 | 12 | 12 | 12 | 7.5 | 85 Ohms | TOP=L2:L3=L2/L4:L6=L5/L7:BOTTOM=L7 |
| PCIE_TX_CAP_P15 | TXC15-DIFF1 | PAIR | 7 | 5.5 | 5 | 10 | 5 | 50 | 6 | 20 | 12 | 12 | 12 | 12 | 7.5 | 85 Ohms | TOP=L2:L3=L2/L4:L6=L5/L7:BOTTOM=L7 |
| PCIE_TX_CAP_P15 | TXC15-DIFF1 | PAIR | 8 | 5.38 | 5 | 10 | 5 | 50 | 6 | 33 | 12 | 12 | 12 | 12 | 6.62 | 85 Ohms | TOP=L2:L3=L2/L4:L6=L5/L7:BOTTOM=L7 |
| PCIE_TX_CAP_N16 | TXC16-DIFF1 | PAIR | 1 | 5.38 | 5 | 10 | 5 | 50 | 6 | 33 | 12 | 12 | 12 | 12 | 6.62 | 85 Ohms | TOP=L2:L3=L2/L4:L6=L5/L7:BOTTOM=L7 |
| PCIE_TX_CAP_N16 | TXC16-DIFF1 | PAIR | 2 | 5.5 | 5 | 10 | 5 | 50 | 6 | 20 | 12 | 12 | 12 | 12 | 7.5 | 85 Ohms | TOP=L2:L3=L2/L4:L6=L5/L7:BOTTOM=L7 |
| PCIE_TX_CAP_N16 | TXC16-DIFF1 | PAIR | 3 | 5.5 | 5 | 10 | 5 | 50 | 6 | 20 | 12 | 12 | 12 | 12 | 7.5 | 85 Ohms | TOP=L2:L3=L2/L4:L6=L5/L7:BOTTOM=L7 |
| PCIE_TX_CAP_N16 | TXC16-DIFF1 | PAIR | 4 | 5.5 | 5 | 10 | 5 | 50 | 6 | 20 | 12 | 12 | 12 | 12 | 7.5 | 85 Ohms | TOP=L2:L3=L2/L4:L6=L5/L7:BOTTOM=L7 |
| PCIE_TX_CAP_N16 | TXC16-DIFF1 | PAIR | 5 | 5.5 | 5 | 10 | 5 | 50 | 6 | 20 | 12 | 12 | 12 | 12 | 7.5 | 85 Ohms | TOP=L2:L3=L2/L4:L6=L5/L7:BOTTOM=L7 |
| PCIE_TX_CAP_N16 | TXC16-DIFF1 | PAIR | 6 | 5.5 | 5 | 10 | 5 | 50 | 6 | 20 | 12 | 12 | 12 | 12 | 7.5 | 85 Ohms | TOP=L2:L3=L2/L4:L6=L5/L7:BOTTOM=L7 |
| PCIE_TX_CAP_N16 | TXC16-DIFF1 | PAIR | 7 | 5.5 | 5 | 10 | 5 | 50 | 6 | 20 | 12 | 12 | 12 | 12 | 7.5 | 85 Ohms | TOP=L2:L3=L2/L4:L6=L5/L7:BOTTOM=L7 |
| PCIE_TX_CAP_N16 | TXC16-DIFF1 | PAIR | 8 | 5.38 | 5 | 10 | 5 | 50 | 6 | 33 | 12 | 12 | 12 | 12 | 6.62 | 85 Ohms | TOP=L2:L3=L2/L4:L6=L5/L7:BOTTOM=L7 |
| PCIE_TX_CAP_P16 | TXC16-DIFF1 | PAIR | 1 | 5.38 | 5 | 10 | 5 | 50 | 6 | 33 | 12 | 12 | 12 | 12 | 6.62 | 85 Ohms | TOP=L2:L3=L2/L4:L6=L5/L7:BOTTOM=L7 |
| PCIE_TX_CAP_P16 | TXC16-DIFF1 | PAIR | 2 | 5.5 | 5 | 10 | 5 | 50 | 6 | 20 | 12 | 12 | 12 | 12 | 7.5 | 85 Ohms | TOP=L2:L3=L2/L4:L6=L5/L7:BOTTOM=L7 |
| PCIE_TX_CAP_P16 | TXC16-DIFF1 | PAIR | 3 | 5.5 | 5 | 10 | 5 | 50 | 6 | 20 | 12 | 12 | 12 | 12 | 7.5 | 85 Ohms | TOP=L2:L3=L2/L4:L6=L5/L7:BOTTOM=L7 |
| PCIE_TX_CAP_P16 | TXC16-DIFF1 | PAIR | 4 | 5.5 | 5 | 10 | 5 | 50 | 6 | 20 | 12 | 12 | 12 | 12 | 7.5 | 85 Ohms | TOP=L2:L3=L2/L4:L6=L5/L7:BOTTOM=L7 |
| PCIE_TX_CAP_P16 | TXC16-DIFF1 | PAIR | 5 | 5.5 | 5 | 10 | 5 | 50 | 6 | 20 | 12 | 12 | 12 | 12 | 7.5 | 85 Ohms | TOP=L2:L3=L2/L4:L6=L5/L7:BOTTOM=L7 |
| PCIE_TX_CAP_P16 | TXC16-DIFF1 | PAIR | 6 | 5.5 | 5 | 10 | 5 | 50 | 6 | 20 | 12 | 12 | 12 | 12 | 7.5 | 85 Ohms | TOP=L2:L3=L2/L4:L6=L5/L7:BOTTOM=L7 |
| PCIE_TX_CAP_P16 | TXC16-DIFF1 | PAIR | 7 | 5.5 | 5 | 10 | 5 | 50 | 6 | 20 | 12 | 12 | 12 | 12 | 7.5 | 85 Ohms | TOP=L2:L3=L2/L4:L6=L5/L7:BOTTOM=L7 |
| PCIE_TX_CAP_P16 | TXC16-DIFF1 | PAIR | 8 | 5.38 | 5 | 10 | 5 | 50 | 6 | 33 | 12 | 12 | 12 | 12 | 6.62 | 85 Ohms | TOP=L2:L3=L2/L4:L6=L5/L7:BOTTOM=L7 |
| PCIE_TX_CAP_N17 | TXC17-DIFF1 | PAIR | 1 | 5.38 | 5 | 10 | 5 | 50 | 6 | 33 | 12 | 12 | 12 | 12 | 6.62 | 85 Ohms | TOP=L2:L3=L2/L4:L6=L5/L7:BOTTOM=L7 |
| PCIE_TX_CAP_N17 | TXC17-DIFF1 | PAIR | 2 | 5.5 | 5 | 10 | 5 | 50 | 6 | 20 | 12 | 12 | 12 | 12 | 7.5 | 85 Ohms | TOP=L2:L3=L2/L4:L6=L5/L7:BOTTOM=L7 |
| PCIE_TX_CAP_N17 | TXC17-DIFF1 | PAIR | 3 | 5.5 | 5 | 10 | 5 | 50 | 6 | 20 | 12 | 12 | 12 | 12 | 7.5 | 85 Ohms | TOP=L2:L3=L2/L4:L6=L5/L7:BOTTOM=L7 |
| PCIE_TX_CAP_N17 | TXC17-DIFF1 | PAIR | 4 | 5.5 | 5 | 10 | 5 | 50 | 6 | 20 | 12 | 12 | 12 | 12 | 7.5 | 85 Ohms | TOP=L2:L3=L2/L4:L6=L5/L7:BOTTOM=L7 |
| PCIE_TX_CAP_N17 | TXC17-DIFF1 | PAIR | 5 | 5.5 | 5 | 10 | 5 | 50 | 6 | 20 | 12 | 12 | 12 | 12 | 7.5 | 85 Ohms | TOP=L2:L3=L2/L4:L6=L5/L7:BOTTOM=L7 |
| PCIE_TX_CAP_N17 | TXC17-DIFF1 | PAIR | 6 | 5.5 | 5 | 10 | 5 | 50 | 6 | 20 | 12 | 12 | 12 | 12 | 7.5 | 85 Ohms | TOP=L2:L3=L2/L4:L6=L5/L7:BOTTOM=L7 |
| PCIE_TX_CAP_N17 | TXC17-DIFF1 | PAIR | 7 | 5.5 | 5 | 10 | 5 | 50 | 6 | 20 | 12 | 12 | 12 | 12 | 7.5 | 85 Ohms | TOP=L2:L3=L2/L4:L6=L5/L7:BOTTOM=L7 |
| PCIE_TX_CAP_N17 | TXC17-DIFF1 | PAIR | 8 | 5.38 | 5 | 10 | 5 | 50 | 6 | 33 | 12 | 12 | 12 | 12 | 6.62 | 85 Ohms | TOP=L2:L3=L2/L4:L6=L5/L7:BOTTOM=L7 |
| PCIE_TX_CAP_P17 | TXC17-DIFF1 | PAIR | 1 | 5.38 | 5 | 10 | 5 | 50 | 6 | 33 | 12 | 12 | 12 | 12 | 6.62 | 85 Ohms | TOP=L2:L3=L2/L4:L6=L5/L7:BOTTOM=L7 |
| PCIE_TX_CAP_P17 | TXC17-DIFF1 | PAIR | 2 | 5.5 | 5 | 10 | 5 | 50 | 6 | 20 | 12 | 12 | 12 | 12 | 7.5 | 85 Ohms | TOP=L2:L3=L2/L4:L6=L5/L7:BOTTOM=L7 |
| PCIE_TX_CAP_P17 | TXC17-DIFF1 | PAIR | 3 | 5.5 | 5 | 10 | 5 | 50 | 6 | 20 | 12 | 12 | 12 | 12 | 7.5 | 85 Ohms | TOP=L2:L3=L2/L4:L6=L5/L7:BOTTOM=L7 |
| PCIE_TX_CAP_P17 | TXC17-DIFF1 | PAIR | 4 | 5.5 | 5 | 10 | 5 | 50 | 6 | 20 | 12 | 12 | 12 | 12 | 7.5 | 85 Ohms | TOP=L2:L3=L2/L4:L6=L5/L7:BOTTOM=L7 |
| PCIE_TX_CAP_P17 | TXC17-DIFF1 | PAIR | 5 | 5.5 | 5 | 10 | 5 | 50 | 6 | 20 | 12 | 12 | 12 | 12 | 7.5 | 85 Ohms | TOP=L2:L3=L2/L4:L6=L5/L7:BOTTOM=L7 |
| PCIE_TX_CAP_P17 | TXC17-DIFF1 | PAIR | 6 | 5.5 | 5 | 10 | 5 | 50 | 6 | 20 | 12 | 12 | 12 | 12 | 7.5 | 85 Ohms | TOP=L2:L3=L2/L4:L6=L5/L7:BOTTOM=L7 |
| PCIE_TX_CAP_P17 | TXC17-DIFF1 | PAIR | 7 | 5.5 | 5 | 10 | 5 | 50 | 6 | 20 | 12 | 12 | 12 | 12 | 7.5 | 85 Ohms | TOP=L2:L3=L2/L4:L6=L5/L7:BOTTOM=L7 |
| PCIE_TX_CAP_P17 | TXC17-DIFF1 | PAIR | 8 | 5.38 | 5 | 10 | 5 | 50 | 6 | 33 | 12 | 12 | 12 | 12 | 6.62 | 85 Ohms | TOP=L2:L3=L2/L4:L6=L5/L7:BOTTOM=L7 |
| PCIE_TX_CAP_N18 | TXC18-DIFF1 | PAIR | 1 | 5.38 | 5 | 10 | 5 | 50 | 6 | 33 | 12 | 12 | 12 | 12 | 6.62 | 85 Ohms | TOP=L2:L3=L2/L4:L6=L5/L7:BOTTOM=L7 |
| PCIE_TX_CAP_N18 | TXC18-DIFF1 | PAIR | 2 | 5.5 | 5 | 10 | 5 | 50 | 6 | 20 | 12 | 12 | 12 | 12 | 7.5 | 85 Ohms | TOP=L2:L3=L2/L4:L6=L5/L7:BOTTOM=L7 |
| PCIE_TX_CAP_N18 | TXC18-DIFF1 | PAIR | 3 | 5.5 | 5 | 10 | 5 | 50 | 6 | 20 | 12 | 12 | 12 | 12 | 7.5 | 85 Ohms | TOP=L2:L3=L2/L4:L6=L5/L7:BOTTOM=L7 |
| PCIE_TX_CAP_N18 | TXC18-DIFF1 | PAIR | 4 | 5.5 | 5 | 10 | 5 | 50 | 6 | 20 | 12 | 12 | 12 | 12 | 7.5 | 85 Ohms | TOP=L2:L3=L2/L4:L6=L5/L7:BOTTOM=L7 |
| PCIE_TX_CAP_N18 | TXC18-DIFF1 | PAIR | 5 | 5.5 | 5 | 10 | 5 | 50 | 6 | 20 | 12 | 12 | 12 | 12 | 7.5 | 85 Ohms | TOP=L2:L3=L2/L4:L6=L5/L7:BOTTOM=L7 |
| PCIE_TX_CAP_N18 | TXC18-DIFF1 | PAIR | 6 | 5.5 | 5 | 10 | 5 | 50 | 6 | 20 | 12 | 12 | 12 | 12 | 7.5 | 85 Ohms | TOP=L2:L3=L2/L4:L6=L5/L7:BOTTOM=L7 |
| PCIE_TX_CAP_N18 | TXC18-DIFF1 | PAIR | 7 | 5.5 | 5 | 10 | 5 | 50 | 6 | 20 | 12 | 12 | 12 | 12 | 7.5 | 85 Ohms | TOP=L2:L3=L2/L4:L6=L5/L7:BOTTOM=L7 |
| PCIE_TX_CAP_N18 | TXC18-DIFF1 | PAIR | 8 | 5.38 | 5 | 10 | 5 | 50 | 6 | 33 | 12 | 12 | 12 | 12 | 6.62 | 85 Ohms | TOP=L2:L3=L2/L4:L6=L5/L7:BOTTOM=L7 |
| PCIE_TX_CAP_P18 | TXC18-DIFF1 | PAIR | 1 | 5.38 | 5 | 10 | 5 | 50 | 6 | 33 | 12 | 12 | 12 | 12 | 6.62 | 85 Ohms | TOP=L2:L3=L2/L4:L6=L5/L7:BOTTOM=L7 |
| PCIE_TX_CAP_P18 | TXC18-DIFF1 | PAIR | 2 | 5.5 | 5 | 10 | 5 | 50 | 6 | 20 | 12 | 12 | 12 | 12 | 7.5 | 85 Ohms | TOP=L2:L3=L2/L4:L6=L5/L7:BOTTOM=L7 |
| PCIE_TX_CAP_P18 | TXC18-DIFF1 | PAIR | 3 | 5.5 | 5 | 10 | 5 | 50 | 6 | 20 | 12 | 12 | 12 | 12 | 7.5 | 85 Ohms | TOP=L2:L3=L2/L4:L6=L5/L7:BOTTOM=L7 |
| PCIE_TX_CAP_P18 | TXC18-DIFF1 | PAIR | 4 | 5.5 | 5 | 10 | 5 | 50 | 6 | 20 | 12 | 12 | 12 | 12 | 7.5 | 85 Ohms | TOP=L2:L3=L2/L4:L6=L5/L7:BOTTOM=L7 |
| PCIE_TX_CAP_P18 | TXC18-DIFF1 | PAIR | 5 | 5.5 | 5 | 10 | 5 | 50 | 6 | 20 | 12 | 12 | 12 | 12 | 7.5 | 85 Ohms | TOP=L2:L3=L2/L4:L6=L5/L7:BOTTOM=L7 |
| PCIE_TX_CAP_P18 | TXC18-DIFF1 | PAIR | 6 | 5.5 | 5 | 10 | 5 | 50 | 6 | 20 | 12 | 12 | 12 | 12 | 7.5 | 85 Ohms | TOP=L2:L3=L2/L4:L6=L5/L7:BOTTOM=L7 |
| PCIE_TX_CAP_P18 | TXC18-DIFF1 | PAIR | 7 | 5.5 | 5 | 10 | 5 | 50 | 6 | 20 | 12 | 12 | 12 | 12 | 7.5 | 85 Ohms | TOP=L2:L3=L2/L4:L6=L5/L7:BOTTOM=L7 |
| PCIE_TX_CAP_P18 | TXC18-DIFF1 | PAIR | 8 | 5.38 | 5 | 10 | 5 | 50 | 6 | 33 | 12 | 12 | 12 | 12 | 6.62 | 85 Ohms | TOP=L2:L3=L2/L4:L6=L5/L7:BOTTOM=L7 |
| PCIE_TX_CAP_N19 | TXC19-DIFF1 | PAIR | 1 | 5.38 | 5 | 10 | 5 | 50 | 6 | 33 | 12 | 12 | 12 | 12 | 6.62 | 85 Ohms | TOP=L2:L3=L2/L4:L6=L5/L7:BOTTOM=L7 |
| PCIE_TX_CAP_N19 | TXC19-DIFF1 | PAIR | 2 | 5.5 | 5 | 10 | 5 | 50 | 6 | 20 | 12 | 12 | 12 | 12 | 7.5 | 85 Ohms | TOP=L2:L3=L2/L4:L6=L5/L7:BOTTOM=L7 |
| PCIE_TX_CAP_N19 | TXC19-DIFF1 | PAIR | 3 | 5.5 | 5 | 10 | 5 | 50 | 6 | 20 | 12 | 12 | 12 | 12 | 7.5 | 85 Ohms | TOP=L2:L3=L2/L4:L6=L5/L7:BOTTOM=L7 |
| PCIE_TX_CAP_N19 | TXC19-DIFF1 | PAIR | 4 | 5.5 | 5 | 10 | 5 | 50 | 6 | 20 | 12 | 12 | 12 | 12 | 7.5 | 85 Ohms | TOP=L2:L3=L2/L4:L6=L5/L7:BOTTOM=L7 |
| PCIE_TX_CAP_N19 | TXC19-DIFF1 | PAIR | 5 | 5.5 | 5 | 10 | 5 | 50 | 6 | 20 | 12 | 12 | 12 | 12 | 7.5 | 85 Ohms | TOP=L2:L3=L2/L4:L6=L5/L7:BOTTOM=L7 |
| PCIE_TX_CAP_N19 | TXC19-DIFF1 | PAIR | 6 | 5.5 | 5 | 10 | 5 | 50 | 6 | 20 | 12 | 12 | 12 | 12 | 7.5 | 85 Ohms | TOP=L2:L3=L2/L4:L6=L5/L7:BOTTOM=L7 |
| PCIE_TX_CAP_N19 | TXC19-DIFF1 | PAIR | 7 | 5.5 | 5 | 10 | 5 | 50 | 6 | 20 | 12 | 12 | 12 | 12 | 7.5 | 85 Ohms | TOP=L2:L3=L2/L4:L6=L5/L7:BOTTOM=L7 |
| PCIE_TX_CAP_N19 | TXC19-DIFF1 | PAIR | 8 | 5.38 | 5 | 10 | 5 | 50 | 6 | 33 | 12 | 12 | 12 | 12 | 6.62 | 85 Ohms | TOP=L2:L3=L2/L4:L6=L5/L7:BOTTOM=L7 |
| PCIE_TX_CAP_P19 | TXC19-DIFF1 | PAIR | 1 | 5.38 | 5 | 10 | 5 | 50 | 6 | 33 | 12 | 12 | 12 | 12 | 6.62 | 85 Ohms | TOP=L2:L3=L2/L4:L6=L5/L7:BOTTOM=L7 |
| PCIE_TX_CAP_P19 | TXC19-DIFF1 | PAIR | 2 | 5.5 | 5 | 10 | 5 | 50 | 6 | 20 | 12 | 12 | 12 | 12 | 7.5 | 85 Ohms | TOP=L2:L3=L2/L4:L6=L5/L7:BOTTOM=L7 |
| PCIE_TX_CAP_P19 | TXC19-DIFF1 | PAIR | 3 | 5.5 | 5 | 10 | 5 | 50 | 6 | 20 | 12 | 12 | 12 | 12 | 7.5 | 85 Ohms | TOP=L2:L3=L2/L4:L6=L5/L7:BOTTOM=L7 |
| PCIE_TX_CAP_P19 | TXC19-DIFF1 | PAIR | 4 | 5.5 | 5 | 10 | 5 | 50 | 6 | 20 | 12 | 12 | 12 | 12 | 7.5 | 85 Ohms | TOP=L2:L3=L2/L4:L6=L5/L7:BOTTOM=L7 |
| PCIE_TX_CAP_P19 | TXC19-DIFF1 | PAIR | 5 | 5.5 | 5 | 10 | 5 | 50 | 6 | 20 | 12 | 12 | 12 | 12 | 7.5 | 85 Ohms | TOP=L2:L3=L2/L4:L6=L5/L7:BOTTOM=L7 |
| PCIE_TX_CAP_P19 | TXC19-DIFF1 | PAIR | 6 | 5.5 | 5 | 10 | 5 | 50 | 6 | 20 | 12 | 12 | 12 | 12 | 7.5 | 85 Ohms | TOP=L2:L3=L2/L4:L6=L5/L7:BOTTOM=L7 |
| PCIE_TX_CAP_P19 | TXC19-DIFF1 | PAIR | 7 | 5.5 | 5 | 10 | 5 | 50 | 6 | 20 | 12 | 12 | 12 | 12 | 7.5 | 85 Ohms | TOP=L2:L3=L2/L4:L6=L5/L7:BOTTOM=L7 |
| PCIE_TX_CAP_P19 | TXC19-DIFF1 | PAIR | 8 | 5.38 | 5 | 10 | 5 | 50 | 6 | 33 | 12 | 12 | 12 | 12 | 6.62 | 85 Ohms | TOP=L2:L3=L2/L4:L6=L5/L7:BOTTOM=L7 |
| PCIE_TX_CAP_N1 | TXC1-DIFF1 | PAIR | 1 | 5.38 | 5 | 10 | 5 | 50 | 6 | 33 | 12 | 12 | 12 | 12 | 6.62 | 85 Ohms | TOP=L2:L3=L2/L4:L6=L5/L7:BOTTOM=L7 |
| PCIE_TX_CAP_N1 | TXC1-DIFF1 | PAIR | 2 | 5.5 | 5 | 10 | 5 | 50 | 6 | 20 | 12 | 12 | 12 | 12 | 7.5 | 85 Ohms | TOP=L2:L3=L2/L4:L6=L5/L7:BOTTOM=L7 |
| PCIE_TX_CAP_N1 | TXC1-DIFF1 | PAIR | 3 | 5.5 | 5 | 10 | 5 | 50 | 6 | 20 | 12 | 12 | 12 | 12 | 7.5 | 85 Ohms | TOP=L2:L3=L2/L4:L6=L5/L7:BOTTOM=L7 |
| PCIE_TX_CAP_N1 | TXC1-DIFF1 | PAIR | 4 | 5.5 | 5 | 10 | 5 | 50 | 6 | 20 | 12 | 12 | 12 | 12 | 7.5 | 85 Ohms | TOP=L2:L3=L2/L4:L6=L5/L7:BOTTOM=L7 |
| PCIE_TX_CAP_N1 | TXC1-DIFF1 | PAIR | 5 | 5.5 | 5 | 10 | 5 | 50 | 6 | 20 | 12 | 12 | 12 | 12 | 7.5 | 85 Ohms | TOP=L2:L3=L2/L4:L6=L5/L7:BOTTOM=L7 |
| PCIE_TX_CAP_N1 | TXC1-DIFF1 | PAIR | 6 | 5.5 | 5 | 10 | 5 | 50 | 6 | 20 | 12 | 12 | 12 | 12 | 7.5 | 85 Ohms | TOP=L2:L3=L2/L4:L6=L5/L7:BOTTOM=L7 |
| PCIE_TX_CAP_N1 | TXC1-DIFF1 | PAIR | 7 | 5.5 | 5 | 10 | 5 | 50 | 6 | 20 | 12 | 12 | 12 | 12 | 7.5 | 85 Ohms | TOP=L2:L3=L2/L4:L6=L5/L7:BOTTOM=L7 |
| PCIE_TX_CAP_N1 | TXC1-DIFF1 | PAIR | 8 | 5.38 | 5 | 10 | 5 | 50 | 6 | 33 | 12 | 12 | 12 | 12 | 6.62 | 85 Ohms | TOP=L2:L3=L2/L4:L6=L5/L7:BOTTOM=L7 |
| PCIE_TX_CAP_P1 | TXC1-DIFF1 | PAIR | 1 | 5.38 | 5 | 10 | 5 | 50 | 6 | 33 | 12 | 12 | 12 | 12 | 6.62 | 85 Ohms | TOP=L2:L3=L2/L4:L6=L5/L7:BOTTOM=L7 |
| PCIE_TX_CAP_P1 | TXC1-DIFF1 | PAIR | 2 | 5.5 | 5 | 10 | 5 | 50 | 6 | 20 | 12 | 12 | 12 | 12 | 7.5 | 85 Ohms | TOP=L2:L3=L2/L4:L6=L5/L7:BOTTOM=L7 |
| PCIE_TX_CAP_P1 | TXC1-DIFF1 | PAIR | 3 | 5.5 | 5 | 10 | 5 | 50 | 6 | 20 | 12 | 12 | 12 | 12 | 7.5 | 85 Ohms | TOP=L2:L3=L2/L4:L6=L5/L7:BOTTOM=L7 |
| PCIE_TX_CAP_P1 | TXC1-DIFF1 | PAIR | 4 | 5.5 | 5 | 10 | 5 | 50 | 6 | 20 | 12 | 12 | 12 | 12 | 7.5 | 85 Ohms | TOP=L2:L3=L2/L4:L6=L5/L7:BOTTOM=L7 |
| PCIE_TX_CAP_P1 | TXC1-DIFF1 | PAIR | 5 | 5.5 | 5 | 10 | 5 | 50 | 6 | 20 | 12 | 12 | 12 | 12 | 7.5 | 85 Ohms | TOP=L2:L3=L2/L4:L6=L5/L7:BOTTOM=L7 |
| PCIE_TX_CAP_P1 | TXC1-DIFF1 | PAIR | 6 | 5.5 | 5 | 10 | 5 | 50 | 6 | 20 | 12 | 12 | 12 | 12 | 7.5 | 85 Ohms | TOP=L2:L3=L2/L4:L6=L5/L7:BOTTOM=L7 |
| PCIE_TX_CAP_P1 | TXC1-DIFF1 | PAIR | 7 | 5.5 | 5 | 10 | 5 | 50 | 6 | 20 | 12 | 12 | 12 | 12 | 7.5 | 85 Ohms | TOP=L2:L3=L2/L4:L6=L5/L7:BOTTOM=L7 |
| PCIE_TX_CAP_P1 | TXC1-DIFF1 | PAIR | 8 | 5.38 | 5 | 10 | 5 | 50 | 6 | 33 | 12 | 12 | 12 | 12 | 6.62 | 85 Ohms | TOP=L2:L3=L2/L4:L6=L5/L7:BOTTOM=L7 |
| PCIE_TX_CAP_N20 | TXC20-DIFF1 | PAIR | 1 | 5.38 | 5 | 10 | 5 | 50 | 6 | 33 | 12 | 12 | 12 | 12 | 6.62 | 85 Ohms | TOP=L2:L3=L2/L4:L6=L5/L7:BOTTOM=L7 |
| PCIE_TX_CAP_N20 | TXC20-DIFF1 | PAIR | 2 | 5.5 | 5 | 10 | 5 | 50 | 6 | 20 | 12 | 12 | 12 | 12 | 7.5 | 85 Ohms | TOP=L2:L3=L2/L4:L6=L5/L7:BOTTOM=L7 |
| PCIE_TX_CAP_N20 | TXC20-DIFF1 | PAIR | 3 | 5.5 | 5 | 10 | 5 | 50 | 6 | 20 | 12 | 12 | 12 | 12 | 7.5 | 85 Ohms | TOP=L2:L3=L2/L4:L6=L5/L7:BOTTOM=L7 |
| PCIE_TX_CAP_N20 | TXC20-DIFF1 | PAIR | 4 | 5.5 | 5 | 10 | 5 | 50 | 6 | 20 | 12 | 12 | 12 | 12 | 7.5 | 85 Ohms | TOP=L2:L3=L2/L4:L6=L5/L7:BOTTOM=L7 |
| PCIE_TX_CAP_N20 | TXC20-DIFF1 | PAIR | 5 | 5.5 | 5 | 10 | 5 | 50 | 6 | 20 | 12 | 12 | 12 | 12 | 7.5 | 85 Ohms | TOP=L2:L3=L2/L4:L6=L5/L7:BOTTOM=L7 |
| PCIE_TX_CAP_N20 | TXC20-DIFF1 | PAIR | 6 | 5.5 | 5 | 10 | 5 | 50 | 6 | 20 | 12 | 12 | 12 | 12 | 7.5 | 85 Ohms | TOP=L2:L3=L2/L4:L6=L5/L7:BOTTOM=L7 |
| PCIE_TX_CAP_N20 | TXC20-DIFF1 | PAIR | 7 | 5.5 | 5 | 10 | 5 | 50 | 6 | 20 | 12 | 12 | 12 | 12 | 7.5 | 85 Ohms | TOP=L2:L3=L2/L4:L6=L5/L7:BOTTOM=L7 |
| PCIE_TX_CAP_N20 | TXC20-DIFF1 | PAIR | 8 | 5.38 | 5 | 10 | 5 | 50 | 6 | 33 | 12 | 12 | 12 | 12 | 6.62 | 85 Ohms | TOP=L2:L3=L2/L4:L6=L5/L7:BOTTOM=L7 |
| PCIE_TX_CAP_P20 | TXC20-DIFF1 | PAIR | 1 | 5.38 | 5 | 10 | 5 | 50 | 6 | 33 | 12 | 12 | 12 | 12 | 6.62 | 85 Ohms | TOP=L2:L3=L2/L4:L6=L5/L7:BOTTOM=L7 |
| PCIE_TX_CAP_P20 | TXC20-DIFF1 | PAIR | 2 | 5.5 | 5 | 10 | 5 | 50 | 6 | 20 | 12 | 12 | 12 | 12 | 7.5 | 85 Ohms | TOP=L2:L3=L2/L4:L6=L5/L7:BOTTOM=L7 |
| PCIE_TX_CAP_P20 | TXC20-DIFF1 | PAIR | 3 | 5.5 | 5 | 10 | 5 | 50 | 6 | 20 | 12 | 12 | 12 | 12 | 7.5 | 85 Ohms | TOP=L2:L3=L2/L4:L6=L5/L7:BOTTOM=L7 |
| PCIE_TX_CAP_P20 | TXC20-DIFF1 | PAIR | 4 | 5.5 | 5 | 10 | 5 | 50 | 6 | 20 | 12 | 12 | 12 | 12 | 7.5 | 85 Ohms | TOP=L2:L3=L2/L4:L6=L5/L7:BOTTOM=L7 |
| PCIE_TX_CAP_P20 | TXC20-DIFF1 | PAIR | 5 | 5.5 | 5 | 10 | 5 | 50 | 6 | 20 | 12 | 12 | 12 | 12 | 7.5 | 85 Ohms | TOP=L2:L3=L2/L4:L6=L5/L7:BOTTOM=L7 |
| PCIE_TX_CAP_P20 | TXC20-DIFF1 | PAIR | 6 | 5.5 | 5 | 10 | 5 | 50 | 6 | 20 | 12 | 12 | 12 | 12 | 7.5 | 85 Ohms | TOP=L2:L3=L2/L4:L6=L5/L7:BOTTOM=L7 |
| PCIE_TX_CAP_P20 | TXC20-DIFF1 | PAIR | 7 | 5.5 | 5 | 10 | 5 | 50 | 6 | 20 | 12 | 12 | 12 | 12 | 7.5 | 85 Ohms | TOP=L2:L3=L2/L4:L6=L5/L7:BOTTOM=L7 |
| PCIE_TX_CAP_P20 | TXC20-DIFF1 | PAIR | 8 | 5.38 | 5 | 10 | 5 | 50 | 6 | 33 | 12 | 12 | 12 | 12 | 6.62 | 85 Ohms | TOP=L2:L3=L2/L4:L6=L5/L7:BOTTOM=L7 |
| PCIE_TX_CAP_N21 | TXC21-DIFF1 | PAIR | 1 | 5.38 | 5 | 10 | 5 | 50 | 6 | 33 | 12 | 12 | 12 | 12 | 6.62 | 85 Ohms | TOP=L2:L3=L2/L4:L6=L5/L7:BOTTOM=L7 |
| PCIE_TX_CAP_N21 | TXC21-DIFF1 | PAIR | 2 | 5.5 | 5 | 10 | 5 | 50 | 6 | 20 | 12 | 12 | 12 | 12 | 7.5 | 85 Ohms | TOP=L2:L3=L2/L4:L6=L5/L7:BOTTOM=L7 |
| PCIE_TX_CAP_N21 | TXC21-DIFF1 | PAIR | 3 | 5.5 | 5 | 10 | 5 | 50 | 6 | 20 | 12 | 12 | 12 | 12 | 7.5 | 85 Ohms | TOP=L2:L3=L2/L4:L6=L5/L7:BOTTOM=L7 |
| PCIE_TX_CAP_N21 | TXC21-DIFF1 | PAIR | 4 | 5.5 | 5 | 10 | 5 | 50 | 6 | 20 | 12 | 12 | 12 | 12 | 7.5 | 85 Ohms | TOP=L2:L3=L2/L4:L6=L5/L7:BOTTOM=L7 |
| PCIE_TX_CAP_N21 | TXC21-DIFF1 | PAIR | 5 | 5.5 | 5 | 10 | 5 | 50 | 6 | 20 | 12 | 12 | 12 | 12 | 7.5 | 85 Ohms | TOP=L2:L3=L2/L4:L6=L5/L7:BOTTOM=L7 |
| PCIE_TX_CAP_N21 | TXC21-DIFF1 | PAIR | 6 | 5.5 | 5 | 10 | 5 | 50 | 6 | 20 | 12 | 12 | 12 | 12 | 7.5 | 85 Ohms | TOP=L2:L3=L2/L4:L6=L5/L7:BOTTOM=L7 |
| PCIE_TX_CAP_N21 | TXC21-DIFF1 | PAIR | 7 | 5.5 | 5 | 10 | 5 | 50 | 6 | 20 | 12 | 12 | 12 | 12 | 7.5 | 85 Ohms | TOP=L2:L3=L2/L4:L6=L5/L7:BOTTOM=L7 |
| PCIE_TX_CAP_N21 | TXC21-DIFF1 | PAIR | 8 | 5.38 | 5 | 10 | 5 | 50 | 6 | 33 | 12 | 12 | 12 | 12 | 6.62 | 85 Ohms | TOP=L2:L3=L2/L4:L6=L5/L7:BOTTOM=L7 |
| PCIE_TX_CAP_P21 | TXC21-DIFF1 | PAIR | 1 | 5.38 | 5 | 10 | 5 | 50 | 6 | 33 | 12 | 12 | 12 | 12 | 6.62 | 85 Ohms | TOP=L2:L3=L2/L4:L6=L5/L7:BOTTOM=L7 |
| PCIE_TX_CAP_P21 | TXC21-DIFF1 | PAIR | 2 | 5.5 | 5 | 10 | 5 | 50 | 6 | 20 | 12 | 12 | 12 | 12 | 7.5 | 85 Ohms | TOP=L2:L3=L2/L4:L6=L5/L7:BOTTOM=L7 |
| PCIE_TX_CAP_P21 | TXC21-DIFF1 | PAIR | 3 | 5.5 | 5 | 10 | 5 | 50 | 6 | 20 | 12 | 12 | 12 | 12 | 7.5 | 85 Ohms | TOP=L2:L3=L2/L4:L6=L5/L7:BOTTOM=L7 |
| PCIE_TX_CAP_P21 | TXC21-DIFF1 | PAIR | 4 | 5.5 | 5 | 10 | 5 | 50 | 6 | 20 | 12 | 12 | 12 | 12 | 7.5 | 85 Ohms | TOP=L2:L3=L2/L4:L6=L5/L7:BOTTOM=L7 |
| PCIE_TX_CAP_P21 | TXC21-DIFF1 | PAIR | 5 | 5.5 | 5 | 10 | 5 | 50 | 6 | 20 | 12 | 12 | 12 | 12 | 7.5 | 85 Ohms | TOP=L2:L3=L2/L4:L6=L5/L7:BOTTOM=L7 |
| PCIE_TX_CAP_P21 | TXC21-DIFF1 | PAIR | 6 | 5.5 | 5 | 10 | 5 | 50 | 6 | 20 | 12 | 12 | 12 | 12 | 7.5 | 85 Ohms | TOP=L2:L3=L2/L4:L6=L5/L7:BOTTOM=L7 |
| PCIE_TX_CAP_P21 | TXC21-DIFF1 | PAIR | 7 | 5.5 | 5 | 10 | 5 | 50 | 6 | 20 | 12 | 12 | 12 | 12 | 7.5 | 85 Ohms | TOP=L2:L3=L2/L4:L6=L5/L7:BOTTOM=L7 |
| PCIE_TX_CAP_P21 | TXC21-DIFF1 | PAIR | 8 | 5.38 | 5 | 10 | 5 | 50 | 6 | 33 | 12 | 12 | 12 | 12 | 6.62 | 85 Ohms | TOP=L2:L3=L2/L4:L6=L5/L7:BOTTOM=L7 |
| PCIE_TX_CAP_N22 | TXC22-DIFF1 | PAIR | 1 | 5.38 | 5 | 10 | 5 | 50 | 6 | 33 | 12 | 12 | 12 | 12 | 6.62 | 85 Ohms | TOP=L2:L3=L2/L4:L6=L5/L7:BOTTOM=L7 |
| PCIE_TX_CAP_N22 | TXC22-DIFF1 | PAIR | 2 | 5.5 | 5 | 10 | 5 | 50 | 6 | 20 | 12 | 12 | 12 | 12 | 7.5 | 85 Ohms | TOP=L2:L3=L2/L4:L6=L5/L7:BOTTOM=L7 |
| PCIE_TX_CAP_N22 | TXC22-DIFF1 | PAIR | 3 | 5.5 | 5 | 10 | 5 | 50 | 6 | 20 | 12 | 12 | 12 | 12 | 7.5 | 85 Ohms | TOP=L2:L3=L2/L4:L6=L5/L7:BOTTOM=L7 |
| PCIE_TX_CAP_N22 | TXC22-DIFF1 | PAIR | 4 | 5.5 | 5 | 10 | 5 | 50 | 6 | 20 | 12 | 12 | 12 | 12 | 7.5 | 85 Ohms | TOP=L2:L3=L2/L4:L6=L5/L7:BOTTOM=L7 |
| PCIE_TX_CAP_N22 | TXC22-DIFF1 | PAIR | 5 | 5.5 | 5 | 10 | 5 | 50 | 6 | 20 | 12 | 12 | 12 | 12 | 7.5 | 85 Ohms | TOP=L2:L3=L2/L4:L6=L5/L7:BOTTOM=L7 |
| PCIE_TX_CAP_N22 | TXC22-DIFF1 | PAIR | 6 | 5.5 | 5 | 10 | 5 | 50 | 6 | 20 | 12 | 12 | 12 | 12 | 7.5 | 85 Ohms | TOP=L2:L3=L2/L4:L6=L5/L7:BOTTOM=L7 |
| PCIE_TX_CAP_N22 | TXC22-DIFF1 | PAIR | 7 | 5.5 | 5 | 10 | 5 | 50 | 6 | 20 | 12 | 12 | 12 | 12 | 7.5 | 85 Ohms | TOP=L2:L3=L2/L4:L6=L5/L7:BOTTOM=L7 |
| PCIE_TX_CAP_N22 | TXC22-DIFF1 | PAIR | 8 | 5.38 | 5 | 10 | 5 | 50 | 6 | 33 | 12 | 12 | 12 | 12 | 6.62 | 85 Ohms | TOP=L2:L3=L2/L4:L6=L5/L7:BOTTOM=L7 |
| PCIE_TX_CAP_P22 | TXC22-DIFF1 | PAIR | 1 | 5.38 | 5 | 10 | 5 | 50 | 6 | 33 | 12 | 12 | 12 | 12 | 6.62 | 85 Ohms | TOP=L2:L3=L2/L4:L6=L5/L7:BOTTOM=L7 |
| PCIE_TX_CAP_P22 | TXC22-DIFF1 | PAIR | 2 | 5.5 | 5 | 10 | 5 | 50 | 6 | 20 | 12 | 12 | 12 | 12 | 7.5 | 85 Ohms | TOP=L2:L3=L2/L4:L6=L5/L7:BOTTOM=L7 |
| PCIE_TX_CAP_P22 | TXC22-DIFF1 | PAIR | 3 | 5.5 | 5 | 10 | 5 | 50 | 6 | 20 | 12 | 12 | 12 | 12 | 7.5 | 85 Ohms | TOP=L2:L3=L2/L4:L6=L5/L7:BOTTOM=L7 |
| PCIE_TX_CAP_P22 | TXC22-DIFF1 | PAIR | 4 | 5.5 | 5 | 10 | 5 | 50 | 6 | 20 | 12 | 12 | 12 | 12 | 7.5 | 85 Ohms | TOP=L2:L3=L2/L4:L6=L5/L7:BOTTOM=L7 |
| PCIE_TX_CAP_P22 | TXC22-DIFF1 | PAIR | 5 | 5.5 | 5 | 10 | 5 | 50 | 6 | 20 | 12 | 12 | 12 | 12 | 7.5 | 85 Ohms | TOP=L2:L3=L2/L4:L6=L5/L7:BOTTOM=L7 |
| PCIE_TX_CAP_P22 | TXC22-DIFF1 | PAIR | 6 | 5.5 | 5 | 10 | 5 | 50 | 6 | 20 | 12 | 12 | 12 | 12 | 7.5 | 85 Ohms | TOP=L2:L3=L2/L4:L6=L5/L7:BOTTOM=L7 |
| PCIE_TX_CAP_P22 | TXC22-DIFF1 | PAIR | 7 | 5.5 | 5 | 10 | 5 | 50 | 6 | 20 | 12 | 12 | 12 | 12 | 7.5 | 85 Ohms | TOP=L2:L3=L2/L4:L6=L5/L7:BOTTOM=L7 |
| PCIE_TX_CAP_P22 | TXC22-DIFF1 | PAIR | 8 | 5.38 | 5 | 10 | 5 | 50 | 6 | 33 | 12 | 12 | 12 | 12 | 6.62 | 85 Ohms | TOP=L2:L3=L2/L4:L6=L5/L7:BOTTOM=L7 |
| PCIE_TX_CAP_N23 | TXC23-DIFF1 | PAIR | 1 | 5.38 | 5 | 10 | 5 | 50 | 6 | 33 | 12 | 12 | 12 | 12 | 6.62 | 85 Ohms | TOP=L2:L3=L2/L4:L6=L5/L7:BOTTOM=L7 |
| PCIE_TX_CAP_N23 | TXC23-DIFF1 | PAIR | 2 | 5.5 | 5 | 10 | 5 | 50 | 6 | 20 | 12 | 12 | 12 | 12 | 7.5 | 85 Ohms | TOP=L2:L3=L2/L4:L6=L5/L7:BOTTOM=L7 |
| PCIE_TX_CAP_N23 | TXC23-DIFF1 | PAIR | 3 | 5.5 | 5 | 10 | 5 | 50 | 6 | 20 | 12 | 12 | 12 | 12 | 7.5 | 85 Ohms | TOP=L2:L3=L2/L4:L6=L5/L7:BOTTOM=L7 |
| PCIE_TX_CAP_N23 | TXC23-DIFF1 | PAIR | 4 | 5.5 | 5 | 10 | 5 | 50 | 6 | 20 | 12 | 12 | 12 | 12 | 7.5 | 85 Ohms | TOP=L2:L3=L2/L4:L6=L5/L7:BOTTOM=L7 |
| PCIE_TX_CAP_N23 | TXC23-DIFF1 | PAIR | 5 | 5.5 | 5 | 10 | 5 | 50 | 6 | 20 | 12 | 12 | 12 | 12 | 7.5 | 85 Ohms | TOP=L2:L3=L2/L4:L6=L5/L7:BOTTOM=L7 |
| PCIE_TX_CAP_N23 | TXC23-DIFF1 | PAIR | 6 | 5.5 | 5 | 10 | 5 | 50 | 6 | 20 | 12 | 12 | 12 | 12 | 7.5 | 85 Ohms | TOP=L2:L3=L2/L4:L6=L5/L7:BOTTOM=L7 |
| PCIE_TX_CAP_N23 | TXC23-DIFF1 | PAIR | 7 | 5.5 | 5 | 10 | 5 | 50 | 6 | 20 | 12 | 12 | 12 | 12 | 7.5 | 85 Ohms | TOP=L2:L3=L2/L4:L6=L5/L7:BOTTOM=L7 |
| PCIE_TX_CAP_N23 | TXC23-DIFF1 | PAIR | 8 | 5.38 | 5 | 10 | 5 | 50 | 6 | 33 | 12 | 12 | 12 | 12 | 6.62 | 85 Ohms | TOP=L2:L3=L2/L4:L6=L5/L7:BOTTOM=L7 |
| PCIE_TX_CAP_P23 | TXC23-DIFF1 | PAIR | 1 | 5.38 | 5 | 10 | 5 | 50 | 6 | 33 | 12 | 12 | 12 | 12 | 6.62 | 85 Ohms | TOP=L2:L3=L2/L4:L6=L5/L7:BOTTOM=L7 |
| PCIE_TX_CAP_P23 | TXC23-DIFF1 | PAIR | 2 | 5.5 | 5 | 10 | 5 | 50 | 6 | 20 | 12 | 12 | 12 | 12 | 7.5 | 85 Ohms | TOP=L2:L3=L2/L4:L6=L5/L7:BOTTOM=L7 |
| PCIE_TX_CAP_P23 | TXC23-DIFF1 | PAIR | 3 | 5.5 | 5 | 10 | 5 | 50 | 6 | 20 | 12 | 12 | 12 | 12 | 7.5 | 85 Ohms | TOP=L2:L3=L2/L4:L6=L5/L7:BOTTOM=L7 |
| PCIE_TX_CAP_P23 | TXC23-DIFF1 | PAIR | 4 | 5.5 | 5 | 10 | 5 | 50 | 6 | 20 | 12 | 12 | 12 | 12 | 7.5 | 85 Ohms | TOP=L2:L3=L2/L4:L6=L5/L7:BOTTOM=L7 |
| PCIE_TX_CAP_P23 | TXC23-DIFF1 | PAIR | 5 | 5.5 | 5 | 10 | 5 | 50 | 6 | 20 | 12 | 12 | 12 | 12 | 7.5 | 85 Ohms | TOP=L2:L3=L2/L4:L6=L5/L7:BOTTOM=L7 |
| PCIE_TX_CAP_P23 | TXC23-DIFF1 | PAIR | 6 | 5.5 | 5 | 10 | 5 | 50 | 6 | 20 | 12 | 12 | 12 | 12 | 7.5 | 85 Ohms | TOP=L2:L3=L2/L4:L6=L5/L7:BOTTOM=L7 |
| PCIE_TX_CAP_P23 | TXC23-DIFF1 | PAIR | 7 | 5.5 | 5 | 10 | 5 | 50 | 6 | 20 | 12 | 12 | 12 | 12 | 7.5 | 85 Ohms | TOP=L2:L3=L2/L4:L6=L5/L7:BOTTOM=L7 |
| PCIE_TX_CAP_P23 | TXC23-DIFF1 | PAIR | 8 | 5.38 | 5 | 10 | 5 | 50 | 6 | 33 | 12 | 12 | 12 | 12 | 6.62 | 85 Ohms | TOP=L2:L3=L2/L4:L6=L5/L7:BOTTOM=L7 |
| PCIE_TX_CAP_N24 | TXC24-DIFF1 | PAIR | 1 | 5.38 | 5 | 10 | 5 | 50 | 6 | 33 | 12 | 12 | 12 | 12 | 6.62 | 85 Ohms | TOP=L2:L3=L2/L4:L6=L5/L7:BOTTOM=L7 |
| PCIE_TX_CAP_N24 | TXC24-DIFF1 | PAIR | 2 | 5.5 | 5 | 10 | 5 | 50 | 6 | 20 | 12 | 12 | 12 | 12 | 7.5 | 85 Ohms | TOP=L2:L3=L2/L4:L6=L5/L7:BOTTOM=L7 |
| PCIE_TX_CAP_N24 | TXC24-DIFF1 | PAIR | 3 | 5.5 | 5 | 10 | 5 | 50 | 6 | 20 | 12 | 12 | 12 | 12 | 7.5 | 85 Ohms | TOP=L2:L3=L2/L4:L6=L5/L7:BOTTOM=L7 |
| PCIE_TX_CAP_N24 | TXC24-DIFF1 | PAIR | 4 | 5.5 | 5 | 10 | 5 | 50 | 6 | 20 | 12 | 12 | 12 | 12 | 7.5 | 85 Ohms | TOP=L2:L3=L2/L4:L6=L5/L7:BOTTOM=L7 |
| PCIE_TX_CAP_N24 | TXC24-DIFF1 | PAIR | 5 | 5.5 | 5 | 10 | 5 | 50 | 6 | 20 | 12 | 12 | 12 | 12 | 7.5 | 85 Ohms | TOP=L2:L3=L2/L4:L6=L5/L7:BOTTOM=L7 |
| PCIE_TX_CAP_N24 | TXC24-DIFF1 | PAIR | 6 | 5.5 | 5 | 10 | 5 | 50 | 6 | 20 | 12 | 12 | 12 | 12 | 7.5 | 85 Ohms | TOP=L2:L3=L2/L4:L6=L5/L7:BOTTOM=L7 |
| PCIE_TX_CAP_N24 | TXC24-DIFF1 | PAIR | 7 | 5.5 | 5 | 10 | 5 | 50 | 6 | 20 | 12 | 12 | 12 | 12 | 7.5 | 85 Ohms | TOP=L2:L3=L2/L4:L6=L5/L7:BOTTOM=L7 |
| PCIE_TX_CAP_N24 | TXC24-DIFF1 | PAIR | 8 | 5.38 | 5 | 10 | 5 | 50 | 6 | 33 | 12 | 12 | 12 | 12 | 6.62 | 85 Ohms | TOP=L2:L3=L2/L4:L6=L5/L7:BOTTOM=L7 |
| PCIE_TX_CAP_P24 | TXC24-DIFF1 | PAIR | 1 | 5.38 | 5 | 10 | 5 | 50 | 6 | 33 | 12 | 12 | 12 | 12 | 6.62 | 85 Ohms | TOP=L2:L3=L2/L4:L6=L5/L7:BOTTOM=L7 |
| PCIE_TX_CAP_P24 | TXC24-DIFF1 | PAIR | 2 | 5.5 | 5 | 10 | 5 | 50 | 6 | 20 | 12 | 12 | 12 | 12 | 7.5 | 85 Ohms | TOP=L2:L3=L2/L4:L6=L5/L7:BOTTOM=L7 |
| PCIE_TX_CAP_P24 | TXC24-DIFF1 | PAIR | 3 | 5.5 | 5 | 10 | 5 | 50 | 6 | 20 | 12 | 12 | 12 | 12 | 7.5 | 85 Ohms | TOP=L2:L3=L2/L4:L6=L5/L7:BOTTOM=L7 |
| PCIE_TX_CAP_P24 | TXC24-DIFF1 | PAIR | 4 | 5.5 | 5 | 10 | 5 | 50 | 6 | 20 | 12 | 12 | 12 | 12 | 7.5 | 85 Ohms | TOP=L2:L3=L2/L4:L6=L5/L7:BOTTOM=L7 |
| PCIE_TX_CAP_P24 | TXC24-DIFF1 | PAIR | 5 | 5.5 | 5 | 10 | 5 | 50 | 6 | 20 | 12 | 12 | 12 | 12 | 7.5 | 85 Ohms | TOP=L2:L3=L2/L4:L6=L5/L7:BOTTOM=L7 |
| PCIE_TX_CAP_P24 | TXC24-DIFF1 | PAIR | 6 | 5.5 | 5 | 10 | 5 | 50 | 6 | 20 | 12 | 12 | 12 | 12 | 7.5 | 85 Ohms | TOP=L2:L3=L2/L4:L6=L5/L7:BOTTOM=L7 |
| PCIE_TX_CAP_P24 | TXC24-DIFF1 | PAIR | 7 | 5.5 | 5 | 10 | 5 | 50 | 6 | 20 | 12 | 12 | 12 | 12 | 7.5 | 85 Ohms | TOP=L2:L3=L2/L4:L6=L5/L7:BOTTOM=L7 |
| PCIE_TX_CAP_P24 | TXC24-DIFF1 | PAIR | 8 | 5.38 | 5 | 10 | 5 | 50 | 6 | 33 | 12 | 12 | 12 | 12 | 6.62 | 85 Ohms | TOP=L2:L3=L2/L4:L6=L5/L7:BOTTOM=L7 |
| PCIE_TX_CAP_N25 | TXC25-DIFF1 | PAIR | 1 | 5.38 | 5 | 10 | 5 | 50 | 6 | 33 | 12 | 12 | 12 | 12 | 6.62 | 85 Ohms | TOP=L2:L3=L2/L4:L6=L5/L7:BOTTOM=L7 |
| PCIE_TX_CAP_N25 | TXC25-DIFF1 | PAIR | 2 | 5.5 | 5 | 10 | 5 | 50 | 6 | 20 | 12 | 12 | 12 | 12 | 7.5 | 85 Ohms | TOP=L2:L3=L2/L4:L6=L5/L7:BOTTOM=L7 |
| PCIE_TX_CAP_N25 | TXC25-DIFF1 | PAIR | 3 | 5.5 | 5 | 10 | 5 | 50 | 6 | 20 | 12 | 12 | 12 | 12 | 7.5 | 85 Ohms | TOP=L2:L3=L2/L4:L6=L5/L7:BOTTOM=L7 |
| PCIE_TX_CAP_N25 | TXC25-DIFF1 | PAIR | 4 | 5.5 | 5 | 10 | 5 | 50 | 6 | 20 | 12 | 12 | 12 | 12 | 7.5 | 85 Ohms | TOP=L2:L3=L2/L4:L6=L5/L7:BOTTOM=L7 |
| PCIE_TX_CAP_N25 | TXC25-DIFF1 | PAIR | 5 | 5.5 | 5 | 10 | 5 | 50 | 6 | 20 | 12 | 12 | 12 | 12 | 7.5 | 85 Ohms | TOP=L2:L3=L2/L4:L6=L5/L7:BOTTOM=L7 |
| PCIE_TX_CAP_N25 | TXC25-DIFF1 | PAIR | 6 | 5.5 | 5 | 10 | 5 | 50 | 6 | 20 | 12 | 12 | 12 | 12 | 7.5 | 85 Ohms | TOP=L2:L3=L2/L4:L6=L5/L7:BOTTOM=L7 |
| PCIE_TX_CAP_N25 | TXC25-DIFF1 | PAIR | 7 | 5.5 | 5 | 10 | 5 | 50 | 6 | 20 | 12 | 12 | 12 | 12 | 7.5 | 85 Ohms | TOP=L2:L3=L2/L4:L6=L5/L7:BOTTOM=L7 |
| PCIE_TX_CAP_N25 | TXC25-DIFF1 | PAIR | 8 | 5.38 | 5 | 10 | 5 | 50 | 6 | 33 | 12 | 12 | 12 | 12 | 6.62 | 85 Ohms | TOP=L2:L3=L2/L4:L6=L5/L7:BOTTOM=L7 |
| PCIE_TX_CAP_P25 | TXC25-DIFF1 | PAIR | 1 | 5.38 | 5 | 10 | 5 | 50 | 6 | 33 | 12 | 12 | 12 | 12 | 6.62 | 85 Ohms | TOP=L2:L3=L2/L4:L6=L5/L7:BOTTOM=L7 |
| PCIE_TX_CAP_P25 | TXC25-DIFF1 | PAIR | 2 | 5.5 | 5 | 10 | 5 | 50 | 6 | 20 | 12 | 12 | 12 | 12 | 7.5 | 85 Ohms | TOP=L2:L3=L2/L4:L6=L5/L7:BOTTOM=L7 |
| PCIE_TX_CAP_P25 | TXC25-DIFF1 | PAIR | 3 | 5.5 | 5 | 10 | 5 | 50 | 6 | 20 | 12 | 12 | 12 | 12 | 7.5 | 85 Ohms | TOP=L2:L3=L2/L4:L6=L5/L7:BOTTOM=L7 |
| PCIE_TX_CAP_P25 | TXC25-DIFF1 | PAIR | 4 | 5.5 | 5 | 10 | 5 | 50 | 6 | 20 | 12 | 12 | 12 | 12 | 7.5 | 85 Ohms | TOP=L2:L3=L2/L4:L6=L5/L7:BOTTOM=L7 |
| PCIE_TX_CAP_P25 | TXC25-DIFF1 | PAIR | 5 | 5.5 | 5 | 10 | 5 | 50 | 6 | 20 | 12 | 12 | 12 | 12 | 7.5 | 85 Ohms | TOP=L2:L3=L2/L4:L6=L5/L7:BOTTOM=L7 |
| PCIE_TX_CAP_P25 | TXC25-DIFF1 | PAIR | 6 | 5.5 | 5 | 10 | 5 | 50 | 6 | 20 | 12 | 12 | 12 | 12 | 7.5 | 85 Ohms | TOP=L2:L3=L2/L4:L6=L5/L7:BOTTOM=L7 |
| PCIE_TX_CAP_P25 | TXC25-DIFF1 | PAIR | 7 | 5.5 | 5 | 10 | 5 | 50 | 6 | 20 | 12 | 12 | 12 | 12 | 7.5 | 85 Ohms | TOP=L2:L3=L2/L4:L6=L5/L7:BOTTOM=L7 |
| PCIE_TX_CAP_P25 | TXC25-DIFF1 | PAIR | 8 | 5.38 | 5 | 10 | 5 | 50 | 6 | 33 | 12 | 12 | 12 | 12 | 6.62 | 85 Ohms | TOP=L2:L3=L2/L4:L6=L5/L7:BOTTOM=L7 |
| PCIE_TX_CAP_N26 | TXC26-DIFF1 | PAIR | 1 | 5.38 | 5 | 10 | 5 | 50 | 6 | 33 | 12 | 12 | 12 | 12 | 6.62 | 85 Ohms | TOP=L2:L3=L2/L4:L6=L5/L7:BOTTOM=L7 |
| PCIE_TX_CAP_N26 | TXC26-DIFF1 | PAIR | 2 | 5.5 | 5 | 10 | 5 | 50 | 6 | 20 | 12 | 12 | 12 | 12 | 7.5 | 85 Ohms | TOP=L2:L3=L2/L4:L6=L5/L7:BOTTOM=L7 |
| PCIE_TX_CAP_N26 | TXC26-DIFF1 | PAIR | 3 | 5.5 | 5 | 10 | 5 | 50 | 6 | 20 | 12 | 12 | 12 | 12 | 7.5 | 85 Ohms | TOP=L2:L3=L2/L4:L6=L5/L7:BOTTOM=L7 |
| PCIE_TX_CAP_N26 | TXC26-DIFF1 | PAIR | 4 | 5.5 | 5 | 10 | 5 | 50 | 6 | 20 | 12 | 12 | 12 | 12 | 7.5 | 85 Ohms | TOP=L2:L3=L2/L4:L6=L5/L7:BOTTOM=L7 |
| PCIE_TX_CAP_N26 | TXC26-DIFF1 | PAIR | 5 | 5.5 | 5 | 10 | 5 | 50 | 6 | 20 | 12 | 12 | 12 | 12 | 7.5 | 85 Ohms | TOP=L2:L3=L2/L4:L6=L5/L7:BOTTOM=L7 |
| PCIE_TX_CAP_N26 | TXC26-DIFF1 | PAIR | 6 | 5.5 | 5 | 10 | 5 | 50 | 6 | 20 | 12 | 12 | 12 | 12 | 7.5 | 85 Ohms | TOP=L2:L3=L2/L4:L6=L5/L7:BOTTOM=L7 |
| PCIE_TX_CAP_N26 | TXC26-DIFF1 | PAIR | 7 | 5.5 | 5 | 10 | 5 | 50 | 6 | 20 | 12 | 12 | 12 | 12 | 7.5 | 85 Ohms | TOP=L2:L3=L2/L4:L6=L5/L7:BOTTOM=L7 |
| PCIE_TX_CAP_N26 | TXC26-DIFF1 | PAIR | 8 | 5.38 | 5 | 10 | 5 | 50 | 6 | 33 | 12 | 12 | 12 | 12 | 6.62 | 85 Ohms | TOP=L2:L3=L2/L4:L6=L5/L7:BOTTOM=L7 |
| PCIE_TX_CAP_P26 | TXC26-DIFF1 | PAIR | 1 | 5.38 | 5 | 10 | 5 | 50 | 6 | 33 | 12 | 12 | 12 | 12 | 6.62 | 85 Ohms | TOP=L2:L3=L2/L4:L6=L5/L7:BOTTOM=L7 |
| PCIE_TX_CAP_P26 | TXC26-DIFF1 | PAIR | 2 | 5.5 | 5 | 10 | 5 | 50 | 6 | 20 | 12 | 12 | 12 | 12 | 7.5 | 85 Ohms | TOP=L2:L3=L2/L4:L6=L5/L7:BOTTOM=L7 |
| PCIE_TX_CAP_P26 | TXC26-DIFF1 | PAIR | 3 | 5.5 | 5 | 10 | 5 | 50 | 6 | 20 | 12 | 12 | 12 | 12 | 7.5 | 85 Ohms | TOP=L2:L3=L2/L4:L6=L5/L7:BOTTOM=L7 |
| PCIE_TX_CAP_P26 | TXC26-DIFF1 | PAIR | 4 | 5.5 | 5 | 10 | 5 | 50 | 6 | 20 | 12 | 12 | 12 | 12 | 7.5 | 85 Ohms | TOP=L2:L3=L2/L4:L6=L5/L7:BOTTOM=L7 |
| PCIE_TX_CAP_P26 | TXC26-DIFF1 | PAIR | 5 | 5.5 | 5 | 10 | 5 | 50 | 6 | 20 | 12 | 12 | 12 | 12 | 7.5 | 85 Ohms | TOP=L2:L3=L2/L4:L6=L5/L7:BOTTOM=L7 |
| PCIE_TX_CAP_P26 | TXC26-DIFF1 | PAIR | 6 | 5.5 | 5 | 10 | 5 | 50 | 6 | 20 | 12 | 12 | 12 | 12 | 7.5 | 85 Ohms | TOP=L2:L3=L2/L4:L6=L5/L7:BOTTOM=L7 |
| PCIE_TX_CAP_P26 | TXC26-DIFF1 | PAIR | 7 | 5.5 | 5 | 10 | 5 | 50 | 6 | 20 | 12 | 12 | 12 | 12 | 7.5 | 85 Ohms | TOP=L2:L3=L2/L4:L6=L5/L7:BOTTOM=L7 |
| PCIE_TX_CAP_P26 | TXC26-DIFF1 | PAIR | 8 | 5.38 | 5 | 10 | 5 | 50 | 6 | 33 | 12 | 12 | 12 | 12 | 6.62 | 85 Ohms | TOP=L2:L3=L2/L4:L6=L5/L7:BOTTOM=L7 |
| PCIE_TX_CAP_N27 | TXC27-DIFF1 | PAIR | 1 | 5.38 | 5 | 10 | 5 | 50 | 6 | 33 | 12 | 12 | 12 | 12 | 6.62 | 85 Ohms | TOP=L2:L3=L2/L4:L6=L5/L7:BOTTOM=L7 |
| PCIE_TX_CAP_N27 | TXC27-DIFF1 | PAIR | 2 | 5.5 | 5 | 10 | 5 | 50 | 6 | 20 | 12 | 12 | 12 | 12 | 7.5 | 85 Ohms | TOP=L2:L3=L2/L4:L6=L5/L7:BOTTOM=L7 |
| PCIE_TX_CAP_N27 | TXC27-DIFF1 | PAIR | 3 | 5.5 | 5 | 10 | 5 | 50 | 6 | 20 | 12 | 12 | 12 | 12 | 7.5 | 85 Ohms | TOP=L2:L3=L2/L4:L6=L5/L7:BOTTOM=L7 |
| PCIE_TX_CAP_N27 | TXC27-DIFF1 | PAIR | 4 | 5.5 | 5 | 10 | 5 | 50 | 6 | 20 | 12 | 12 | 12 | 12 | 7.5 | 85 Ohms | TOP=L2:L3=L2/L4:L6=L5/L7:BOTTOM=L7 |
| PCIE_TX_CAP_N27 | TXC27-DIFF1 | PAIR | 5 | 5.5 | 5 | 10 | 5 | 50 | 6 | 20 | 12 | 12 | 12 | 12 | 7.5 | 85 Ohms | TOP=L2:L3=L2/L4:L6=L5/L7:BOTTOM=L7 |
| PCIE_TX_CAP_N27 | TXC27-DIFF1 | PAIR | 6 | 5.5 | 5 | 10 | 5 | 50 | 6 | 20 | 12 | 12 | 12 | 12 | 7.5 | 85 Ohms | TOP=L2:L3=L2/L4:L6=L5/L7:BOTTOM=L7 |
| PCIE_TX_CAP_N27 | TXC27-DIFF1 | PAIR | 7 | 5.5 | 5 | 10 | 5 | 50 | 6 | 20 | 12 | 12 | 12 | 12 | 7.5 | 85 Ohms | TOP=L2:L3=L2/L4:L6=L5/L7:BOTTOM=L7 |
| PCIE_TX_CAP_N27 | TXC27-DIFF1 | PAIR | 8 | 5.38 | 5 | 10 | 5 | 50 | 6 | 33 | 12 | 12 | 12 | 12 | 6.62 | 85 Ohms | TOP=L2:L3=L2/L4:L6=L5/L7:BOTTOM=L7 |
| PCIE_TX_CAP_P27 | TXC27-DIFF1 | PAIR | 1 | 5.38 | 5 | 10 | 5 | 50 | 6 | 33 | 12 | 12 | 12 | 12 | 6.62 | 85 Ohms | TOP=L2:L3=L2/L4:L6=L5/L7:BOTTOM=L7 |
| PCIE_TX_CAP_P27 | TXC27-DIFF1 | PAIR | 2 | 5.5 | 5 | 10 | 5 | 50 | 6 | 20 | 12 | 12 | 12 | 12 | 7.5 | 85 Ohms | TOP=L2:L3=L2/L4:L6=L5/L7:BOTTOM=L7 |
| PCIE_TX_CAP_P27 | TXC27-DIFF1 | PAIR | 3 | 5.5 | 5 | 10 | 5 | 50 | 6 | 20 | 12 | 12 | 12 | 12 | 7.5 | 85 Ohms | TOP=L2:L3=L2/L4:L6=L5/L7:BOTTOM=L7 |
| PCIE_TX_CAP_P27 | TXC27-DIFF1 | PAIR | 4 | 5.5 | 5 | 10 | 5 | 50 | 6 | 20 | 12 | 12 | 12 | 12 | 7.5 | 85 Ohms | TOP=L2:L3=L2/L4:L6=L5/L7:BOTTOM=L7 |
| PCIE_TX_CAP_P27 | TXC27-DIFF1 | PAIR | 5 | 5.5 | 5 | 10 | 5 | 50 | 6 | 20 | 12 | 12 | 12 | 12 | 7.5 | 85 Ohms | TOP=L2:L3=L2/L4:L6=L5/L7:BOTTOM=L7 |
| PCIE_TX_CAP_P27 | TXC27-DIFF1 | PAIR | 6 | 5.5 | 5 | 10 | 5 | 50 | 6 | 20 | 12 | 12 | 12 | 12 | 7.5 | 85 Ohms | TOP=L2:L3=L2/L4:L6=L5/L7:BOTTOM=L7 |
| PCIE_TX_CAP_P27 | TXC27-DIFF1 | PAIR | 7 | 5.5 | 5 | 10 | 5 | 50 | 6 | 20 | 12 | 12 | 12 | 12 | 7.5 | 85 Ohms | TOP=L2:L3=L2/L4:L6=L5/L7:BOTTOM=L7 |
| PCIE_TX_CAP_P27 | TXC27-DIFF1 | PAIR | 8 | 5.38 | 5 | 10 | 5 | 50 | 6 | 33 | 12 | 12 | 12 | 12 | 6.62 | 85 Ohms | TOP=L2:L3=L2/L4:L6=L5/L7:BOTTOM=L7 |
| PCIE_TX_CAP_N28 | TXC28-DIFF1 | PAIR | 1 | 5.38 | 5 | 10 | 5 | 50 | 6 | 33 | 12 | 12 | 12 | 12 | 6.62 | 85 Ohms | TOP=L2:L3=L2/L4:L6=L5/L7:BOTTOM=L7 |
| PCIE_TX_CAP_N28 | TXC28-DIFF1 | PAIR | 2 | 5.5 | 5 | 10 | 5 | 50 | 6 | 20 | 12 | 12 | 12 | 12 | 7.5 | 85 Ohms | TOP=L2:L3=L2/L4:L6=L5/L7:BOTTOM=L7 |
| PCIE_TX_CAP_N28 | TXC28-DIFF1 | PAIR | 3 | 5.5 | 5 | 10 | 5 | 50 | 6 | 20 | 12 | 12 | 12 | 12 | 7.5 | 85 Ohms | TOP=L2:L3=L2/L4:L6=L5/L7:BOTTOM=L7 |
| PCIE_TX_CAP_N28 | TXC28-DIFF1 | PAIR | 4 | 5.5 | 5 | 10 | 5 | 50 | 6 | 20 | 12 | 12 | 12 | 12 | 7.5 | 85 Ohms | TOP=L2:L3=L2/L4:L6=L5/L7:BOTTOM=L7 |
| PCIE_TX_CAP_N28 | TXC28-DIFF1 | PAIR | 5 | 5.5 | 5 | 10 | 5 | 50 | 6 | 20 | 12 | 12 | 12 | 12 | 7.5 | 85 Ohms | TOP=L2:L3=L2/L4:L6=L5/L7:BOTTOM=L7 |
| PCIE_TX_CAP_N28 | TXC28-DIFF1 | PAIR | 6 | 5.5 | 5 | 10 | 5 | 50 | 6 | 20 | 12 | 12 | 12 | 12 | 7.5 | 85 Ohms | TOP=L2:L3=L2/L4:L6=L5/L7:BOTTOM=L7 |
| PCIE_TX_CAP_N28 | TXC28-DIFF1 | PAIR | 7 | 5.5 | 5 | 10 | 5 | 50 | 6 | 20 | 12 | 12 | 12 | 12 | 7.5 | 85 Ohms | TOP=L2:L3=L2/L4:L6=L5/L7:BOTTOM=L7 |
| PCIE_TX_CAP_N28 | TXC28-DIFF1 | PAIR | 8 | 5.38 | 5 | 10 | 5 | 50 | 6 | 33 | 12 | 12 | 12 | 12 | 6.62 | 85 Ohms | TOP=L2:L3=L2/L4:L6=L5/L7:BOTTOM=L7 |
| PCIE_TX_CAP_P28 | TXC28-DIFF1 | PAIR | 1 | 5.38 | 5 | 10 | 5 | 50 | 6 | 33 | 12 | 12 | 12 | 12 | 6.62 | 85 Ohms | TOP=L2:L3=L2/L4:L6=L5/L7:BOTTOM=L7 |
| PCIE_TX_CAP_P28 | TXC28-DIFF1 | PAIR | 2 | 5.5 | 5 | 10 | 5 | 50 | 6 | 20 | 12 | 12 | 12 | 12 | 7.5 | 85 Ohms | TOP=L2:L3=L2/L4:L6=L5/L7:BOTTOM=L7 |
| PCIE_TX_CAP_P28 | TXC28-DIFF1 | PAIR | 3 | 5.5 | 5 | 10 | 5 | 50 | 6 | 20 | 12 | 12 | 12 | 12 | 7.5 | 85 Ohms | TOP=L2:L3=L2/L4:L6=L5/L7:BOTTOM=L7 |
| PCIE_TX_CAP_P28 | TXC28-DIFF1 | PAIR | 4 | 5.5 | 5 | 10 | 5 | 50 | 6 | 20 | 12 | 12 | 12 | 12 | 7.5 | 85 Ohms | TOP=L2:L3=L2/L4:L6=L5/L7:BOTTOM=L7 |
| PCIE_TX_CAP_P28 | TXC28-DIFF1 | PAIR | 5 | 5.5 | 5 | 10 | 5 | 50 | 6 | 20 | 12 | 12 | 12 | 12 | 7.5 | 85 Ohms | TOP=L2:L3=L2/L4:L6=L5/L7:BOTTOM=L7 |
| PCIE_TX_CAP_P28 | TXC28-DIFF1 | PAIR | 6 | 5.5 | 5 | 10 | 5 | 50 | 6 | 20 | 12 | 12 | 12 | 12 | 7.5 | 85 Ohms | TOP=L2:L3=L2/L4:L6=L5/L7:BOTTOM=L7 |
| PCIE_TX_CAP_P28 | TXC28-DIFF1 | PAIR | 7 | 5.5 | 5 | 10 | 5 | 50 | 6 | 20 | 12 | 12 | 12 | 12 | 7.5 | 85 Ohms | TOP=L2:L3=L2/L4:L6=L5/L7:BOTTOM=L7 |
| PCIE_TX_CAP_P28 | TXC28-DIFF1 | PAIR | 8 | 5.38 | 5 | 10 | 5 | 50 | 6 | 33 | 12 | 12 | 12 | 12 | 6.62 | 85 Ohms | TOP=L2:L3=L2/L4:L6=L5/L7:BOTTOM=L7 |
| PCIE_TX_CAP_N29 | TXC29-DIFF1 | PAIR | 1 | 5.38 | 5 | 10 | 5 | 50 | 6 | 33 | 12 | 12 | 12 | 12 | 6.62 | 85 Ohms | TOP=L2:L3=L2/L4:L6=L5/L7:BOTTOM=L7 |
| PCIE_TX_CAP_N29 | TXC29-DIFF1 | PAIR | 2 | 5.5 | 5 | 10 | 5 | 50 | 6 | 20 | 12 | 12 | 12 | 12 | 7.5 | 85 Ohms | TOP=L2:L3=L2/L4:L6=L5/L7:BOTTOM=L7 |
| PCIE_TX_CAP_N29 | TXC29-DIFF1 | PAIR | 3 | 5.5 | 5 | 10 | 5 | 50 | 6 | 20 | 12 | 12 | 12 | 12 | 7.5 | 85 Ohms | TOP=L2:L3=L2/L4:L6=L5/L7:BOTTOM=L7 |
| PCIE_TX_CAP_N29 | TXC29-DIFF1 | PAIR | 4 | 5.5 | 5 | 10 | 5 | 50 | 6 | 20 | 12 | 12 | 12 | 12 | 7.5 | 85 Ohms | TOP=L2:L3=L2/L4:L6=L5/L7:BOTTOM=L7 |
| PCIE_TX_CAP_N29 | TXC29-DIFF1 | PAIR | 5 | 5.5 | 5 | 10 | 5 | 50 | 6 | 20 | 12 | 12 | 12 | 12 | 7.5 | 85 Ohms | TOP=L2:L3=L2/L4:L6=L5/L7:BOTTOM=L7 |
| PCIE_TX_CAP_N29 | TXC29-DIFF1 | PAIR | 6 | 5.5 | 5 | 10 | 5 | 50 | 6 | 20 | 12 | 12 | 12 | 12 | 7.5 | 85 Ohms | TOP=L2:L3=L2/L4:L6=L5/L7:BOTTOM=L7 |
| PCIE_TX_CAP_N29 | TXC29-DIFF1 | PAIR | 7 | 5.5 | 5 | 10 | 5 | 50 | 6 | 20 | 12 | 12 | 12 | 12 | 7.5 | 85 Ohms | TOP=L2:L3=L2/L4:L6=L5/L7:BOTTOM=L7 |
| PCIE_TX_CAP_N29 | TXC29-DIFF1 | PAIR | 8 | 5.38 | 5 | 10 | 5 | 50 | 6 | 33 | 12 | 12 | 12 | 12 | 6.62 | 85 Ohms | TOP=L2:L3=L2/L4:L6=L5/L7:BOTTOM=L7 |
| PCIE_TX_CAP_P29 | TXC29-DIFF1 | PAIR | 1 | 5.38 | 5 | 10 | 5 | 50 | 6 | 33 | 12 | 12 | 12 | 12 | 6.62 | 85 Ohms | TOP=L2:L3=L2/L4:L6=L5/L7:BOTTOM=L7 |
| PCIE_TX_CAP_P29 | TXC29-DIFF1 | PAIR | 2 | 5.5 | 5 | 10 | 5 | 50 | 6 | 20 | 12 | 12 | 12 | 12 | 7.5 | 85 Ohms | TOP=L2:L3=L2/L4:L6=L5/L7:BOTTOM=L7 |
| PCIE_TX_CAP_P29 | TXC29-DIFF1 | PAIR | 3 | 5.5 | 5 | 10 | 5 | 50 | 6 | 20 | 12 | 12 | 12 | 12 | 7.5 | 85 Ohms | TOP=L2:L3=L2/L4:L6=L5/L7:BOTTOM=L7 |
| PCIE_TX_CAP_P29 | TXC29-DIFF1 | PAIR | 4 | 5.5 | 5 | 10 | 5 | 50 | 6 | 20 | 12 | 12 | 12 | 12 | 7.5 | 85 Ohms | TOP=L2:L3=L2/L4:L6=L5/L7:BOTTOM=L7 |
| PCIE_TX_CAP_P29 | TXC29-DIFF1 | PAIR | 5 | 5.5 | 5 | 10 | 5 | 50 | 6 | 20 | 12 | 12 | 12 | 12 | 7.5 | 85 Ohms | TOP=L2:L3=L2/L4:L6=L5/L7:BOTTOM=L7 |
| PCIE_TX_CAP_P29 | TXC29-DIFF1 | PAIR | 6 | 5.5 | 5 | 10 | 5 | 50 | 6 | 20 | 12 | 12 | 12 | 12 | 7.5 | 85 Ohms | TOP=L2:L3=L2/L4:L6=L5/L7:BOTTOM=L7 |
| PCIE_TX_CAP_P29 | TXC29-DIFF1 | PAIR | 7 | 5.5 | 5 | 10 | 5 | 50 | 6 | 20 | 12 | 12 | 12 | 12 | 7.5 | 85 Ohms | TOP=L2:L3=L2/L4:L6=L5/L7:BOTTOM=L7 |
| PCIE_TX_CAP_P29 | TXC29-DIFF1 | PAIR | 8 | 5.38 | 5 | 10 | 5 | 50 | 6 | 33 | 12 | 12 | 12 | 12 | 6.62 | 85 Ohms | TOP=L2:L3=L2/L4:L6=L5/L7:BOTTOM=L7 |
| PCIE_TX_CAP_N2 | TXC2-DIFF1 | PAIR | 1 | 5.38 | 5 | 10 | 5 | 50 | 6 | 33 | 12 | 12 | 12 | 12 | 6.62 | 85 Ohms | TOP=L2:L3=L2/L4:L6=L5/L7:BOTTOM=L7 |
| PCIE_TX_CAP_N2 | TXC2-DIFF1 | PAIR | 2 | 5.5 | 5 | 10 | 5 | 50 | 6 | 20 | 12 | 12 | 12 | 12 | 7.5 | 85 Ohms | TOP=L2:L3=L2/L4:L6=L5/L7:BOTTOM=L7 |
| PCIE_TX_CAP_N2 | TXC2-DIFF1 | PAIR | 3 | 5.5 | 5 | 10 | 5 | 50 | 6 | 20 | 12 | 12 | 12 | 12 | 7.5 | 85 Ohms | TOP=L2:L3=L2/L4:L6=L5/L7:BOTTOM=L7 |
| PCIE_TX_CAP_N2 | TXC2-DIFF1 | PAIR | 4 | 5.5 | 5 | 10 | 5 | 50 | 6 | 20 | 12 | 12 | 12 | 12 | 7.5 | 85 Ohms | TOP=L2:L3=L2/L4:L6=L5/L7:BOTTOM=L7 |
| PCIE_TX_CAP_N2 | TXC2-DIFF1 | PAIR | 5 | 5.5 | 5 | 10 | 5 | 50 | 6 | 20 | 12 | 12 | 12 | 12 | 7.5 | 85 Ohms | TOP=L2:L3=L2/L4:L6=L5/L7:BOTTOM=L7 |
| PCIE_TX_CAP_N2 | TXC2-DIFF1 | PAIR | 6 | 5.5 | 5 | 10 | 5 | 50 | 6 | 20 | 12 | 12 | 12 | 12 | 7.5 | 85 Ohms | TOP=L2:L3=L2/L4:L6=L5/L7:BOTTOM=L7 |
| PCIE_TX_CAP_N2 | TXC2-DIFF1 | PAIR | 7 | 5.5 | 5 | 10 | 5 | 50 | 6 | 20 | 12 | 12 | 12 | 12 | 7.5 | 85 Ohms | TOP=L2:L3=L2/L4:L6=L5/L7:BOTTOM=L7 |
| PCIE_TX_CAP_N2 | TXC2-DIFF1 | PAIR | 8 | 5.38 | 5 | 10 | 5 | 50 | 6 | 33 | 12 | 12 | 12 | 12 | 6.62 | 85 Ohms | TOP=L2:L3=L2/L4:L6=L5/L7:BOTTOM=L7 |
| PCIE_TX_CAP_P2 | TXC2-DIFF1 | PAIR | 1 | 5.38 | 5 | 10 | 5 | 50 | 6 | 33 | 12 | 12 | 12 | 12 | 6.62 | 85 Ohms | TOP=L2:L3=L2/L4:L6=L5/L7:BOTTOM=L7 |
| PCIE_TX_CAP_P2 | TXC2-DIFF1 | PAIR | 2 | 5.5 | 5 | 10 | 5 | 50 | 6 | 20 | 12 | 12 | 12 | 12 | 7.5 | 85 Ohms | TOP=L2:L3=L2/L4:L6=L5/L7:BOTTOM=L7 |
| PCIE_TX_CAP_P2 | TXC2-DIFF1 | PAIR | 3 | 5.5 | 5 | 10 | 5 | 50 | 6 | 20 | 12 | 12 | 12 | 12 | 7.5 | 85 Ohms | TOP=L2:L3=L2/L4:L6=L5/L7:BOTTOM=L7 |
| PCIE_TX_CAP_P2 | TXC2-DIFF1 | PAIR | 4 | 5.5 | 5 | 10 | 5 | 50 | 6 | 20 | 12 | 12 | 12 | 12 | 7.5 | 85 Ohms | TOP=L2:L3=L2/L4:L6=L5/L7:BOTTOM=L7 |
| PCIE_TX_CAP_P2 | TXC2-DIFF1 | PAIR | 5 | 5.5 | 5 | 10 | 5 | 50 | 6 | 20 | 12 | 12 | 12 | 12 | 7.5 | 85 Ohms | TOP=L2:L3=L2/L4:L6=L5/L7:BOTTOM=L7 |
| PCIE_TX_CAP_P2 | TXC2-DIFF1 | PAIR | 6 | 5.5 | 5 | 10 | 5 | 50 | 6 | 20 | 12 | 12 | 12 | 12 | 7.5 | 85 Ohms | TOP=L2:L3=L2/L4:L6=L5/L7:BOTTOM=L7 |
| PCIE_TX_CAP_P2 | TXC2-DIFF1 | PAIR | 7 | 5.5 | 5 | 10 | 5 | 50 | 6 | 20 | 12 | 12 | 12 | 12 | 7.5 | 85 Ohms | TOP=L2:L3=L2/L4:L6=L5/L7:BOTTOM=L7 |
| PCIE_TX_CAP_P2 | TXC2-DIFF1 | PAIR | 8 | 5.38 | 5 | 10 | 5 | 50 | 6 | 33 | 12 | 12 | 12 | 12 | 6.62 | 85 Ohms | TOP=L2:L3=L2/L4:L6=L5/L7:BOTTOM=L7 |
| PCIE_TX_CAP_N30 | TXC30-DIFF1 | PAIR | 1 | 5.38 | 5 | 10 | 5 | 50 | 6 | 33 | 12 | 12 | 12 | 12 | 6.62 | 85 Ohms | TOP=L2:L3=L2/L4:L6=L5/L7:BOTTOM=L7 |
| PCIE_TX_CAP_N30 | TXC30-DIFF1 | PAIR | 2 | 5.5 | 5 | 10 | 5 | 50 | 6 | 20 | 12 | 12 | 12 | 12 | 7.5 | 85 Ohms | TOP=L2:L3=L2/L4:L6=L5/L7:BOTTOM=L7 |
| PCIE_TX_CAP_N30 | TXC30-DIFF1 | PAIR | 3 | 5.5 | 5 | 10 | 5 | 50 | 6 | 20 | 12 | 12 | 12 | 12 | 7.5 | 85 Ohms | TOP=L2:L3=L2/L4:L6=L5/L7:BOTTOM=L7 |
| PCIE_TX_CAP_N30 | TXC30-DIFF1 | PAIR | 4 | 5.5 | 5 | 10 | 5 | 50 | 6 | 20 | 12 | 12 | 12 | 12 | 7.5 | 85 Ohms | TOP=L2:L3=L2/L4:L6=L5/L7:BOTTOM=L7 |
| PCIE_TX_CAP_N30 | TXC30-DIFF1 | PAIR | 5 | 5.5 | 5 | 10 | 5 | 50 | 6 | 20 | 12 | 12 | 12 | 12 | 7.5 | 85 Ohms | TOP=L2:L3=L2/L4:L6=L5/L7:BOTTOM=L7 |
| PCIE_TX_CAP_N30 | TXC30-DIFF1 | PAIR | 6 | 5.5 | 5 | 10 | 5 | 50 | 6 | 20 | 12 | 12 | 12 | 12 | 7.5 | 85 Ohms | TOP=L2:L3=L2/L4:L6=L5/L7:BOTTOM=L7 |
| PCIE_TX_CAP_N30 | TXC30-DIFF1 | PAIR | 7 | 5.5 | 5 | 10 | 5 | 50 | 6 | 20 | 12 | 12 | 12 | 12 | 7.5 | 85 Ohms | TOP=L2:L3=L2/L4:L6=L5/L7:BOTTOM=L7 |
| PCIE_TX_CAP_N30 | TXC30-DIFF1 | PAIR | 8 | 5.38 | 5 | 10 | 5 | 50 | 6 | 33 | 12 | 12 | 12 | 12 | 6.62 | 85 Ohms | TOP=L2:L3=L2/L4:L6=L5/L7:BOTTOM=L7 |
| PCIE_TX_CAP_P30 | TXC30-DIFF1 | PAIR | 1 | 5.38 | 5 | 10 | 5 | 50 | 6 | 33 | 12 | 12 | 12 | 12 | 6.62 | 85 Ohms | TOP=L2:L3=L2/L4:L6=L5/L7:BOTTOM=L7 |
| PCIE_TX_CAP_P30 | TXC30-DIFF1 | PAIR | 2 | 5.5 | 5 | 10 | 5 | 50 | 6 | 20 | 12 | 12 | 12 | 12 | 7.5 | 85 Ohms | TOP=L2:L3=L2/L4:L6=L5/L7:BOTTOM=L7 |
| PCIE_TX_CAP_P30 | TXC30-DIFF1 | PAIR | 3 | 5.5 | 5 | 10 | 5 | 50 | 6 | 20 | 12 | 12 | 12 | 12 | 7.5 | 85 Ohms | TOP=L2:L3=L2/L4:L6=L5/L7:BOTTOM=L7 |
| PCIE_TX_CAP_P30 | TXC30-DIFF1 | PAIR | 4 | 5.5 | 5 | 10 | 5 | 50 | 6 | 20 | 12 | 12 | 12 | 12 | 7.5 | 85 Ohms | TOP=L2:L3=L2/L4:L6=L5/L7:BOTTOM=L7 |
| PCIE_TX_CAP_P30 | TXC30-DIFF1 | PAIR | 5 | 5.5 | 5 | 10 | 5 | 50 | 6 | 20 | 12 | 12 | 12 | 12 | 7.5 | 85 Ohms | TOP=L2:L3=L2/L4:L6=L5/L7:BOTTOM=L7 |
| PCIE_TX_CAP_P30 | TXC30-DIFF1 | PAIR | 6 | 5.5 | 5 | 10 | 5 | 50 | 6 | 20 | 12 | 12 | 12 | 12 | 7.5 | 85 Ohms | TOP=L2:L3=L2/L4:L6=L5/L7:BOTTOM=L7 |
| PCIE_TX_CAP_P30 | TXC30-DIFF1 | PAIR | 7 | 5.5 | 5 | 10 | 5 | 50 | 6 | 20 | 12 | 12 | 12 | 12 | 7.5 | 85 Ohms | TOP=L2:L3=L2/L4:L6=L5/L7:BOTTOM=L7 |
| PCIE_TX_CAP_P30 | TXC30-DIFF1 | PAIR | 8 | 5.38 | 5 | 10 | 5 | 50 | 6 | 33 | 12 | 12 | 12 | 12 | 6.62 | 85 Ohms | TOP=L2:L3=L2/L4:L6=L5/L7:BOTTOM=L7 |
| PCIE_TX_CAP_N31 | TXC31-DIFF1 | PAIR | 1 | 5.38 | 5 | 10 | 5 | 50 | 6 | 33 | 12 | 12 | 12 | 12 | 6.62 | 85 Ohms | TOP=L2:L3=L2/L4:L6=L5/L7:BOTTOM=L7 |
| PCIE_TX_CAP_N31 | TXC31-DIFF1 | PAIR | 2 | 5.5 | 5 | 10 | 5 | 50 | 6 | 20 | 12 | 12 | 12 | 12 | 7.5 | 85 Ohms | TOP=L2:L3=L2/L4:L6=L5/L7:BOTTOM=L7 |
| PCIE_TX_CAP_N31 | TXC31-DIFF1 | PAIR | 3 | 5.5 | 5 | 10 | 5 | 50 | 6 | 20 | 12 | 12 | 12 | 12 | 7.5 | 85 Ohms | TOP=L2:L3=L2/L4:L6=L5/L7:BOTTOM=L7 |
| PCIE_TX_CAP_N31 | TXC31-DIFF1 | PAIR | 4 | 5.5 | 5 | 10 | 5 | 50 | 6 | 20 | 12 | 12 | 12 | 12 | 7.5 | 85 Ohms | TOP=L2:L3=L2/L4:L6=L5/L7:BOTTOM=L7 |
| PCIE_TX_CAP_N31 | TXC31-DIFF1 | PAIR | 5 | 5.5 | 5 | 10 | 5 | 50 | 6 | 20 | 12 | 12 | 12 | 12 | 7.5 | 85 Ohms | TOP=L2:L3=L2/L4:L6=L5/L7:BOTTOM=L7 |
| PCIE_TX_CAP_N31 | TXC31-DIFF1 | PAIR | 6 | 5.5 | 5 | 10 | 5 | 50 | 6 | 20 | 12 | 12 | 12 | 12 | 7.5 | 85 Ohms | TOP=L2:L3=L2/L4:L6=L5/L7:BOTTOM=L7 |
| PCIE_TX_CAP_N31 | TXC31-DIFF1 | PAIR | 7 | 5.5 | 5 | 10 | 5 | 50 | 6 | 20 | 12 | 12 | 12 | 12 | 7.5 | 85 Ohms | TOP=L2:L3=L2/L4:L6=L5/L7:BOTTOM=L7 |
| PCIE_TX_CAP_N31 | TXC31-DIFF1 | PAIR | 8 | 5.38 | 5 | 10 | 5 | 50 | 6 | 33 | 12 | 12 | 12 | 12 | 6.62 | 85 Ohms | TOP=L2:L3=L2/L4:L6=L5/L7:BOTTOM=L7 |
| PCIE_TX_CAP_P31 | TXC31-DIFF1 | PAIR | 1 | 5.38 | 5 | 10 | 5 | 50 | 6 | 33 | 12 | 12 | 12 | 12 | 6.62 | 85 Ohms | TOP=L2:L3=L2/L4:L6=L5/L7:BOTTOM=L7 |
| PCIE_TX_CAP_P31 | TXC31-DIFF1 | PAIR | 2 | 5.5 | 5 | 10 | 5 | 50 | 6 | 20 | 12 | 12 | 12 | 12 | 7.5 | 85 Ohms | TOP=L2:L3=L2/L4:L6=L5/L7:BOTTOM=L7 |
| PCIE_TX_CAP_P31 | TXC31-DIFF1 | PAIR | 3 | 5.5 | 5 | 10 | 5 | 50 | 6 | 20 | 12 | 12 | 12 | 12 | 7.5 | 85 Ohms | TOP=L2:L3=L2/L4:L6=L5/L7:BOTTOM=L7 |
| PCIE_TX_CAP_P31 | TXC31-DIFF1 | PAIR | 4 | 5.5 | 5 | 10 | 5 | 50 | 6 | 20 | 12 | 12 | 12 | 12 | 7.5 | 85 Ohms | TOP=L2:L3=L2/L4:L6=L5/L7:BOTTOM=L7 |
| PCIE_TX_CAP_P31 | TXC31-DIFF1 | PAIR | 5 | 5.5 | 5 | 10 | 5 | 50 | 6 | 20 | 12 | 12 | 12 | 12 | 7.5 | 85 Ohms | TOP=L2:L3=L2/L4:L6=L5/L7:BOTTOM=L7 |
| PCIE_TX_CAP_P31 | TXC31-DIFF1 | PAIR | 6 | 5.5 | 5 | 10 | 5 | 50 | 6 | 20 | 12 | 12 | 12 | 12 | 7.5 | 85 Ohms | TOP=L2:L3=L2/L4:L6=L5/L7:BOTTOM=L7 |
| PCIE_TX_CAP_P31 | TXC31-DIFF1 | PAIR | 7 | 5.5 | 5 | 10 | 5 | 50 | 6 | 20 | 12 | 12 | 12 | 12 | 7.5 | 85 Ohms | TOP=L2:L3=L2/L4:L6=L5/L7:BOTTOM=L7 |
| PCIE_TX_CAP_P31 | TXC31-DIFF1 | PAIR | 8 | 5.38 | 5 | 10 | 5 | 50 | 6 | 33 | 12 | 12 | 12 | 12 | 6.62 | 85 Ohms | TOP=L2:L3=L2/L4:L6=L5/L7:BOTTOM=L7 |
| PCIE_TX_CAP_N32 | TXC32-DIFF1 | PAIR | 1 | 5.38 | 5 | 10 | 5 | 50 | 6 | 33 | 12 | 12 | 12 | 12 | 6.62 | 85 Ohms | TOP=L2:L3=L2/L4:L6=L5/L7:BOTTOM=L7 |
| PCIE_TX_CAP_N32 | TXC32-DIFF1 | PAIR | 2 | 5.5 | 5 | 10 | 5 | 50 | 6 | 20 | 12 | 12 | 12 | 12 | 7.5 | 85 Ohms | TOP=L2:L3=L2/L4:L6=L5/L7:BOTTOM=L7 |
| PCIE_TX_CAP_N32 | TXC32-DIFF1 | PAIR | 3 | 5.5 | 5 | 10 | 5 | 50 | 6 | 20 | 12 | 12 | 12 | 12 | 7.5 | 85 Ohms | TOP=L2:L3=L2/L4:L6=L5/L7:BOTTOM=L7 |
| PCIE_TX_CAP_N32 | TXC32-DIFF1 | PAIR | 4 | 5.5 | 5 | 10 | 5 | 50 | 6 | 20 | 12 | 12 | 12 | 12 | 7.5 | 85 Ohms | TOP=L2:L3=L2/L4:L6=L5/L7:BOTTOM=L7 |
| PCIE_TX_CAP_N32 | TXC32-DIFF1 | PAIR | 5 | 5.5 | 5 | 10 | 5 | 50 | 6 | 20 | 12 | 12 | 12 | 12 | 7.5 | 85 Ohms | TOP=L2:L3=L2/L4:L6=L5/L7:BOTTOM=L7 |
| PCIE_TX_CAP_N32 | TXC32-DIFF1 | PAIR | 6 | 5.5 | 5 | 10 | 5 | 50 | 6 | 20 | 12 | 12 | 12 | 12 | 7.5 | 85 Ohms | TOP=L2:L3=L2/L4:L6=L5/L7:BOTTOM=L7 |
| PCIE_TX_CAP_N32 | TXC32-DIFF1 | PAIR | 7 | 5.5 | 5 | 10 | 5 | 50 | 6 | 20 | 12 | 12 | 12 | 12 | 7.5 | 85 Ohms | TOP=L2:L3=L2/L4:L6=L5/L7:BOTTOM=L7 |
| PCIE_TX_CAP_N32 | TXC32-DIFF1 | PAIR | 8 | 5.38 | 5 | 10 | 5 | 50 | 6 | 33 | 12 | 12 | 12 | 12 | 6.62 | 85 Ohms | TOP=L2:L3=L2/L4:L6=L5/L7:BOTTOM=L7 |
| PCIE_TX_CAP_P32 | TXC32-DIFF1 | PAIR | 1 | 5.38 | 5 | 10 | 5 | 50 | 6 | 33 | 12 | 12 | 12 | 12 | 6.62 | 85 Ohms | TOP=L2:L3=L2/L4:L6=L5/L7:BOTTOM=L7 |
| PCIE_TX_CAP_P32 | TXC32-DIFF1 | PAIR | 2 | 5.5 | 5 | 10 | 5 | 50 | 6 | 20 | 12 | 12 | 12 | 12 | 7.5 | 85 Ohms | TOP=L2:L3=L2/L4:L6=L5/L7:BOTTOM=L7 |
| PCIE_TX_CAP_P32 | TXC32-DIFF1 | PAIR | 3 | 5.5 | 5 | 10 | 5 | 50 | 6 | 20 | 12 | 12 | 12 | 12 | 7.5 | 85 Ohms | TOP=L2:L3=L2/L4:L6=L5/L7:BOTTOM=L7 |
| PCIE_TX_CAP_P32 | TXC32-DIFF1 | PAIR | 4 | 5.5 | 5 | 10 | 5 | 50 | 6 | 20 | 12 | 12 | 12 | 12 | 7.5 | 85 Ohms | TOP=L2:L3=L2/L4:L6=L5/L7:BOTTOM=L7 |
| PCIE_TX_CAP_P32 | TXC32-DIFF1 | PAIR | 5 | 5.5 | 5 | 10 | 5 | 50 | 6 | 20 | 12 | 12 | 12 | 12 | 7.5 | 85 Ohms | TOP=L2:L3=L2/L4:L6=L5/L7:BOTTOM=L7 |
| PCIE_TX_CAP_P32 | TXC32-DIFF1 | PAIR | 6 | 5.5 | 5 | 10 | 5 | 50 | 6 | 20 | 12 | 12 | 12 | 12 | 7.5 | 85 Ohms | TOP=L2:L3=L2/L4:L6=L5/L7:BOTTOM=L7 |
| PCIE_TX_CAP_P32 | TXC32-DIFF1 | PAIR | 7 | 5.5 | 5 | 10 | 5 | 50 | 6 | 20 | 12 | 12 | 12 | 12 | 7.5 | 85 Ohms | TOP=L2:L3=L2/L4:L6=L5/L7:BOTTOM=L7 |
| PCIE_TX_CAP_P32 | TXC32-DIFF1 | PAIR | 8 | 5.38 | 5 | 10 | 5 | 50 | 6 | 33 | 12 | 12 | 12 | 12 | 6.62 | 85 Ohms | TOP=L2:L3=L2/L4:L6=L5/L7:BOTTOM=L7 |
| PCIE_TX_CAP_N33 | TXC33-DIFF1 | PAIR | 1 | 5.38 | 5 | 10 | 5 | 50 | 6 | 33 | 12 | 12 | 12 | 12 | 6.62 | 85 Ohms | TOP=L2:L3=L2/L4:L6=L5/L7:BOTTOM=L7 |
| PCIE_TX_CAP_N33 | TXC33-DIFF1 | PAIR | 2 | 5.5 | 5 | 10 | 5 | 50 | 6 | 20 | 12 | 12 | 12 | 12 | 7.5 | 85 Ohms | TOP=L2:L3=L2/L4:L6=L5/L7:BOTTOM=L7 |
| PCIE_TX_CAP_N33 | TXC33-DIFF1 | PAIR | 3 | 5.5 | 5 | 10 | 5 | 50 | 6 | 20 | 12 | 12 | 12 | 12 | 7.5 | 85 Ohms | TOP=L2:L3=L2/L4:L6=L5/L7:BOTTOM=L7 |
| PCIE_TX_CAP_N33 | TXC33-DIFF1 | PAIR | 4 | 5.5 | 5 | 10 | 5 | 50 | 6 | 20 | 12 | 12 | 12 | 12 | 7.5 | 85 Ohms | TOP=L2:L3=L2/L4:L6=L5/L7:BOTTOM=L7 |
| PCIE_TX_CAP_N33 | TXC33-DIFF1 | PAIR | 5 | 5.5 | 5 | 10 | 5 | 50 | 6 | 20 | 12 | 12 | 12 | 12 | 7.5 | 85 Ohms | TOP=L2:L3=L2/L4:L6=L5/L7:BOTTOM=L7 |
| PCIE_TX_CAP_N33 | TXC33-DIFF1 | PAIR | 6 | 5.5 | 5 | 10 | 5 | 50 | 6 | 20 | 12 | 12 | 12 | 12 | 7.5 | 85 Ohms | TOP=L2:L3=L2/L4:L6=L5/L7:BOTTOM=L7 |
| PCIE_TX_CAP_N33 | TXC33-DIFF1 | PAIR | 7 | 5.5 | 5 | 10 | 5 | 50 | 6 | 20 | 12 | 12 | 12 | 12 | 7.5 | 85 Ohms | TOP=L2:L3=L2/L4:L6=L5/L7:BOTTOM=L7 |
| PCIE_TX_CAP_N33 | TXC33-DIFF1 | PAIR | 8 | 5.38 | 5 | 10 | 5 | 50 | 6 | 33 | 12 | 12 | 12 | 12 | 6.62 | 85 Ohms | TOP=L2:L3=L2/L4:L6=L5/L7:BOTTOM=L7 |
| PCIE_TX_CAP_P33 | TXC33-DIFF1 | PAIR | 1 | 5.38 | 5 | 10 | 5 | 50 | 6 | 33 | 12 | 12 | 12 | 12 | 6.62 | 85 Ohms | TOP=L2:L3=L2/L4:L6=L5/L7:BOTTOM=L7 |
| PCIE_TX_CAP_P33 | TXC33-DIFF1 | PAIR | 2 | 5.5 | 5 | 10 | 5 | 50 | 6 | 20 | 12 | 12 | 12 | 12 | 7.5 | 85 Ohms | TOP=L2:L3=L2/L4:L6=L5/L7:BOTTOM=L7 |
| PCIE_TX_CAP_P33 | TXC33-DIFF1 | PAIR | 3 | 5.5 | 5 | 10 | 5 | 50 | 6 | 20 | 12 | 12 | 12 | 12 | 7.5 | 85 Ohms | TOP=L2:L3=L2/L4:L6=L5/L7:BOTTOM=L7 |
| PCIE_TX_CAP_P33 | TXC33-DIFF1 | PAIR | 4 | 5.5 | 5 | 10 | 5 | 50 | 6 | 20 | 12 | 12 | 12 | 12 | 7.5 | 85 Ohms | TOP=L2:L3=L2/L4:L6=L5/L7:BOTTOM=L7 |
| PCIE_TX_CAP_P33 | TXC33-DIFF1 | PAIR | 5 | 5.5 | 5 | 10 | 5 | 50 | 6 | 20 | 12 | 12 | 12 | 12 | 7.5 | 85 Ohms | TOP=L2:L3=L2/L4:L6=L5/L7:BOTTOM=L7 |
| PCIE_TX_CAP_P33 | TXC33-DIFF1 | PAIR | 6 | 5.5 | 5 | 10 | 5 | 50 | 6 | 20 | 12 | 12 | 12 | 12 | 7.5 | 85 Ohms | TOP=L2:L3=L2/L4:L6=L5/L7:BOTTOM=L7 |
| PCIE_TX_CAP_P33 | TXC33-DIFF1 | PAIR | 7 | 5.5 | 5 | 10 | 5 | 50 | 6 | 20 | 12 | 12 | 12 | 12 | 7.5 | 85 Ohms | TOP=L2:L3=L2/L4:L6=L5/L7:BOTTOM=L7 |
| PCIE_TX_CAP_P33 | TXC33-DIFF1 | PAIR | 8 | 5.38 | 5 | 10 | 5 | 50 | 6 | 33 | 12 | 12 | 12 | 12 | 6.62 | 85 Ohms | TOP=L2:L3=L2/L4:L6=L5/L7:BOTTOM=L7 |
| PCIE_TX_CAP_N34 | TXC34-DIFF1 | PAIR | 1 | 5.38 | 5 | 10 | 5 | 50 | 6 | 33 | 12 | 12 | 12 | 12 | 6.62 | 85 Ohms | TOP=L2:L3=L2/L4:L6=L5/L7:BOTTOM=L7 |
| PCIE_TX_CAP_N34 | TXC34-DIFF1 | PAIR | 2 | 5.5 | 5 | 10 | 5 | 50 | 6 | 20 | 12 | 12 | 12 | 12 | 7.5 | 85 Ohms | TOP=L2:L3=L2/L4:L6=L5/L7:BOTTOM=L7 |
| PCIE_TX_CAP_N34 | TXC34-DIFF1 | PAIR | 3 | 5.5 | 5 | 10 | 5 | 50 | 6 | 20 | 12 | 12 | 12 | 12 | 7.5 | 85 Ohms | TOP=L2:L3=L2/L4:L6=L5/L7:BOTTOM=L7 |
| PCIE_TX_CAP_N34 | TXC34-DIFF1 | PAIR | 4 | 5.5 | 5 | 10 | 5 | 50 | 6 | 20 | 12 | 12 | 12 | 12 | 7.5 | 85 Ohms | TOP=L2:L3=L2/L4:L6=L5/L7:BOTTOM=L7 |
| PCIE_TX_CAP_N34 | TXC34-DIFF1 | PAIR | 5 | 5.5 | 5 | 10 | 5 | 50 | 6 | 20 | 12 | 12 | 12 | 12 | 7.5 | 85 Ohms | TOP=L2:L3=L2/L4:L6=L5/L7:BOTTOM=L7 |
| PCIE_TX_CAP_N34 | TXC34-DIFF1 | PAIR | 6 | 5.5 | 5 | 10 | 5 | 50 | 6 | 20 | 12 | 12 | 12 | 12 | 7.5 | 85 Ohms | TOP=L2:L3=L2/L4:L6=L5/L7:BOTTOM=L7 |
| PCIE_TX_CAP_N34 | TXC34-DIFF1 | PAIR | 7 | 5.5 | 5 | 10 | 5 | 50 | 6 | 20 | 12 | 12 | 12 | 12 | 7.5 | 85 Ohms | TOP=L2:L3=L2/L4:L6=L5/L7:BOTTOM=L7 |
| PCIE_TX_CAP_N34 | TXC34-DIFF1 | PAIR | 8 | 5.38 | 5 | 10 | 5 | 50 | 6 | 33 | 12 | 12 | 12 | 12 | 6.62 | 85 Ohms | TOP=L2:L3=L2/L4:L6=L5/L7:BOTTOM=L7 |
| PCIE_TX_CAP_P34 | TXC34-DIFF1 | PAIR | 1 | 5.38 | 5 | 10 | 5 | 50 | 6 | 33 | 12 | 12 | 12 | 12 | 6.62 | 85 Ohms | TOP=L2:L3=L2/L4:L6=L5/L7:BOTTOM=L7 |
| PCIE_TX_CAP_P34 | TXC34-DIFF1 | PAIR | 2 | 5.5 | 5 | 10 | 5 | 50 | 6 | 20 | 12 | 12 | 12 | 12 | 7.5 | 85 Ohms | TOP=L2:L3=L2/L4:L6=L5/L7:BOTTOM=L7 |
| PCIE_TX_CAP_P34 | TXC34-DIFF1 | PAIR | 3 | 5.5 | 5 | 10 | 5 | 50 | 6 | 20 | 12 | 12 | 12 | 12 | 7.5 | 85 Ohms | TOP=L2:L3=L2/L4:L6=L5/L7:BOTTOM=L7 |
| PCIE_TX_CAP_P34 | TXC34-DIFF1 | PAIR | 4 | 5.5 | 5 | 10 | 5 | 50 | 6 | 20 | 12 | 12 | 12 | 12 | 7.5 | 85 Ohms | TOP=L2:L3=L2/L4:L6=L5/L7:BOTTOM=L7 |
| PCIE_TX_CAP_P34 | TXC34-DIFF1 | PAIR | 5 | 5.5 | 5 | 10 | 5 | 50 | 6 | 20 | 12 | 12 | 12 | 12 | 7.5 | 85 Ohms | TOP=L2:L3=L2/L4:L6=L5/L7:BOTTOM=L7 |
| PCIE_TX_CAP_P34 | TXC34-DIFF1 | PAIR | 6 | 5.5 | 5 | 10 | 5 | 50 | 6 | 20 | 12 | 12 | 12 | 12 | 7.5 | 85 Ohms | TOP=L2:L3=L2/L4:L6=L5/L7:BOTTOM=L7 |
| PCIE_TX_CAP_P34 | TXC34-DIFF1 | PAIR | 7 | 5.5 | 5 | 10 | 5 | 50 | 6 | 20 | 12 | 12 | 12 | 12 | 7.5 | 85 Ohms | TOP=L2:L3=L2/L4:L6=L5/L7:BOTTOM=L7 |
| PCIE_TX_CAP_P34 | TXC34-DIFF1 | PAIR | 8 | 5.38 | 5 | 10 | 5 | 50 | 6 | 33 | 12 | 12 | 12 | 12 | 6.62 | 85 Ohms | TOP=L2:L3=L2/L4:L6=L5/L7:BOTTOM=L7 |
| PCIE_TX_CAP_N35 | TXC35-DIFF1 | PAIR | 1 | 5.38 | 5 | 10 | 5 | 50 | 6 | 33 | 12 | 12 | 12 | 12 | 6.62 | 85 Ohms | TOP=L2:L3=L2/L4:L6=L5/L7:BOTTOM=L7 |
| PCIE_TX_CAP_N35 | TXC35-DIFF1 | PAIR | 2 | 5.5 | 5 | 10 | 5 | 50 | 6 | 20 | 12 | 12 | 12 | 12 | 7.5 | 85 Ohms | TOP=L2:L3=L2/L4:L6=L5/L7:BOTTOM=L7 |
| PCIE_TX_CAP_N35 | TXC35-DIFF1 | PAIR | 3 | 5.5 | 5 | 10 | 5 | 50 | 6 | 20 | 12 | 12 | 12 | 12 | 7.5 | 85 Ohms | TOP=L2:L3=L2/L4:L6=L5/L7:BOTTOM=L7 |
| PCIE_TX_CAP_N35 | TXC35-DIFF1 | PAIR | 4 | 5.5 | 5 | 10 | 5 | 50 | 6 | 20 | 12 | 12 | 12 | 12 | 7.5 | 85 Ohms | TOP=L2:L3=L2/L4:L6=L5/L7:BOTTOM=L7 |
| PCIE_TX_CAP_N35 | TXC35-DIFF1 | PAIR | 5 | 5.5 | 5 | 10 | 5 | 50 | 6 | 20 | 12 | 12 | 12 | 12 | 7.5 | 85 Ohms | TOP=L2:L3=L2/L4:L6=L5/L7:BOTTOM=L7 |
| PCIE_TX_CAP_N35 | TXC35-DIFF1 | PAIR | 6 | 5.5 | 5 | 10 | 5 | 50 | 6 | 20 | 12 | 12 | 12 | 12 | 7.5 | 85 Ohms | TOP=L2:L3=L2/L4:L6=L5/L7:BOTTOM=L7 |
| PCIE_TX_CAP_N35 | TXC35-DIFF1 | PAIR | 7 | 5.5 | 5 | 10 | 5 | 50 | 6 | 20 | 12 | 12 | 12 | 12 | 7.5 | 85 Ohms | TOP=L2:L3=L2/L4:L6=L5/L7:BOTTOM=L7 |
| PCIE_TX_CAP_N35 | TXC35-DIFF1 | PAIR | 8 | 5.38 | 5 | 10 | 5 | 50 | 6 | 33 | 12 | 12 | 12 | 12 | 6.62 | 85 Ohms | TOP=L2:L3=L2/L4:L6=L5/L7:BOTTOM=L7 |
| PCIE_TX_CAP_P35 | TXC35-DIFF1 | PAIR | 1 | 5.38 | 5 | 10 | 5 | 50 | 6 | 33 | 12 | 12 | 12 | 12 | 6.62 | 85 Ohms | TOP=L2:L3=L2/L4:L6=L5/L7:BOTTOM=L7 |
| PCIE_TX_CAP_P35 | TXC35-DIFF1 | PAIR | 2 | 5.5 | 5 | 10 | 5 | 50 | 6 | 20 | 12 | 12 | 12 | 12 | 7.5 | 85 Ohms | TOP=L2:L3=L2/L4:L6=L5/L7:BOTTOM=L7 |
| PCIE_TX_CAP_P35 | TXC35-DIFF1 | PAIR | 3 | 5.5 | 5 | 10 | 5 | 50 | 6 | 20 | 12 | 12 | 12 | 12 | 7.5 | 85 Ohms | TOP=L2:L3=L2/L4:L6=L5/L7:BOTTOM=L7 |
| PCIE_TX_CAP_P35 | TXC35-DIFF1 | PAIR | 4 | 5.5 | 5 | 10 | 5 | 50 | 6 | 20 | 12 | 12 | 12 | 12 | 7.5 | 85 Ohms | TOP=L2:L3=L2/L4:L6=L5/L7:BOTTOM=L7 |
| PCIE_TX_CAP_P35 | TXC35-DIFF1 | PAIR | 5 | 5.5 | 5 | 10 | 5 | 50 | 6 | 20 | 12 | 12 | 12 | 12 | 7.5 | 85 Ohms | TOP=L2:L3=L2/L4:L6=L5/L7:BOTTOM=L7 |
| PCIE_TX_CAP_P35 | TXC35-DIFF1 | PAIR | 6 | 5.5 | 5 | 10 | 5 | 50 | 6 | 20 | 12 | 12 | 12 | 12 | 7.5 | 85 Ohms | TOP=L2:L3=L2/L4:L6=L5/L7:BOTTOM=L7 |
| PCIE_TX_CAP_P35 | TXC35-DIFF1 | PAIR | 7 | 5.5 | 5 | 10 | 5 | 50 | 6 | 20 | 12 | 12 | 12 | 12 | 7.5 | 85 Ohms | TOP=L2:L3=L2/L4:L6=L5/L7:BOTTOM=L7 |
| PCIE_TX_CAP_P35 | TXC35-DIFF1 | PAIR | 8 | 5.38 | 5 | 10 | 5 | 50 | 6 | 33 | 12 | 12 | 12 | 12 | 6.62 | 85 Ohms | TOP=L2:L3=L2/L4:L6=L5/L7:BOTTOM=L7 |
| PCIE_TX_CAP_N36 | TXC36-DIFF1 | PAIR | 1 | 5.38 | 5 | 10 | 5 | 50 | 6 | 33 | 12 | 12 | 12 | 12 | 6.62 | 85 Ohms | TOP=L2:L3=L2/L4:L6=L5/L7:BOTTOM=L7 |
| PCIE_TX_CAP_N36 | TXC36-DIFF1 | PAIR | 2 | 5.5 | 5 | 10 | 5 | 50 | 6 | 20 | 12 | 12 | 12 | 12 | 7.5 | 85 Ohms | TOP=L2:L3=L2/L4:L6=L5/L7:BOTTOM=L7 |
| PCIE_TX_CAP_N36 | TXC36-DIFF1 | PAIR | 3 | 5.5 | 5 | 10 | 5 | 50 | 6 | 20 | 12 | 12 | 12 | 12 | 7.5 | 85 Ohms | TOP=L2:L3=L2/L4:L6=L5/L7:BOTTOM=L7 |
| PCIE_TX_CAP_N36 | TXC36-DIFF1 | PAIR | 4 | 5.5 | 5 | 10 | 5 | 50 | 6 | 20 | 12 | 12 | 12 | 12 | 7.5 | 85 Ohms | TOP=L2:L3=L2/L4:L6=L5/L7:BOTTOM=L7 |
| PCIE_TX_CAP_N36 | TXC36-DIFF1 | PAIR | 5 | 5.5 | 5 | 10 | 5 | 50 | 6 | 20 | 12 | 12 | 12 | 12 | 7.5 | 85 Ohms | TOP=L2:L3=L2/L4:L6=L5/L7:BOTTOM=L7 |
| PCIE_TX_CAP_N36 | TXC36-DIFF1 | PAIR | 6 | 5.5 | 5 | 10 | 5 | 50 | 6 | 20 | 12 | 12 | 12 | 12 | 7.5 | 85 Ohms | TOP=L2:L3=L2/L4:L6=L5/L7:BOTTOM=L7 |
| PCIE_TX_CAP_N36 | TXC36-DIFF1 | PAIR | 7 | 5.5 | 5 | 10 | 5 | 50 | 6 | 20 | 12 | 12 | 12 | 12 | 7.5 | 85 Ohms | TOP=L2:L3=L2/L4:L6=L5/L7:BOTTOM=L7 |
| PCIE_TX_CAP_N36 | TXC36-DIFF1 | PAIR | 8 | 5.38 | 5 | 10 | 5 | 50 | 6 | 33 | 12 | 12 | 12 | 12 | 6.62 | 85 Ohms | TOP=L2:L3=L2/L4:L6=L5/L7:BOTTOM=L7 |
| PCIE_TX_CAP_P36 | TXC36-DIFF1 | PAIR | 1 | 5.38 | 5 | 10 | 5 | 50 | 6 | 33 | 12 | 12 | 12 | 12 | 6.62 | 85 Ohms | TOP=L2:L3=L2/L4:L6=L5/L7:BOTTOM=L7 |
| PCIE_TX_CAP_P36 | TXC36-DIFF1 | PAIR | 2 | 5.5 | 5 | 10 | 5 | 50 | 6 | 20 | 12 | 12 | 12 | 12 | 7.5 | 85 Ohms | TOP=L2:L3=L2/L4:L6=L5/L7:BOTTOM=L7 |
| PCIE_TX_CAP_P36 | TXC36-DIFF1 | PAIR | 3 | 5.5 | 5 | 10 | 5 | 50 | 6 | 20 | 12 | 12 | 12 | 12 | 7.5 | 85 Ohms | TOP=L2:L3=L2/L4:L6=L5/L7:BOTTOM=L7 |
| PCIE_TX_CAP_P36 | TXC36-DIFF1 | PAIR | 4 | 5.5 | 5 | 10 | 5 | 50 | 6 | 20 | 12 | 12 | 12 | 12 | 7.5 | 85 Ohms | TOP=L2:L3=L2/L4:L6=L5/L7:BOTTOM=L7 |
| PCIE_TX_CAP_P36 | TXC36-DIFF1 | PAIR | 5 | 5.5 | 5 | 10 | 5 | 50 | 6 | 20 | 12 | 12 | 12 | 12 | 7.5 | 85 Ohms | TOP=L2:L3=L2/L4:L6=L5/L7:BOTTOM=L7 |
| PCIE_TX_CAP_P36 | TXC36-DIFF1 | PAIR | 6 | 5.5 | 5 | 10 | 5 | 50 | 6 | 20 | 12 | 12 | 12 | 12 | 7.5 | 85 Ohms | TOP=L2:L3=L2/L4:L6=L5/L7:BOTTOM=L7 |
| PCIE_TX_CAP_P36 | TXC36-DIFF1 | PAIR | 7 | 5.5 | 5 | 10 | 5 | 50 | 6 | 20 | 12 | 12 | 12 | 12 | 7.5 | 85 Ohms | TOP=L2:L3=L2/L4:L6=L5/L7:BOTTOM=L7 |
| PCIE_TX_CAP_P36 | TXC36-DIFF1 | PAIR | 8 | 5.38 | 5 | 10 | 5 | 50 | 6 | 33 | 12 | 12 | 12 | 12 | 6.62 | 85 Ohms | TOP=L2:L3=L2/L4:L6=L5/L7:BOTTOM=L7 |
| PCIE_TX_CAP_N37 | TXC37-DIFF1 | PAIR | 1 | 5.38 | 5 | 10 | 5 | 50 | 6 | 33 | 12 | 12 | 12 | 12 | 6.62 | 85 Ohms | TOP=L2:L3=L2/L4:L6=L5/L7:BOTTOM=L7 |
| PCIE_TX_CAP_N37 | TXC37-DIFF1 | PAIR | 2 | 5.5 | 5 | 10 | 5 | 50 | 6 | 20 | 12 | 12 | 12 | 12 | 7.5 | 85 Ohms | TOP=L2:L3=L2/L4:L6=L5/L7:BOTTOM=L7 |
| PCIE_TX_CAP_N37 | TXC37-DIFF1 | PAIR | 3 | 5.5 | 5 | 10 | 5 | 50 | 6 | 20 | 12 | 12 | 12 | 12 | 7.5 | 85 Ohms | TOP=L2:L3=L2/L4:L6=L5/L7:BOTTOM=L7 |
| PCIE_TX_CAP_N37 | TXC37-DIFF1 | PAIR | 4 | 5.5 | 5 | 10 | 5 | 50 | 6 | 20 | 12 | 12 | 12 | 12 | 7.5 | 85 Ohms | TOP=L2:L3=L2/L4:L6=L5/L7:BOTTOM=L7 |
| PCIE_TX_CAP_N37 | TXC37-DIFF1 | PAIR | 5 | 5.5 | 5 | 10 | 5 | 50 | 6 | 20 | 12 | 12 | 12 | 12 | 7.5 | 85 Ohms | TOP=L2:L3=L2/L4:L6=L5/L7:BOTTOM=L7 |
| PCIE_TX_CAP_N37 | TXC37-DIFF1 | PAIR | 6 | 5.5 | 5 | 10 | 5 | 50 | 6 | 20 | 12 | 12 | 12 | 12 | 7.5 | 85 Ohms | TOP=L2:L3=L2/L4:L6=L5/L7:BOTTOM=L7 |
| PCIE_TX_CAP_N37 | TXC37-DIFF1 | PAIR | 7 | 5.5 | 5 | 10 | 5 | 50 | 6 | 20 | 12 | 12 | 12 | 12 | 7.5 | 85 Ohms | TOP=L2:L3=L2/L4:L6=L5/L7:BOTTOM=L7 |
| PCIE_TX_CAP_N37 | TXC37-DIFF1 | PAIR | 8 | 5.38 | 5 | 10 | 5 | 50 | 6 | 33 | 12 | 12 | 12 | 12 | 6.62 | 85 Ohms | TOP=L2:L3=L2/L4:L6=L5/L7:BOTTOM=L7 |
| PCIE_TX_CAP_P37 | TXC37-DIFF1 | PAIR | 1 | 5.38 | 5 | 10 | 5 | 50 | 6 | 33 | 12 | 12 | 12 | 12 | 6.62 | 85 Ohms | TOP=L2:L3=L2/L4:L6=L5/L7:BOTTOM=L7 |
| PCIE_TX_CAP_P37 | TXC37-DIFF1 | PAIR | 2 | 5.5 | 5 | 10 | 5 | 50 | 6 | 20 | 12 | 12 | 12 | 12 | 7.5 | 85 Ohms | TOP=L2:L3=L2/L4:L6=L5/L7:BOTTOM=L7 |
| PCIE_TX_CAP_P37 | TXC37-DIFF1 | PAIR | 3 | 5.5 | 5 | 10 | 5 | 50 | 6 | 20 | 12 | 12 | 12 | 12 | 7.5 | 85 Ohms | TOP=L2:L3=L2/L4:L6=L5/L7:BOTTOM=L7 |
| PCIE_TX_CAP_P37 | TXC37-DIFF1 | PAIR | 4 | 5.5 | 5 | 10 | 5 | 50 | 6 | 20 | 12 | 12 | 12 | 12 | 7.5 | 85 Ohms | TOP=L2:L3=L2/L4:L6=L5/L7:BOTTOM=L7 |
| PCIE_TX_CAP_P37 | TXC37-DIFF1 | PAIR | 5 | 5.5 | 5 | 10 | 5 | 50 | 6 | 20 | 12 | 12 | 12 | 12 | 7.5 | 85 Ohms | TOP=L2:L3=L2/L4:L6=L5/L7:BOTTOM=L7 |
| PCIE_TX_CAP_P37 | TXC37-DIFF1 | PAIR | 6 | 5.5 | 5 | 10 | 5 | 50 | 6 | 20 | 12 | 12 | 12 | 12 | 7.5 | 85 Ohms | TOP=L2:L3=L2/L4:L6=L5/L7:BOTTOM=L7 |
| PCIE_TX_CAP_P37 | TXC37-DIFF1 | PAIR | 7 | 5.5 | 5 | 10 | 5 | 50 | 6 | 20 | 12 | 12 | 12 | 12 | 7.5 | 85 Ohms | TOP=L2:L3=L2/L4:L6=L5/L7:BOTTOM=L7 |
| PCIE_TX_CAP_P37 | TXC37-DIFF1 | PAIR | 8 | 5.38 | 5 | 10 | 5 | 50 | 6 | 33 | 12 | 12 | 12 | 12 | 6.62 | 85 Ohms | TOP=L2:L3=L2/L4:L6=L5/L7:BOTTOM=L7 |
| PCIE_TX_CAP_N38 | TXC38-DIFF1 | PAIR | 1 | 5.38 | 5 | 10 | 5 | 50 | 6 | 33 | 12 | 12 | 12 | 12 | 6.62 | 85 Ohms | TOP=L2:L3=L2/L4:L6=L5/L7:BOTTOM=L7 |
| PCIE_TX_CAP_N38 | TXC38-DIFF1 | PAIR | 2 | 5.5 | 5 | 10 | 5 | 50 | 6 | 20 | 12 | 12 | 12 | 12 | 7.5 | 85 Ohms | TOP=L2:L3=L2/L4:L6=L5/L7:BOTTOM=L7 |
| PCIE_TX_CAP_N38 | TXC38-DIFF1 | PAIR | 3 | 5.5 | 5 | 10 | 5 | 50 | 6 | 20 | 12 | 12 | 12 | 12 | 7.5 | 85 Ohms | TOP=L2:L3=L2/L4:L6=L5/L7:BOTTOM=L7 |
| PCIE_TX_CAP_N38 | TXC38-DIFF1 | PAIR | 4 | 5.5 | 5 | 10 | 5 | 50 | 6 | 20 | 12 | 12 | 12 | 12 | 7.5 | 85 Ohms | TOP=L2:L3=L2/L4:L6=L5/L7:BOTTOM=L7 |
| PCIE_TX_CAP_N38 | TXC38-DIFF1 | PAIR | 5 | 5.5 | 5 | 10 | 5 | 50 | 6 | 20 | 12 | 12 | 12 | 12 | 7.5 | 85 Ohms | TOP=L2:L3=L2/L4:L6=L5/L7:BOTTOM=L7 |
| PCIE_TX_CAP_N38 | TXC38-DIFF1 | PAIR | 6 | 5.5 | 5 | 10 | 5 | 50 | 6 | 20 | 12 | 12 | 12 | 12 | 7.5 | 85 Ohms | TOP=L2:L3=L2/L4:L6=L5/L7:BOTTOM=L7 |
| PCIE_TX_CAP_N38 | TXC38-DIFF1 | PAIR | 7 | 5.5 | 5 | 10 | 5 | 50 | 6 | 20 | 12 | 12 | 12 | 12 | 7.5 | 85 Ohms | TOP=L2:L3=L2/L4:L6=L5/L7:BOTTOM=L7 |
| PCIE_TX_CAP_N38 | TXC38-DIFF1 | PAIR | 8 | 5.38 | 5 | 10 | 5 | 50 | 6 | 33 | 12 | 12 | 12 | 12 | 6.62 | 85 Ohms | TOP=L2:L3=L2/L4:L6=L5/L7:BOTTOM=L7 |
| PCIE_TX_CAP_P38 | TXC38-DIFF1 | PAIR | 1 | 5.38 | 5 | 10 | 5 | 50 | 6 | 33 | 12 | 12 | 12 | 12 | 6.62 | 85 Ohms | TOP=L2:L3=L2/L4:L6=L5/L7:BOTTOM=L7 |
| PCIE_TX_CAP_P38 | TXC38-DIFF1 | PAIR | 2 | 5.5 | 5 | 10 | 5 | 50 | 6 | 20 | 12 | 12 | 12 | 12 | 7.5 | 85 Ohms | TOP=L2:L3=L2/L4:L6=L5/L7:BOTTOM=L7 |
| PCIE_TX_CAP_P38 | TXC38-DIFF1 | PAIR | 3 | 5.5 | 5 | 10 | 5 | 50 | 6 | 20 | 12 | 12 | 12 | 12 | 7.5 | 85 Ohms | TOP=L2:L3=L2/L4:L6=L5/L7:BOTTOM=L7 |
| PCIE_TX_CAP_P38 | TXC38-DIFF1 | PAIR | 4 | 5.5 | 5 | 10 | 5 | 50 | 6 | 20 | 12 | 12 | 12 | 12 | 7.5 | 85 Ohms | TOP=L2:L3=L2/L4:L6=L5/L7:BOTTOM=L7 |
| PCIE_TX_CAP_P38 | TXC38-DIFF1 | PAIR | 5 | 5.5 | 5 | 10 | 5 | 50 | 6 | 20 | 12 | 12 | 12 | 12 | 7.5 | 85 Ohms | TOP=L2:L3=L2/L4:L6=L5/L7:BOTTOM=L7 |
| PCIE_TX_CAP_P38 | TXC38-DIFF1 | PAIR | 6 | 5.5 | 5 | 10 | 5 | 50 | 6 | 20 | 12 | 12 | 12 | 12 | 7.5 | 85 Ohms | TOP=L2:L3=L2/L4:L6=L5/L7:BOTTOM=L7 |
| PCIE_TX_CAP_P38 | TXC38-DIFF1 | PAIR | 7 | 5.5 | 5 | 10 | 5 | 50 | 6 | 20 | 12 | 12 | 12 | 12 | 7.5 | 85 Ohms | TOP=L2:L3=L2/L4:L6=L5/L7:BOTTOM=L7 |
| PCIE_TX_CAP_P38 | TXC38-DIFF1 | PAIR | 8 | 5.38 | 5 | 10 | 5 | 50 | 6 | 33 | 12 | 12 | 12 | 12 | 6.62 | 85 Ohms | TOP=L2:L3=L2/L4:L6=L5/L7:BOTTOM=L7 |
| PCIE_TX_CAP_N39 | TXC39-DIFF1 | PAIR | 1 | 5.38 | 5 | 10 | 5 | 50 | 6 | 33 | 12 | 12 | 12 | 12 | 6.62 | 85 Ohms | TOP=L2:L3=L2/L4:L6=L5/L7:BOTTOM=L7 |
| PCIE_TX_CAP_N39 | TXC39-DIFF1 | PAIR | 2 | 5.5 | 5 | 10 | 5 | 50 | 6 | 20 | 12 | 12 | 12 | 12 | 7.5 | 85 Ohms | TOP=L2:L3=L2/L4:L6=L5/L7:BOTTOM=L7 |
| PCIE_TX_CAP_N39 | TXC39-DIFF1 | PAIR | 3 | 5.5 | 5 | 10 | 5 | 50 | 6 | 20 | 12 | 12 | 12 | 12 | 7.5 | 85 Ohms | TOP=L2:L3=L2/L4:L6=L5/L7:BOTTOM=L7 |
| PCIE_TX_CAP_N39 | TXC39-DIFF1 | PAIR | 4 | 5.5 | 5 | 10 | 5 | 50 | 6 | 20 | 12 | 12 | 12 | 12 | 7.5 | 85 Ohms | TOP=L2:L3=L2/L4:L6=L5/L7:BOTTOM=L7 |
| PCIE_TX_CAP_N39 | TXC39-DIFF1 | PAIR | 5 | 5.5 | 5 | 10 | 5 | 50 | 6 | 20 | 12 | 12 | 12 | 12 | 7.5 | 85 Ohms | TOP=L2:L3=L2/L4:L6=L5/L7:BOTTOM=L7 |
| PCIE_TX_CAP_N39 | TXC39-DIFF1 | PAIR | 6 | 5.5 | 5 | 10 | 5 | 50 | 6 | 20 | 12 | 12 | 12 | 12 | 7.5 | 85 Ohms | TOP=L2:L3=L2/L4:L6=L5/L7:BOTTOM=L7 |
| PCIE_TX_CAP_N39 | TXC39-DIFF1 | PAIR | 7 | 5.5 | 5 | 10 | 5 | 50 | 6 | 20 | 12 | 12 | 12 | 12 | 7.5 | 85 Ohms | TOP=L2:L3=L2/L4:L6=L5/L7:BOTTOM=L7 |
| PCIE_TX_CAP_N39 | TXC39-DIFF1 | PAIR | 8 | 5.38 | 5 | 10 | 5 | 50 | 6 | 33 | 12 | 12 | 12 | 12 | 6.62 | 85 Ohms | TOP=L2:L3=L2/L4:L6=L5/L7:BOTTOM=L7 |
| PCIE_TX_CAP_P39 | TXC39-DIFF1 | PAIR | 1 | 5.38 | 5 | 10 | 5 | 50 | 6 | 33 | 12 | 12 | 12 | 12 | 6.62 | 85 Ohms | TOP=L2:L3=L2/L4:L6=L5/L7:BOTTOM=L7 |
| PCIE_TX_CAP_P39 | TXC39-DIFF1 | PAIR | 2 | 5.5 | 5 | 10 | 5 | 50 | 6 | 20 | 12 | 12 | 12 | 12 | 7.5 | 85 Ohms | TOP=L2:L3=L2/L4:L6=L5/L7:BOTTOM=L7 |
| PCIE_TX_CAP_P39 | TXC39-DIFF1 | PAIR | 3 | 5.5 | 5 | 10 | 5 | 50 | 6 | 20 | 12 | 12 | 12 | 12 | 7.5 | 85 Ohms | TOP=L2:L3=L2/L4:L6=L5/L7:BOTTOM=L7 |
| PCIE_TX_CAP_P39 | TXC39-DIFF1 | PAIR | 4 | 5.5 | 5 | 10 | 5 | 50 | 6 | 20 | 12 | 12 | 12 | 12 | 7.5 | 85 Ohms | TOP=L2:L3=L2/L4:L6=L5/L7:BOTTOM=L7 |
| PCIE_TX_CAP_P39 | TXC39-DIFF1 | PAIR | 5 | 5.5 | 5 | 10 | 5 | 50 | 6 | 20 | 12 | 12 | 12 | 12 | 7.5 | 85 Ohms | TOP=L2:L3=L2/L4:L6=L5/L7:BOTTOM=L7 |
| PCIE_TX_CAP_P39 | TXC39-DIFF1 | PAIR | 6 | 5.5 | 5 | 10 | 5 | 50 | 6 | 20 | 12 | 12 | 12 | 12 | 7.5 | 85 Ohms | TOP=L2:L3=L2/L4:L6=L5/L7:BOTTOM=L7 |
| PCIE_TX_CAP_P39 | TXC39-DIFF1 | PAIR | 7 | 5.5 | 5 | 10 | 5 | 50 | 6 | 20 | 12 | 12 | 12 | 12 | 7.5 | 85 Ohms | TOP=L2:L3=L2/L4:L6=L5/L7:BOTTOM=L7 |
| PCIE_TX_CAP_P39 | TXC39-DIFF1 | PAIR | 8 | 5.38 | 5 | 10 | 5 | 50 | 6 | 33 | 12 | 12 | 12 | 12 | 6.62 | 85 Ohms | TOP=L2:L3=L2/L4:L6=L5/L7:BOTTOM=L7 |
| PCIE_TX_CAP_N3 | TXC3-DIFF1 | PAIR | 1 | 5.38 | 5 | 10 | 5 | 50 | 6 | 33 | 12 | 12 | 12 | 12 | 6.62 | 85 Ohms | TOP=L2:L3=L2/L4:L6=L5/L7:BOTTOM=L7 |
| PCIE_TX_CAP_N3 | TXC3-DIFF1 | PAIR | 2 | 5.5 | 5 | 10 | 5 | 50 | 6 | 20 | 12 | 12 | 12 | 12 | 7.5 | 85 Ohms | TOP=L2:L3=L2/L4:L6=L5/L7:BOTTOM=L7 |
| PCIE_TX_CAP_N3 | TXC3-DIFF1 | PAIR | 3 | 5.5 | 5 | 10 | 5 | 50 | 6 | 20 | 12 | 12 | 12 | 12 | 7.5 | 85 Ohms | TOP=L2:L3=L2/L4:L6=L5/L7:BOTTOM=L7 |
| PCIE_TX_CAP_N3 | TXC3-DIFF1 | PAIR | 4 | 5.5 | 5 | 10 | 5 | 50 | 6 | 20 | 12 | 12 | 12 | 12 | 7.5 | 85 Ohms | TOP=L2:L3=L2/L4:L6=L5/L7:BOTTOM=L7 |
| PCIE_TX_CAP_N3 | TXC3-DIFF1 | PAIR | 5 | 5.5 | 5 | 10 | 5 | 50 | 6 | 20 | 12 | 12 | 12 | 12 | 7.5 | 85 Ohms | TOP=L2:L3=L2/L4:L6=L5/L7:BOTTOM=L7 |
| PCIE_TX_CAP_N3 | TXC3-DIFF1 | PAIR | 6 | 5.5 | 5 | 10 | 5 | 50 | 6 | 20 | 12 | 12 | 12 | 12 | 7.5 | 85 Ohms | TOP=L2:L3=L2/L4:L6=L5/L7:BOTTOM=L7 |
| PCIE_TX_CAP_N3 | TXC3-DIFF1 | PAIR | 7 | 5.5 | 5 | 10 | 5 | 50 | 6 | 20 | 12 | 12 | 12 | 12 | 7.5 | 85 Ohms | TOP=L2:L3=L2/L4:L6=L5/L7:BOTTOM=L7 |
| PCIE_TX_CAP_N3 | TXC3-DIFF1 | PAIR | 8 | 5.38 | 5 | 10 | 5 | 50 | 6 | 33 | 12 | 12 | 12 | 12 | 6.62 | 85 Ohms | TOP=L2:L3=L2/L4:L6=L5/L7:BOTTOM=L7 |
| PCIE_TX_CAP_P3 | TXC3-DIFF1 | PAIR | 1 | 5.38 | 5 | 10 | 5 | 50 | 6 | 33 | 12 | 12 | 12 | 12 | 6.62 | 85 Ohms | TOP=L2:L3=L2/L4:L6=L5/L7:BOTTOM=L7 |
| PCIE_TX_CAP_P3 | TXC3-DIFF1 | PAIR | 2 | 5.5 | 5 | 10 | 5 | 50 | 6 | 20 | 12 | 12 | 12 | 12 | 7.5 | 85 Ohms | TOP=L2:L3=L2/L4:L6=L5/L7:BOTTOM=L7 |
| PCIE_TX_CAP_P3 | TXC3-DIFF1 | PAIR | 3 | 5.5 | 5 | 10 | 5 | 50 | 6 | 20 | 12 | 12 | 12 | 12 | 7.5 | 85 Ohms | TOP=L2:L3=L2/L4:L6=L5/L7:BOTTOM=L7 |
| PCIE_TX_CAP_P3 | TXC3-DIFF1 | PAIR | 4 | 5.5 | 5 | 10 | 5 | 50 | 6 | 20 | 12 | 12 | 12 | 12 | 7.5 | 85 Ohms | TOP=L2:L3=L2/L4:L6=L5/L7:BOTTOM=L7 |
| PCIE_TX_CAP_P3 | TXC3-DIFF1 | PAIR | 5 | 5.5 | 5 | 10 | 5 | 50 | 6 | 20 | 12 | 12 | 12 | 12 | 7.5 | 85 Ohms | TOP=L2:L3=L2/L4:L6=L5/L7:BOTTOM=L7 |
| PCIE_TX_CAP_P3 | TXC3-DIFF1 | PAIR | 6 | 5.5 | 5 | 10 | 5 | 50 | 6 | 20 | 12 | 12 | 12 | 12 | 7.5 | 85 Ohms | TOP=L2:L3=L2/L4:L6=L5/L7:BOTTOM=L7 |
| PCIE_TX_CAP_P3 | TXC3-DIFF1 | PAIR | 7 | 5.5 | 5 | 10 | 5 | 50 | 6 | 20 | 12 | 12 | 12 | 12 | 7.5 | 85 Ohms | TOP=L2:L3=L2/L4:L6=L5/L7:BOTTOM=L7 |
| PCIE_TX_CAP_P3 | TXC3-DIFF1 | PAIR | 8 | 5.38 | 5 | 10 | 5 | 50 | 6 | 33 | 12 | 12 | 12 | 12 | 6.62 | 85 Ohms | TOP=L2:L3=L2/L4:L6=L5/L7:BOTTOM=L7 |
| PCIE_TX_CAP_N40 | TXC40-DIFF1 | PAIR | 1 | 5.38 | 5 | 10 | 5 | 50 | 6 | 33 | 12 | 12 | 12 | 12 | 6.62 | 85 Ohms | TOP=L2:L3=L2/L4:L6=L5/L7:BOTTOM=L7 |
| PCIE_TX_CAP_N40 | TXC40-DIFF1 | PAIR | 2 | 5.5 | 5 | 10 | 5 | 50 | 6 | 20 | 12 | 12 | 12 | 12 | 7.5 | 85 Ohms | TOP=L2:L3=L2/L4:L6=L5/L7:BOTTOM=L7 |
| PCIE_TX_CAP_N40 | TXC40-DIFF1 | PAIR | 3 | 5.5 | 5 | 10 | 5 | 50 | 6 | 20 | 12 | 12 | 12 | 12 | 7.5 | 85 Ohms | TOP=L2:L3=L2/L4:L6=L5/L7:BOTTOM=L7 |
| PCIE_TX_CAP_N40 | TXC40-DIFF1 | PAIR | 4 | 5.5 | 5 | 10 | 5 | 50 | 6 | 20 | 12 | 12 | 12 | 12 | 7.5 | 85 Ohms | TOP=L2:L3=L2/L4:L6=L5/L7:BOTTOM=L7 |
| PCIE_TX_CAP_N40 | TXC40-DIFF1 | PAIR | 5 | 5.5 | 5 | 10 | 5 | 50 | 6 | 20 | 12 | 12 | 12 | 12 | 7.5 | 85 Ohms | TOP=L2:L3=L2/L4:L6=L5/L7:BOTTOM=L7 |
| PCIE_TX_CAP_N40 | TXC40-DIFF1 | PAIR | 6 | 5.5 | 5 | 10 | 5 | 50 | 6 | 20 | 12 | 12 | 12 | 12 | 7.5 | 85 Ohms | TOP=L2:L3=L2/L4:L6=L5/L7:BOTTOM=L7 |
| PCIE_TX_CAP_N40 | TXC40-DIFF1 | PAIR | 7 | 5.5 | 5 | 10 | 5 | 50 | 6 | 20 | 12 | 12 | 12 | 12 | 7.5 | 85 Ohms | TOP=L2:L3=L2/L4:L6=L5/L7:BOTTOM=L7 |
| PCIE_TX_CAP_N40 | TXC40-DIFF1 | PAIR | 8 | 5.38 | 5 | 10 | 5 | 50 | 6 | 33 | 12 | 12 | 12 | 12 | 6.62 | 85 Ohms | TOP=L2:L3=L2/L4:L6=L5/L7:BOTTOM=L7 |
| PCIE_TX_CAP_P40 | TXC40-DIFF1 | PAIR | 1 | 5.38 | 5 | 10 | 5 | 50 | 6 | 33 | 12 | 12 | 12 | 12 | 6.62 | 85 Ohms | TOP=L2:L3=L2/L4:L6=L5/L7:BOTTOM=L7 |
| PCIE_TX_CAP_P40 | TXC40-DIFF1 | PAIR | 2 | 5.5 | 5 | 10 | 5 | 50 | 6 | 20 | 12 | 12 | 12 | 12 | 7.5 | 85 Ohms | TOP=L2:L3=L2/L4:L6=L5/L7:BOTTOM=L7 |
| PCIE_TX_CAP_P40 | TXC40-DIFF1 | PAIR | 3 | 5.5 | 5 | 10 | 5 | 50 | 6 | 20 | 12 | 12 | 12 | 12 | 7.5 | 85 Ohms | TOP=L2:L3=L2/L4:L6=L5/L7:BOTTOM=L7 |
| PCIE_TX_CAP_P40 | TXC40-DIFF1 | PAIR | 4 | 5.5 | 5 | 10 | 5 | 50 | 6 | 20 | 12 | 12 | 12 | 12 | 7.5 | 85 Ohms | TOP=L2:L3=L2/L4:L6=L5/L7:BOTTOM=L7 |
| PCIE_TX_CAP_P40 | TXC40-DIFF1 | PAIR | 5 | 5.5 | 5 | 10 | 5 | 50 | 6 | 20 | 12 | 12 | 12 | 12 | 7.5 | 85 Ohms | TOP=L2:L3=L2/L4:L6=L5/L7:BOTTOM=L7 |
| PCIE_TX_CAP_P40 | TXC40-DIFF1 | PAIR | 6 | 5.5 | 5 | 10 | 5 | 50 | 6 | 20 | 12 | 12 | 12 | 12 | 7.5 | 85 Ohms | TOP=L2:L3=L2/L4:L6=L5/L7:BOTTOM=L7 |
| PCIE_TX_CAP_P40 | TXC40-DIFF1 | PAIR | 7 | 5.5 | 5 | 10 | 5 | 50 | 6 | 20 | 12 | 12 | 12 | 12 | 7.5 | 85 Ohms | TOP=L2:L3=L2/L4:L6=L5/L7:BOTTOM=L7 |
| PCIE_TX_CAP_P40 | TXC40-DIFF1 | PAIR | 8 | 5.38 | 5 | 10 | 5 | 50 | 6 | 33 | 12 | 12 | 12 | 12 | 6.62 | 85 Ohms | TOP=L2:L3=L2/L4:L6=L5/L7:BOTTOM=L7 |
| PCIE_TX_CAP_N41 | TXC41-DIFF1 | PAIR | 1 | 5.38 | 5 | 10 | 5 | 50 | 6 | 33 | 12 | 12 | 12 | 12 | 6.62 | 85 Ohms | TOP=L2:L3=L2/L4:L6=L5/L7:BOTTOM=L7 |
| PCIE_TX_CAP_N41 | TXC41-DIFF1 | PAIR | 2 | 5.5 | 5 | 10 | 5 | 50 | 6 | 20 | 12 | 12 | 12 | 12 | 7.5 | 85 Ohms | TOP=L2:L3=L2/L4:L6=L5/L7:BOTTOM=L7 |
| PCIE_TX_CAP_N41 | TXC41-DIFF1 | PAIR | 3 | 5.5 | 5 | 10 | 5 | 50 | 6 | 20 | 12 | 12 | 12 | 12 | 7.5 | 85 Ohms | TOP=L2:L3=L2/L4:L6=L5/L7:BOTTOM=L7 |
| PCIE_TX_CAP_N41 | TXC41-DIFF1 | PAIR | 4 | 5.5 | 5 | 10 | 5 | 50 | 6 | 20 | 12 | 12 | 12 | 12 | 7.5 | 85 Ohms | TOP=L2:L3=L2/L4:L6=L5/L7:BOTTOM=L7 |
| PCIE_TX_CAP_N41 | TXC41-DIFF1 | PAIR | 5 | 5.5 | 5 | 10 | 5 | 50 | 6 | 20 | 12 | 12 | 12 | 12 | 7.5 | 85 Ohms | TOP=L2:L3=L2/L4:L6=L5/L7:BOTTOM=L7 |
| PCIE_TX_CAP_N41 | TXC41-DIFF1 | PAIR | 6 | 5.5 | 5 | 10 | 5 | 50 | 6 | 20 | 12 | 12 | 12 | 12 | 7.5 | 85 Ohms | TOP=L2:L3=L2/L4:L6=L5/L7:BOTTOM=L7 |
| PCIE_TX_CAP_N41 | TXC41-DIFF1 | PAIR | 7 | 5.5 | 5 | 10 | 5 | 50 | 6 | 20 | 12 | 12 | 12 | 12 | 7.5 | 85 Ohms | TOP=L2:L3=L2/L4:L6=L5/L7:BOTTOM=L7 |
| PCIE_TX_CAP_N41 | TXC41-DIFF1 | PAIR | 8 | 5.38 | 5 | 10 | 5 | 50 | 6 | 33 | 12 | 12 | 12 | 12 | 6.62 | 85 Ohms | TOP=L2:L3=L2/L4:L6=L5/L7:BOTTOM=L7 |
| PCIE_TX_CAP_P41 | TXC41-DIFF1 | PAIR | 1 | 5.38 | 5 | 10 | 5 | 50 | 6 | 33 | 12 | 12 | 12 | 12 | 6.62 | 85 Ohms | TOP=L2:L3=L2/L4:L6=L5/L7:BOTTOM=L7 |
| PCIE_TX_CAP_P41 | TXC41-DIFF1 | PAIR | 2 | 5.5 | 5 | 10 | 5 | 50 | 6 | 20 | 12 | 12 | 12 | 12 | 7.5 | 85 Ohms | TOP=L2:L3=L2/L4:L6=L5/L7:BOTTOM=L7 |
| PCIE_TX_CAP_P41 | TXC41-DIFF1 | PAIR | 3 | 5.5 | 5 | 10 | 5 | 50 | 6 | 20 | 12 | 12 | 12 | 12 | 7.5 | 85 Ohms | TOP=L2:L3=L2/L4:L6=L5/L7:BOTTOM=L7 |
| PCIE_TX_CAP_P41 | TXC41-DIFF1 | PAIR | 4 | 5.5 | 5 | 10 | 5 | 50 | 6 | 20 | 12 | 12 | 12 | 12 | 7.5 | 85 Ohms | TOP=L2:L3=L2/L4:L6=L5/L7:BOTTOM=L7 |
| PCIE_TX_CAP_P41 | TXC41-DIFF1 | PAIR | 5 | 5.5 | 5 | 10 | 5 | 50 | 6 | 20 | 12 | 12 | 12 | 12 | 7.5 | 85 Ohms | TOP=L2:L3=L2/L4:L6=L5/L7:BOTTOM=L7 |
| PCIE_TX_CAP_P41 | TXC41-DIFF1 | PAIR | 6 | 5.5 | 5 | 10 | 5 | 50 | 6 | 20 | 12 | 12 | 12 | 12 | 7.5 | 85 Ohms | TOP=L2:L3=L2/L4:L6=L5/L7:BOTTOM=L7 |
| PCIE_TX_CAP_P41 | TXC41-DIFF1 | PAIR | 7 | 5.5 | 5 | 10 | 5 | 50 | 6 | 20 | 12 | 12 | 12 | 12 | 7.5 | 85 Ohms | TOP=L2:L3=L2/L4:L6=L5/L7:BOTTOM=L7 |
| PCIE_TX_CAP_P41 | TXC41-DIFF1 | PAIR | 8 | 5.38 | 5 | 10 | 5 | 50 | 6 | 33 | 12 | 12 | 12 | 12 | 6.62 | 85 Ohms | TOP=L2:L3=L2/L4:L6=L5/L7:BOTTOM=L7 |
| PCIE_TX_CAP_N42 | TXC42-DIFF1 | PAIR | 1 | 5.38 | 5 | 10 | 5 | 50 | 6 | 33 | 12 | 12 | 12 | 12 | 6.62 | 85 Ohms | TOP=L2:L3=L2/L4:L6=L5/L7:BOTTOM=L7 |
| PCIE_TX_CAP_N42 | TXC42-DIFF1 | PAIR | 2 | 5.5 | 5 | 10 | 5 | 50 | 6 | 20 | 12 | 12 | 12 | 12 | 7.5 | 85 Ohms | TOP=L2:L3=L2/L4:L6=L5/L7:BOTTOM=L7 |
| PCIE_TX_CAP_N42 | TXC42-DIFF1 | PAIR | 3 | 5.5 | 5 | 10 | 5 | 50 | 6 | 20 | 12 | 12 | 12 | 12 | 7.5 | 85 Ohms | TOP=L2:L3=L2/L4:L6=L5/L7:BOTTOM=L7 |
| PCIE_TX_CAP_N42 | TXC42-DIFF1 | PAIR | 4 | 5.5 | 5 | 10 | 5 | 50 | 6 | 20 | 12 | 12 | 12 | 12 | 7.5 | 85 Ohms | TOP=L2:L3=L2/L4:L6=L5/L7:BOTTOM=L7 |
| PCIE_TX_CAP_N42 | TXC42-DIFF1 | PAIR | 5 | 5.5 | 5 | 10 | 5 | 50 | 6 | 20 | 12 | 12 | 12 | 12 | 7.5 | 85 Ohms | TOP=L2:L3=L2/L4:L6=L5/L7:BOTTOM=L7 |
| PCIE_TX_CAP_N42 | TXC42-DIFF1 | PAIR | 6 | 5.5 | 5 | 10 | 5 | 50 | 6 | 20 | 12 | 12 | 12 | 12 | 7.5 | 85 Ohms | TOP=L2:L3=L2/L4:L6=L5/L7:BOTTOM=L7 |
| PCIE_TX_CAP_N42 | TXC42-DIFF1 | PAIR | 7 | 5.5 | 5 | 10 | 5 | 50 | 6 | 20 | 12 | 12 | 12 | 12 | 7.5 | 85 Ohms | TOP=L2:L3=L2/L4:L6=L5/L7:BOTTOM=L7 |
| PCIE_TX_CAP_N42 | TXC42-DIFF1 | PAIR | 8 | 5.38 | 5 | 10 | 5 | 50 | 6 | 33 | 12 | 12 | 12 | 12 | 6.62 | 85 Ohms | TOP=L2:L3=L2/L4:L6=L5/L7:BOTTOM=L7 |
| PCIE_TX_CAP_P42 | TXC42-DIFF1 | PAIR | 1 | 5.38 | 5 | 10 | 5 | 50 | 6 | 33 | 12 | 12 | 12 | 12 | 6.62 | 85 Ohms | TOP=L2:L3=L2/L4:L6=L5/L7:BOTTOM=L7 |
| PCIE_TX_CAP_P42 | TXC42-DIFF1 | PAIR | 2 | 5.5 | 5 | 10 | 5 | 50 | 6 | 20 | 12 | 12 | 12 | 12 | 7.5 | 85 Ohms | TOP=L2:L3=L2/L4:L6=L5/L7:BOTTOM=L7 |
| PCIE_TX_CAP_P42 | TXC42-DIFF1 | PAIR | 3 | 5.5 | 5 | 10 | 5 | 50 | 6 | 20 | 12 | 12 | 12 | 12 | 7.5 | 85 Ohms | TOP=L2:L3=L2/L4:L6=L5/L7:BOTTOM=L7 |
| PCIE_TX_CAP_P42 | TXC42-DIFF1 | PAIR | 4 | 5.5 | 5 | 10 | 5 | 50 | 6 | 20 | 12 | 12 | 12 | 12 | 7.5 | 85 Ohms | TOP=L2:L3=L2/L4:L6=L5/L7:BOTTOM=L7 |
| PCIE_TX_CAP_P42 | TXC42-DIFF1 | PAIR | 5 | 5.5 | 5 | 10 | 5 | 50 | 6 | 20 | 12 | 12 | 12 | 12 | 7.5 | 85 Ohms | TOP=L2:L3=L2/L4:L6=L5/L7:BOTTOM=L7 |
| PCIE_TX_CAP_P42 | TXC42-DIFF1 | PAIR | 6 | 5.5 | 5 | 10 | 5 | 50 | 6 | 20 | 12 | 12 | 12 | 12 | 7.5 | 85 Ohms | TOP=L2:L3=L2/L4:L6=L5/L7:BOTTOM=L7 |
| PCIE_TX_CAP_P42 | TXC42-DIFF1 | PAIR | 7 | 5.5 | 5 | 10 | 5 | 50 | 6 | 20 | 12 | 12 | 12 | 12 | 7.5 | 85 Ohms | TOP=L2:L3=L2/L4:L6=L5/L7:BOTTOM=L7 |
| PCIE_TX_CAP_P42 | TXC42-DIFF1 | PAIR | 8 | 5.38 | 5 | 10 | 5 | 50 | 6 | 33 | 12 | 12 | 12 | 12 | 6.62 | 85 Ohms | TOP=L2:L3=L2/L4:L6=L5/L7:BOTTOM=L7 |
| PCIE_TX_CAP_N43 | TXC43-DIFF1 | PAIR | 1 | 5.38 | 5 | 10 | 5 | 50 | 6 | 33 | 12 | 12 | 12 | 12 | 6.62 | 85 Ohms | TOP=L2:L3=L2/L4:L6=L5/L7:BOTTOM=L7 |
| PCIE_TX_CAP_N43 | TXC43-DIFF1 | PAIR | 2 | 5.5 | 5 | 10 | 5 | 50 | 6 | 20 | 12 | 12 | 12 | 12 | 7.5 | 85 Ohms | TOP=L2:L3=L2/L4:L6=L5/L7:BOTTOM=L7 |
| PCIE_TX_CAP_N43 | TXC43-DIFF1 | PAIR | 3 | 5.5 | 5 | 10 | 5 | 50 | 6 | 20 | 12 | 12 | 12 | 12 | 7.5 | 85 Ohms | TOP=L2:L3=L2/L4:L6=L5/L7:BOTTOM=L7 |
| PCIE_TX_CAP_N43 | TXC43-DIFF1 | PAIR | 4 | 5.5 | 5 | 10 | 5 | 50 | 6 | 20 | 12 | 12 | 12 | 12 | 7.5 | 85 Ohms | TOP=L2:L3=L2/L4:L6=L5/L7:BOTTOM=L7 |
| PCIE_TX_CAP_N43 | TXC43-DIFF1 | PAIR | 5 | 5.5 | 5 | 10 | 5 | 50 | 6 | 20 | 12 | 12 | 12 | 12 | 7.5 | 85 Ohms | TOP=L2:L3=L2/L4:L6=L5/L7:BOTTOM=L7 |
| PCIE_TX_CAP_N43 | TXC43-DIFF1 | PAIR | 6 | 5.5 | 5 | 10 | 5 | 50 | 6 | 20 | 12 | 12 | 12 | 12 | 7.5 | 85 Ohms | TOP=L2:L3=L2/L4:L6=L5/L7:BOTTOM=L7 |
| PCIE_TX_CAP_N43 | TXC43-DIFF1 | PAIR | 7 | 5.5 | 5 | 10 | 5 | 50 | 6 | 20 | 12 | 12 | 12 | 12 | 7.5 | 85 Ohms | TOP=L2:L3=L2/L4:L6=L5/L7:BOTTOM=L7 |
| PCIE_TX_CAP_N43 | TXC43-DIFF1 | PAIR | 8 | 5.38 | 5 | 10 | 5 | 50 | 6 | 33 | 12 | 12 | 12 | 12 | 6.62 | 85 Ohms | TOP=L2:L3=L2/L4:L6=L5/L7:BOTTOM=L7 |
| PCIE_TX_CAP_P43 | TXC43-DIFF1 | PAIR | 1 | 5.38 | 5 | 10 | 5 | 50 | 6 | 33 | 12 | 12 | 12 | 12 | 6.62 | 85 Ohms | TOP=L2:L3=L2/L4:L6=L5/L7:BOTTOM=L7 |
| PCIE_TX_CAP_P43 | TXC43-DIFF1 | PAIR | 2 | 5.5 | 5 | 10 | 5 | 50 | 6 | 20 | 12 | 12 | 12 | 12 | 7.5 | 85 Ohms | TOP=L2:L3=L2/L4:L6=L5/L7:BOTTOM=L7 |
| PCIE_TX_CAP_P43 | TXC43-DIFF1 | PAIR | 3 | 5.5 | 5 | 10 | 5 | 50 | 6 | 20 | 12 | 12 | 12 | 12 | 7.5 | 85 Ohms | TOP=L2:L3=L2/L4:L6=L5/L7:BOTTOM=L7 |
| PCIE_TX_CAP_P43 | TXC43-DIFF1 | PAIR | 4 | 5.5 | 5 | 10 | 5 | 50 | 6 | 20 | 12 | 12 | 12 | 12 | 7.5 | 85 Ohms | TOP=L2:L3=L2/L4:L6=L5/L7:BOTTOM=L7 |
| PCIE_TX_CAP_P43 | TXC43-DIFF1 | PAIR | 5 | 5.5 | 5 | 10 | 5 | 50 | 6 | 20 | 12 | 12 | 12 | 12 | 7.5 | 85 Ohms | TOP=L2:L3=L2/L4:L6=L5/L7:BOTTOM=L7 |
| PCIE_TX_CAP_P43 | TXC43-DIFF1 | PAIR | 6 | 5.5 | 5 | 10 | 5 | 50 | 6 | 20 | 12 | 12 | 12 | 12 | 7.5 | 85 Ohms | TOP=L2:L3=L2/L4:L6=L5/L7:BOTTOM=L7 |
| PCIE_TX_CAP_P43 | TXC43-DIFF1 | PAIR | 7 | 5.5 | 5 | 10 | 5 | 50 | 6 | 20 | 12 | 12 | 12 | 12 | 7.5 | 85 Ohms | TOP=L2:L3=L2/L4:L6=L5/L7:BOTTOM=L7 |
| PCIE_TX_CAP_P43 | TXC43-DIFF1 | PAIR | 8 | 5.38 | 5 | 10 | 5 | 50 | 6 | 33 | 12 | 12 | 12 | 12 | 6.62 | 85 Ohms | TOP=L2:L3=L2/L4:L6=L5/L7:BOTTOM=L7 |
| PCIE_TX_CAP_N44 | TXC44-DIFF1 | PAIR | 1 | 5.38 | 5 | 10 | 5 | 50 | 6 | 33 | 12 | 12 | 12 | 12 | 6.62 | 85 Ohms | TOP=L2:L3=L2/L4:L6=L5/L7:BOTTOM=L7 |
| PCIE_TX_CAP_N44 | TXC44-DIFF1 | PAIR | 2 | 5.5 | 5 | 10 | 5 | 50 | 6 | 20 | 12 | 12 | 12 | 12 | 7.5 | 85 Ohms | TOP=L2:L3=L2/L4:L6=L5/L7:BOTTOM=L7 |
| PCIE_TX_CAP_N44 | TXC44-DIFF1 | PAIR | 3 | 5.5 | 5 | 10 | 5 | 50 | 6 | 20 | 12 | 12 | 12 | 12 | 7.5 | 85 Ohms | TOP=L2:L3=L2/L4:L6=L5/L7:BOTTOM=L7 |
| PCIE_TX_CAP_N44 | TXC44-DIFF1 | PAIR | 4 | 5.5 | 5 | 10 | 5 | 50 | 6 | 20 | 12 | 12 | 12 | 12 | 7.5 | 85 Ohms | TOP=L2:L3=L2/L4:L6=L5/L7:BOTTOM=L7 |
| PCIE_TX_CAP_N44 | TXC44-DIFF1 | PAIR | 5 | 5.5 | 5 | 10 | 5 | 50 | 6 | 20 | 12 | 12 | 12 | 12 | 7.5 | 85 Ohms | TOP=L2:L3=L2/L4:L6=L5/L7:BOTTOM=L7 |
| PCIE_TX_CAP_N44 | TXC44-DIFF1 | PAIR | 6 | 5.5 | 5 | 10 | 5 | 50 | 6 | 20 | 12 | 12 | 12 | 12 | 7.5 | 85 Ohms | TOP=L2:L3=L2/L4:L6=L5/L7:BOTTOM=L7 |
| PCIE_TX_CAP_N44 | TXC44-DIFF1 | PAIR | 7 | 5.5 | 5 | 10 | 5 | 50 | 6 | 20 | 12 | 12 | 12 | 12 | 7.5 | 85 Ohms | TOP=L2:L3=L2/L4:L6=L5/L7:BOTTOM=L7 |
| PCIE_TX_CAP_N44 | TXC44-DIFF1 | PAIR | 8 | 5.38 | 5 | 10 | 5 | 50 | 6 | 33 | 12 | 12 | 12 | 12 | 6.62 | 85 Ohms | TOP=L2:L3=L2/L4:L6=L5/L7:BOTTOM=L7 |
| PCIE_TX_CAP_P44 | TXC44-DIFF1 | PAIR | 1 | 5.38 | 5 | 10 | 5 | 50 | 6 | 33 | 12 | 12 | 12 | 12 | 6.62 | 85 Ohms | TOP=L2:L3=L2/L4:L6=L5/L7:BOTTOM=L7 |
| PCIE_TX_CAP_P44 | TXC44-DIFF1 | PAIR | 2 | 5.5 | 5 | 10 | 5 | 50 | 6 | 20 | 12 | 12 | 12 | 12 | 7.5 | 85 Ohms | TOP=L2:L3=L2/L4:L6=L5/L7:BOTTOM=L7 |
| PCIE_TX_CAP_P44 | TXC44-DIFF1 | PAIR | 3 | 5.5 | 5 | 10 | 5 | 50 | 6 | 20 | 12 | 12 | 12 | 12 | 7.5 | 85 Ohms | TOP=L2:L3=L2/L4:L6=L5/L7:BOTTOM=L7 |
| PCIE_TX_CAP_P44 | TXC44-DIFF1 | PAIR | 4 | 5.5 | 5 | 10 | 5 | 50 | 6 | 20 | 12 | 12 | 12 | 12 | 7.5 | 85 Ohms | TOP=L2:L3=L2/L4:L6=L5/L7:BOTTOM=L7 |
| PCIE_TX_CAP_P44 | TXC44-DIFF1 | PAIR | 5 | 5.5 | 5 | 10 | 5 | 50 | 6 | 20 | 12 | 12 | 12 | 12 | 7.5 | 85 Ohms | TOP=L2:L3=L2/L4:L6=L5/L7:BOTTOM=L7 |
| PCIE_TX_CAP_P44 | TXC44-DIFF1 | PAIR | 6 | 5.5 | 5 | 10 | 5 | 50 | 6 | 20 | 12 | 12 | 12 | 12 | 7.5 | 85 Ohms | TOP=L2:L3=L2/L4:L6=L5/L7:BOTTOM=L7 |
| PCIE_TX_CAP_P44 | TXC44-DIFF1 | PAIR | 7 | 5.5 | 5 | 10 | 5 | 50 | 6 | 20 | 12 | 12 | 12 | 12 | 7.5 | 85 Ohms | TOP=L2:L3=L2/L4:L6=L5/L7:BOTTOM=L7 |
| PCIE_TX_CAP_P44 | TXC44-DIFF1 | PAIR | 8 | 5.38 | 5 | 10 | 5 | 50 | 6 | 33 | 12 | 12 | 12 | 12 | 6.62 | 85 Ohms | TOP=L2:L3=L2/L4:L6=L5/L7:BOTTOM=L7 |
| PCIE_TX_CAP_N45 | TXC45-DIFF1 | PAIR | 1 | 5.38 | 5 | 10 | 5 | 50 | 6 | 33 | 12 | 12 | 12 | 12 | 6.62 | 85 Ohms | TOP=L2:L3=L2/L4:L6=L5/L7:BOTTOM=L7 |
| PCIE_TX_CAP_N45 | TXC45-DIFF1 | PAIR | 2 | 5.5 | 5 | 10 | 5 | 50 | 6 | 20 | 12 | 12 | 12 | 12 | 7.5 | 85 Ohms | TOP=L2:L3=L2/L4:L6=L5/L7:BOTTOM=L7 |
| PCIE_TX_CAP_N45 | TXC45-DIFF1 | PAIR | 3 | 5.5 | 5 | 10 | 5 | 50 | 6 | 20 | 12 | 12 | 12 | 12 | 7.5 | 85 Ohms | TOP=L2:L3=L2/L4:L6=L5/L7:BOTTOM=L7 |
| PCIE_TX_CAP_N45 | TXC45-DIFF1 | PAIR | 4 | 5.5 | 5 | 10 | 5 | 50 | 6 | 20 | 12 | 12 | 12 | 12 | 7.5 | 85 Ohms | TOP=L2:L3=L2/L4:L6=L5/L7:BOTTOM=L7 |
| PCIE_TX_CAP_N45 | TXC45-DIFF1 | PAIR | 5 | 5.5 | 5 | 10 | 5 | 50 | 6 | 20 | 12 | 12 | 12 | 12 | 7.5 | 85 Ohms | TOP=L2:L3=L2/L4:L6=L5/L7:BOTTOM=L7 |
| PCIE_TX_CAP_N45 | TXC45-DIFF1 | PAIR | 6 | 5.5 | 5 | 10 | 5 | 50 | 6 | 20 | 12 | 12 | 12 | 12 | 7.5 | 85 Ohms | TOP=L2:L3=L2/L4:L6=L5/L7:BOTTOM=L7 |
| PCIE_TX_CAP_N45 | TXC45-DIFF1 | PAIR | 7 | 5.5 | 5 | 10 | 5 | 50 | 6 | 20 | 12 | 12 | 12 | 12 | 7.5 | 85 Ohms | TOP=L2:L3=L2/L4:L6=L5/L7:BOTTOM=L7 |
| PCIE_TX_CAP_N45 | TXC45-DIFF1 | PAIR | 8 | 5.38 | 5 | 10 | 5 | 50 | 6 | 33 | 12 | 12 | 12 | 12 | 6.62 | 85 Ohms | TOP=L2:L3=L2/L4:L6=L5/L7:BOTTOM=L7 |
| PCIE_TX_CAP_P45 | TXC45-DIFF1 | PAIR | 1 | 5.38 | 5 | 10 | 5 | 50 | 6 | 33 | 12 | 12 | 12 | 12 | 6.62 | 85 Ohms | TOP=L2:L3=L2/L4:L6=L5/L7:BOTTOM=L7 |
| PCIE_TX_CAP_P45 | TXC45-DIFF1 | PAIR | 2 | 5.5 | 5 | 10 | 5 | 50 | 6 | 20 | 12 | 12 | 12 | 12 | 7.5 | 85 Ohms | TOP=L2:L3=L2/L4:L6=L5/L7:BOTTOM=L7 |
| PCIE_TX_CAP_P45 | TXC45-DIFF1 | PAIR | 3 | 5.5 | 5 | 10 | 5 | 50 | 6 | 20 | 12 | 12 | 12 | 12 | 7.5 | 85 Ohms | TOP=L2:L3=L2/L4:L6=L5/L7:BOTTOM=L7 |
| PCIE_TX_CAP_P45 | TXC45-DIFF1 | PAIR | 4 | 5.5 | 5 | 10 | 5 | 50 | 6 | 20 | 12 | 12 | 12 | 12 | 7.5 | 85 Ohms | TOP=L2:L3=L2/L4:L6=L5/L7:BOTTOM=L7 |
| PCIE_TX_CAP_P45 | TXC45-DIFF1 | PAIR | 5 | 5.5 | 5 | 10 | 5 | 50 | 6 | 20 | 12 | 12 | 12 | 12 | 7.5 | 85 Ohms | TOP=L2:L3=L2/L4:L6=L5/L7:BOTTOM=L7 |
| PCIE_TX_CAP_P45 | TXC45-DIFF1 | PAIR | 6 | 5.5 | 5 | 10 | 5 | 50 | 6 | 20 | 12 | 12 | 12 | 12 | 7.5 | 85 Ohms | TOP=L2:L3=L2/L4:L6=L5/L7:BOTTOM=L7 |
| PCIE_TX_CAP_P45 | TXC45-DIFF1 | PAIR | 7 | 5.5 | 5 | 10 | 5 | 50 | 6 | 20 | 12 | 12 | 12 | 12 | 7.5 | 85 Ohms | TOP=L2:L3=L2/L4:L6=L5/L7:BOTTOM=L7 |
| PCIE_TX_CAP_P45 | TXC45-DIFF1 | PAIR | 8 | 5.38 | 5 | 10 | 5 | 50 | 6 | 33 | 12 | 12 | 12 | 12 | 6.62 | 85 Ohms | TOP=L2:L3=L2/L4:L6=L5/L7:BOTTOM=L7 |
| PCIE_TX_CAP_N46 | TXC46-DIFF1 | PAIR | 1 | 5.38 | 5 | 10 | 5 | 50 | 6 | 33 | 12 | 12 | 12 | 12 | 6.62 | 85 Ohms | TOP=L2:L3=L2/L4:L6=L5/L7:BOTTOM=L7 |
| PCIE_TX_CAP_N46 | TXC46-DIFF1 | PAIR | 2 | 5.5 | 5 | 10 | 5 | 50 | 6 | 20 | 12 | 12 | 12 | 12 | 7.5 | 85 Ohms | TOP=L2:L3=L2/L4:L6=L5/L7:BOTTOM=L7 |
| PCIE_TX_CAP_N46 | TXC46-DIFF1 | PAIR | 3 | 5.5 | 5 | 10 | 5 | 50 | 6 | 20 | 12 | 12 | 12 | 12 | 7.5 | 85 Ohms | TOP=L2:L3=L2/L4:L6=L5/L7:BOTTOM=L7 |
| PCIE_TX_CAP_N46 | TXC46-DIFF1 | PAIR | 4 | 5.5 | 5 | 10 | 5 | 50 | 6 | 20 | 12 | 12 | 12 | 12 | 7.5 | 85 Ohms | TOP=L2:L3=L2/L4:L6=L5/L7:BOTTOM=L7 |
| PCIE_TX_CAP_N46 | TXC46-DIFF1 | PAIR | 5 | 5.5 | 5 | 10 | 5 | 50 | 6 | 20 | 12 | 12 | 12 | 12 | 7.5 | 85 Ohms | TOP=L2:L3=L2/L4:L6=L5/L7:BOTTOM=L7 |
| PCIE_TX_CAP_N46 | TXC46-DIFF1 | PAIR | 6 | 5.5 | 5 | 10 | 5 | 50 | 6 | 20 | 12 | 12 | 12 | 12 | 7.5 | 85 Ohms | TOP=L2:L3=L2/L4:L6=L5/L7:BOTTOM=L7 |
| PCIE_TX_CAP_N46 | TXC46-DIFF1 | PAIR | 7 | 5.5 | 5 | 10 | 5 | 50 | 6 | 20 | 12 | 12 | 12 | 12 | 7.5 | 85 Ohms | TOP=L2:L3=L2/L4:L6=L5/L7:BOTTOM=L7 |
| PCIE_TX_CAP_N46 | TXC46-DIFF1 | PAIR | 8 | 5.38 | 5 | 10 | 5 | 50 | 6 | 33 | 12 | 12 | 12 | 12 | 6.62 | 85 Ohms | TOP=L2:L3=L2/L4:L6=L5/L7:BOTTOM=L7 |
| PCIE_TX_CAP_P46 | TXC46-DIFF1 | PAIR | 1 | 5.38 | 5 | 10 | 5 | 50 | 6 | 33 | 12 | 12 | 12 | 12 | 6.62 | 85 Ohms | TOP=L2:L3=L2/L4:L6=L5/L7:BOTTOM=L7 |
| PCIE_TX_CAP_P46 | TXC46-DIFF1 | PAIR | 2 | 5.5 | 5 | 10 | 5 | 50 | 6 | 20 | 12 | 12 | 12 | 12 | 7.5 | 85 Ohms | TOP=L2:L3=L2/L4:L6=L5/L7:BOTTOM=L7 |
| PCIE_TX_CAP_P46 | TXC46-DIFF1 | PAIR | 3 | 5.5 | 5 | 10 | 5 | 50 | 6 | 20 | 12 | 12 | 12 | 12 | 7.5 | 85 Ohms | TOP=L2:L3=L2/L4:L6=L5/L7:BOTTOM=L7 |
| PCIE_TX_CAP_P46 | TXC46-DIFF1 | PAIR | 4 | 5.5 | 5 | 10 | 5 | 50 | 6 | 20 | 12 | 12 | 12 | 12 | 7.5 | 85 Ohms | TOP=L2:L3=L2/L4:L6=L5/L7:BOTTOM=L7 |
| PCIE_TX_CAP_P46 | TXC46-DIFF1 | PAIR | 5 | 5.5 | 5 | 10 | 5 | 50 | 6 | 20 | 12 | 12 | 12 | 12 | 7.5 | 85 Ohms | TOP=L2:L3=L2/L4:L6=L5/L7:BOTTOM=L7 |
| PCIE_TX_CAP_P46 | TXC46-DIFF1 | PAIR | 6 | 5.5 | 5 | 10 | 5 | 50 | 6 | 20 | 12 | 12 | 12 | 12 | 7.5 | 85 Ohms | TOP=L2:L3=L2/L4:L6=L5/L7:BOTTOM=L7 |
| PCIE_TX_CAP_P46 | TXC46-DIFF1 | PAIR | 7 | 5.5 | 5 | 10 | 5 | 50 | 6 | 20 | 12 | 12 | 12 | 12 | 7.5 | 85 Ohms | TOP=L2:L3=L2/L4:L6=L5/L7:BOTTOM=L7 |
| PCIE_TX_CAP_P46 | TXC46-DIFF1 | PAIR | 8 | 5.38 | 5 | 10 | 5 | 50 | 6 | 33 | 12 | 12 | 12 | 12 | 6.62 | 85 Ohms | TOP=L2:L3=L2/L4:L6=L5/L7:BOTTOM=L7 |
| PCIE_TX_CAP_N47 | TXC47-DIFF1 | PAIR | 1 | 5.38 | 5 | 10 | 5 | 50 | 6 | 33 | 12 | 12 | 12 | 12 | 6.62 | 85 Ohms | TOP=L2:L3=L2/L4:L6=L5/L7:BOTTOM=L7 |
| PCIE_TX_CAP_N47 | TXC47-DIFF1 | PAIR | 2 | 5.5 | 5 | 10 | 5 | 50 | 6 | 20 | 12 | 12 | 12 | 12 | 7.5 | 85 Ohms | TOP=L2:L3=L2/L4:L6=L5/L7:BOTTOM=L7 |
| PCIE_TX_CAP_N47 | TXC47-DIFF1 | PAIR | 3 | 5.5 | 5 | 10 | 5 | 50 | 6 | 20 | 12 | 12 | 12 | 12 | 7.5 | 85 Ohms | TOP=L2:L3=L2/L4:L6=L5/L7:BOTTOM=L7 |
| PCIE_TX_CAP_N47 | TXC47-DIFF1 | PAIR | 4 | 5.5 | 5 | 10 | 5 | 50 | 6 | 20 | 12 | 12 | 12 | 12 | 7.5 | 85 Ohms | TOP=L2:L3=L2/L4:L6=L5/L7:BOTTOM=L7 |
| PCIE_TX_CAP_N47 | TXC47-DIFF1 | PAIR | 5 | 5.5 | 5 | 10 | 5 | 50 | 6 | 20 | 12 | 12 | 12 | 12 | 7.5 | 85 Ohms | TOP=L2:L3=L2/L4:L6=L5/L7:BOTTOM=L7 |
| PCIE_TX_CAP_N47 | TXC47-DIFF1 | PAIR | 6 | 5.5 | 5 | 10 | 5 | 50 | 6 | 20 | 12 | 12 | 12 | 12 | 7.5 | 85 Ohms | TOP=L2:L3=L2/L4:L6=L5/L7:BOTTOM=L7 |
| PCIE_TX_CAP_N47 | TXC47-DIFF1 | PAIR | 7 | 5.5 | 5 | 10 | 5 | 50 | 6 | 20 | 12 | 12 | 12 | 12 | 7.5 | 85 Ohms | TOP=L2:L3=L2/L4:L6=L5/L7:BOTTOM=L7 |
| PCIE_TX_CAP_N47 | TXC47-DIFF1 | PAIR | 8 | 5.38 | 5 | 10 | 5 | 50 | 6 | 33 | 12 | 12 | 12 | 12 | 6.62 | 85 Ohms | TOP=L2:L3=L2/L4:L6=L5/L7:BOTTOM=L7 |
| PCIE_TX_CAP_P47 | TXC47-DIFF1 | PAIR | 1 | 5.38 | 5 | 10 | 5 | 50 | 6 | 33 | 12 | 12 | 12 | 12 | 6.62 | 85 Ohms | TOP=L2:L3=L2/L4:L6=L5/L7:BOTTOM=L7 |
| PCIE_TX_CAP_P47 | TXC47-DIFF1 | PAIR | 2 | 5.5 | 5 | 10 | 5 | 50 | 6 | 20 | 12 | 12 | 12 | 12 | 7.5 | 85 Ohms | TOP=L2:L3=L2/L4:L6=L5/L7:BOTTOM=L7 |
| PCIE_TX_CAP_P47 | TXC47-DIFF1 | PAIR | 3 | 5.5 | 5 | 10 | 5 | 50 | 6 | 20 | 12 | 12 | 12 | 12 | 7.5 | 85 Ohms | TOP=L2:L3=L2/L4:L6=L5/L7:BOTTOM=L7 |
| PCIE_TX_CAP_P47 | TXC47-DIFF1 | PAIR | 4 | 5.5 | 5 | 10 | 5 | 50 | 6 | 20 | 12 | 12 | 12 | 12 | 7.5 | 85 Ohms | TOP=L2:L3=L2/L4:L6=L5/L7:BOTTOM=L7 |
| PCIE_TX_CAP_P47 | TXC47-DIFF1 | PAIR | 5 | 5.5 | 5 | 10 | 5 | 50 | 6 | 20 | 12 | 12 | 12 | 12 | 7.5 | 85 Ohms | TOP=L2:L3=L2/L4:L6=L5/L7:BOTTOM=L7 |
| PCIE_TX_CAP_P47 | TXC47-DIFF1 | PAIR | 6 | 5.5 | 5 | 10 | 5 | 50 | 6 | 20 | 12 | 12 | 12 | 12 | 7.5 | 85 Ohms | TOP=L2:L3=L2/L4:L6=L5/L7:BOTTOM=L7 |
| PCIE_TX_CAP_P47 | TXC47-DIFF1 | PAIR | 7 | 5.5 | 5 | 10 | 5 | 50 | 6 | 20 | 12 | 12 | 12 | 12 | 7.5 | 85 Ohms | TOP=L2:L3=L2/L4:L6=L5/L7:BOTTOM=L7 |
| PCIE_TX_CAP_P47 | TXC47-DIFF1 | PAIR | 8 | 5.38 | 5 | 10 | 5 | 50 | 6 | 33 | 12 | 12 | 12 | 12 | 6.62 | 85 Ohms | TOP=L2:L3=L2/L4:L6=L5/L7:BOTTOM=L7 |
| PCIE_TX_CAP_N48 | TXC48-DIFF1 | PAIR | 1 | 5.38 | 5 | 10 | 5 | 50 | 6 | 33 | 12 | 12 | 12 | 12 | 6.62 | 85 Ohms | TOP=L2:L3=L2/L4:L6=L5/L7:BOTTOM=L7 |
| PCIE_TX_CAP_N48 | TXC48-DIFF1 | PAIR | 2 | 5.5 | 5 | 10 | 5 | 50 | 6 | 20 | 12 | 12 | 12 | 12 | 7.5 | 85 Ohms | TOP=L2:L3=L2/L4:L6=L5/L7:BOTTOM=L7 |
| PCIE_TX_CAP_N48 | TXC48-DIFF1 | PAIR | 3 | 5.5 | 5 | 10 | 5 | 50 | 6 | 20 | 12 | 12 | 12 | 12 | 7.5 | 85 Ohms | TOP=L2:L3=L2/L4:L6=L5/L7:BOTTOM=L7 |
| PCIE_TX_CAP_N48 | TXC48-DIFF1 | PAIR | 4 | 5.5 | 5 | 10 | 5 | 50 | 6 | 20 | 12 | 12 | 12 | 12 | 7.5 | 85 Ohms | TOP=L2:L3=L2/L4:L6=L5/L7:BOTTOM=L7 |
| PCIE_TX_CAP_N48 | TXC48-DIFF1 | PAIR | 5 | 5.5 | 5 | 10 | 5 | 50 | 6 | 20 | 12 | 12 | 12 | 12 | 7.5 | 85 Ohms | TOP=L2:L3=L2/L4:L6=L5/L7:BOTTOM=L7 |
| PCIE_TX_CAP_N48 | TXC48-DIFF1 | PAIR | 6 | 5.5 | 5 | 10 | 5 | 50 | 6 | 20 | 12 | 12 | 12 | 12 | 7.5 | 85 Ohms | TOP=L2:L3=L2/L4:L6=L5/L7:BOTTOM=L7 |
| PCIE_TX_CAP_N48 | TXC48-DIFF1 | PAIR | 7 | 5.5 | 5 | 10 | 5 | 50 | 6 | 20 | 12 | 12 | 12 | 12 | 7.5 | 85 Ohms | TOP=L2:L3=L2/L4:L6=L5/L7:BOTTOM=L7 |
| PCIE_TX_CAP_N48 | TXC48-DIFF1 | PAIR | 8 | 5.38 | 5 | 10 | 5 | 50 | 6 | 33 | 12 | 12 | 12 | 12 | 6.62 | 85 Ohms | TOP=L2:L3=L2/L4:L6=L5/L7:BOTTOM=L7 |
| PCIE_TX_CAP_P48 | TXC48-DIFF1 | PAIR | 1 | 5.38 | 5 | 10 | 5 | 50 | 6 | 33 | 12 | 12 | 12 | 12 | 6.62 | 85 Ohms | TOP=L2:L3=L2/L4:L6=L5/L7:BOTTOM=L7 |
| PCIE_TX_CAP_P48 | TXC48-DIFF1 | PAIR | 2 | 5.5 | 5 | 10 | 5 | 50 | 6 | 20 | 12 | 12 | 12 | 12 | 7.5 | 85 Ohms | TOP=L2:L3=L2/L4:L6=L5/L7:BOTTOM=L7 |
| PCIE_TX_CAP_P48 | TXC48-DIFF1 | PAIR | 3 | 5.5 | 5 | 10 | 5 | 50 | 6 | 20 | 12 | 12 | 12 | 12 | 7.5 | 85 Ohms | TOP=L2:L3=L2/L4:L6=L5/L7:BOTTOM=L7 |
| PCIE_TX_CAP_P48 | TXC48-DIFF1 | PAIR | 4 | 5.5 | 5 | 10 | 5 | 50 | 6 | 20 | 12 | 12 | 12 | 12 | 7.5 | 85 Ohms | TOP=L2:L3=L2/L4:L6=L5/L7:BOTTOM=L7 |
| PCIE_TX_CAP_P48 | TXC48-DIFF1 | PAIR | 5 | 5.5 | 5 | 10 | 5 | 50 | 6 | 20 | 12 | 12 | 12 | 12 | 7.5 | 85 Ohms | TOP=L2:L3=L2/L4:L6=L5/L7:BOTTOM=L7 |
| PCIE_TX_CAP_P48 | TXC48-DIFF1 | PAIR | 6 | 5.5 | 5 | 10 | 5 | 50 | 6 | 20 | 12 | 12 | 12 | 12 | 7.5 | 85 Ohms | TOP=L2:L3=L2/L4:L6=L5/L7:BOTTOM=L7 |
| PCIE_TX_CAP_P48 | TXC48-DIFF1 | PAIR | 7 | 5.5 | 5 | 10 | 5 | 50 | 6 | 20 | 12 | 12 | 12 | 12 | 7.5 | 85 Ohms | TOP=L2:L3=L2/L4:L6=L5/L7:BOTTOM=L7 |
| PCIE_TX_CAP_P48 | TXC48-DIFF1 | PAIR | 8 | 5.38 | 5 | 10 | 5 | 50 | 6 | 33 | 12 | 12 | 12 | 12 | 6.62 | 85 Ohms | TOP=L2:L3=L2/L4:L6=L5/L7:BOTTOM=L7 |
| PCIE_TX_CAP_N49 | TXC49-DIFF1 | PAIR | 1 | 5.38 | 5 | 10 | 5 | 50 | 6 | 33 | 12 | 12 | 12 | 12 | 6.62 | 85 Ohms | TOP=L2:L3=L2/L4:L6=L5/L7:BOTTOM=L7 |
| PCIE_TX_CAP_N49 | TXC49-DIFF1 | PAIR | 2 | 5.5 | 5 | 10 | 5 | 50 | 6 | 20 | 12 | 12 | 12 | 12 | 7.5 | 85 Ohms | TOP=L2:L3=L2/L4:L6=L5/L7:BOTTOM=L7 |
| PCIE_TX_CAP_N49 | TXC49-DIFF1 | PAIR | 3 | 5.5 | 5 | 10 | 5 | 50 | 6 | 20 | 12 | 12 | 12 | 12 | 7.5 | 85 Ohms | TOP=L2:L3=L2/L4:L6=L5/L7:BOTTOM=L7 |
| PCIE_TX_CAP_N49 | TXC49-DIFF1 | PAIR | 4 | 5.5 | 5 | 10 | 5 | 50 | 6 | 20 | 12 | 12 | 12 | 12 | 7.5 | 85 Ohms | TOP=L2:L3=L2/L4:L6=L5/L7:BOTTOM=L7 |
| PCIE_TX_CAP_N49 | TXC49-DIFF1 | PAIR | 5 | 5.5 | 5 | 10 | 5 | 50 | 6 | 20 | 12 | 12 | 12 | 12 | 7.5 | 85 Ohms | TOP=L2:L3=L2/L4:L6=L5/L7:BOTTOM=L7 |
| PCIE_TX_CAP_N49 | TXC49-DIFF1 | PAIR | 6 | 5.5 | 5 | 10 | 5 | 50 | 6 | 20 | 12 | 12 | 12 | 12 | 7.5 | 85 Ohms | TOP=L2:L3=L2/L4:L6=L5/L7:BOTTOM=L7 |
| PCIE_TX_CAP_N49 | TXC49-DIFF1 | PAIR | 7 | 5.5 | 5 | 10 | 5 | 50 | 6 | 20 | 12 | 12 | 12 | 12 | 7.5 | 85 Ohms | TOP=L2:L3=L2/L4:L6=L5/L7:BOTTOM=L7 |
| PCIE_TX_CAP_N49 | TXC49-DIFF1 | PAIR | 8 | 5.38 | 5 | 10 | 5 | 50 | 6 | 33 | 12 | 12 | 12 | 12 | 6.62 | 85 Ohms | TOP=L2:L3=L2/L4:L6=L5/L7:BOTTOM=L7 |
| PCIE_TX_CAP_P49 | TXC49-DIFF1 | PAIR | 1 | 5.38 | 5 | 10 | 5 | 50 | 6 | 33 | 12 | 12 | 12 | 12 | 6.62 | 85 Ohms | TOP=L2:L3=L2/L4:L6=L5/L7:BOTTOM=L7 |
| PCIE_TX_CAP_P49 | TXC49-DIFF1 | PAIR | 2 | 5.5 | 5 | 10 | 5 | 50 | 6 | 20 | 12 | 12 | 12 | 12 | 7.5 | 85 Ohms | TOP=L2:L3=L2/L4:L6=L5/L7:BOTTOM=L7 |
| PCIE_TX_CAP_P49 | TXC49-DIFF1 | PAIR | 3 | 5.5 | 5 | 10 | 5 | 50 | 6 | 20 | 12 | 12 | 12 | 12 | 7.5 | 85 Ohms | TOP=L2:L3=L2/L4:L6=L5/L7:BOTTOM=L7 |
| PCIE_TX_CAP_P49 | TXC49-DIFF1 | PAIR | 4 | 5.5 | 5 | 10 | 5 | 50 | 6 | 20 | 12 | 12 | 12 | 12 | 7.5 | 85 Ohms | TOP=L2:L3=L2/L4:L6=L5/L7:BOTTOM=L7 |
| PCIE_TX_CAP_P49 | TXC49-DIFF1 | PAIR | 5 | 5.5 | 5 | 10 | 5 | 50 | 6 | 20 | 12 | 12 | 12 | 12 | 7.5 | 85 Ohms | TOP=L2:L3=L2/L4:L6=L5/L7:BOTTOM=L7 |
| PCIE_TX_CAP_P49 | TXC49-DIFF1 | PAIR | 6 | 5.5 | 5 | 10 | 5 | 50 | 6 | 20 | 12 | 12 | 12 | 12 | 7.5 | 85 Ohms | TOP=L2:L3=L2/L4:L6=L5/L7:BOTTOM=L7 |
| PCIE_TX_CAP_P49 | TXC49-DIFF1 | PAIR | 7 | 5.5 | 5 | 10 | 5 | 50 | 6 | 20 | 12 | 12 | 12 | 12 | 7.5 | 85 Ohms | TOP=L2:L3=L2/L4:L6=L5/L7:BOTTOM=L7 |
| PCIE_TX_CAP_P49 | TXC49-DIFF1 | PAIR | 8 | 5.38 | 5 | 10 | 5 | 50 | 6 | 33 | 12 | 12 | 12 | 12 | 6.62 | 85 Ohms | TOP=L2:L3=L2/L4:L6=L5/L7:BOTTOM=L7 |
| PCIE_TX_CAP_N4 | TXC4-DIFF1 | PAIR | 1 | 5.38 | 5 | 10 | 5 | 50 | 6 | 33 | 12 | 12 | 12 | 12 | 6.62 | 85 Ohms | TOP=L2:L3=L2/L4:L6=L5/L7:BOTTOM=L7 |
| PCIE_TX_CAP_N4 | TXC4-DIFF1 | PAIR | 2 | 5.5 | 5 | 10 | 5 | 50 | 6 | 20 | 12 | 12 | 12 | 12 | 7.5 | 85 Ohms | TOP=L2:L3=L2/L4:L6=L5/L7:BOTTOM=L7 |
| PCIE_TX_CAP_N4 | TXC4-DIFF1 | PAIR | 3 | 5.5 | 5 | 10 | 5 | 50 | 6 | 20 | 12 | 12 | 12 | 12 | 7.5 | 85 Ohms | TOP=L2:L3=L2/L4:L6=L5/L7:BOTTOM=L7 |
| PCIE_TX_CAP_N4 | TXC4-DIFF1 | PAIR | 4 | 5.5 | 5 | 10 | 5 | 50 | 6 | 20 | 12 | 12 | 12 | 12 | 7.5 | 85 Ohms | TOP=L2:L3=L2/L4:L6=L5/L7:BOTTOM=L7 |
| PCIE_TX_CAP_N4 | TXC4-DIFF1 | PAIR | 5 | 5.5 | 5 | 10 | 5 | 50 | 6 | 20 | 12 | 12 | 12 | 12 | 7.5 | 85 Ohms | TOP=L2:L3=L2/L4:L6=L5/L7:BOTTOM=L7 |
| PCIE_TX_CAP_N4 | TXC4-DIFF1 | PAIR | 6 | 5.5 | 5 | 10 | 5 | 50 | 6 | 20 | 12 | 12 | 12 | 12 | 7.5 | 85 Ohms | TOP=L2:L3=L2/L4:L6=L5/L7:BOTTOM=L7 |
| PCIE_TX_CAP_N4 | TXC4-DIFF1 | PAIR | 7 | 5.5 | 5 | 10 | 5 | 50 | 6 | 20 | 12 | 12 | 12 | 12 | 7.5 | 85 Ohms | TOP=L2:L3=L2/L4:L6=L5/L7:BOTTOM=L7 |
| PCIE_TX_CAP_N4 | TXC4-DIFF1 | PAIR | 8 | 5.38 | 5 | 10 | 5 | 50 | 6 | 33 | 12 | 12 | 12 | 12 | 6.62 | 85 Ohms | TOP=L2:L3=L2/L4:L6=L5/L7:BOTTOM=L7 |
| PCIE_TX_CAP_P4 | TXC4-DIFF1 | PAIR | 1 | 5.38 | 5 | 10 | 5 | 50 | 6 | 33 | 12 | 12 | 12 | 12 | 6.62 | 85 Ohms | TOP=L2:L3=L2/L4:L6=L5/L7:BOTTOM=L7 |
| PCIE_TX_CAP_P4 | TXC4-DIFF1 | PAIR | 2 | 5.5 | 5 | 10 | 5 | 50 | 6 | 20 | 12 | 12 | 12 | 12 | 7.5 | 85 Ohms | TOP=L2:L3=L2/L4:L6=L5/L7:BOTTOM=L7 |
| PCIE_TX_CAP_P4 | TXC4-DIFF1 | PAIR | 3 | 5.5 | 5 | 10 | 5 | 50 | 6 | 20 | 12 | 12 | 12 | 12 | 7.5 | 85 Ohms | TOP=L2:L3=L2/L4:L6=L5/L7:BOTTOM=L7 |
| PCIE_TX_CAP_P4 | TXC4-DIFF1 | PAIR | 4 | 5.5 | 5 | 10 | 5 | 50 | 6 | 20 | 12 | 12 | 12 | 12 | 7.5 | 85 Ohms | TOP=L2:L3=L2/L4:L6=L5/L7:BOTTOM=L7 |
| PCIE_TX_CAP_P4 | TXC4-DIFF1 | PAIR | 5 | 5.5 | 5 | 10 | 5 | 50 | 6 | 20 | 12 | 12 | 12 | 12 | 7.5 | 85 Ohms | TOP=L2:L3=L2/L4:L6=L5/L7:BOTTOM=L7 |
| PCIE_TX_CAP_P4 | TXC4-DIFF1 | PAIR | 6 | 5.5 | 5 | 10 | 5 | 50 | 6 | 20 | 12 | 12 | 12 | 12 | 7.5 | 85 Ohms | TOP=L2:L3=L2/L4:L6=L5/L7:BOTTOM=L7 |
| PCIE_TX_CAP_P4 | TXC4-DIFF1 | PAIR | 7 | 5.5 | 5 | 10 | 5 | 50 | 6 | 20 | 12 | 12 | 12 | 12 | 7.5 | 85 Ohms | TOP=L2:L3=L2/L4:L6=L5/L7:BOTTOM=L7 |
| PCIE_TX_CAP_P4 | TXC4-DIFF1 | PAIR | 8 | 5.38 | 5 | 10 | 5 | 50 | 6 | 33 | 12 | 12 | 12 | 12 | 6.62 | 85 Ohms | TOP=L2:L3=L2/L4:L6=L5/L7:BOTTOM=L7 |
| PCIE_TX_CAP_N50 | TXC50-DIFF1 | PAIR | 1 | 5.38 | 5 | 10 | 5 | 50 | 6 | 33 | 12 | 12 | 12 | 12 | 6.62 | 85 Ohms | TOP=L2:L3=L2/L4:L6=L5/L7:BOTTOM=L7 |
| PCIE_TX_CAP_N50 | TXC50-DIFF1 | PAIR | 2 | 5.5 | 5 | 10 | 5 | 50 | 6 | 20 | 12 | 12 | 12 | 12 | 7.5 | 85 Ohms | TOP=L2:L3=L2/L4:L6=L5/L7:BOTTOM=L7 |
| PCIE_TX_CAP_N50 | TXC50-DIFF1 | PAIR | 3 | 5.5 | 5 | 10 | 5 | 50 | 6 | 20 | 12 | 12 | 12 | 12 | 7.5 | 85 Ohms | TOP=L2:L3=L2/L4:L6=L5/L7:BOTTOM=L7 |
| PCIE_TX_CAP_N50 | TXC50-DIFF1 | PAIR | 4 | 5.5 | 5 | 10 | 5 | 50 | 6 | 20 | 12 | 12 | 12 | 12 | 7.5 | 85 Ohms | TOP=L2:L3=L2/L4:L6=L5/L7:BOTTOM=L7 |
| PCIE_TX_CAP_N50 | TXC50-DIFF1 | PAIR | 5 | 5.5 | 5 | 10 | 5 | 50 | 6 | 20 | 12 | 12 | 12 | 12 | 7.5 | 85 Ohms | TOP=L2:L3=L2/L4:L6=L5/L7:BOTTOM=L7 |
| PCIE_TX_CAP_N50 | TXC50-DIFF1 | PAIR | 6 | 5.5 | 5 | 10 | 5 | 50 | 6 | 20 | 12 | 12 | 12 | 12 | 7.5 | 85 Ohms | TOP=L2:L3=L2/L4:L6=L5/L7:BOTTOM=L7 |
| PCIE_TX_CAP_N50 | TXC50-DIFF1 | PAIR | 7 | 5.5 | 5 | 10 | 5 | 50 | 6 | 20 | 12 | 12 | 12 | 12 | 7.5 | 85 Ohms | TOP=L2:L3=L2/L4:L6=L5/L7:BOTTOM=L7 |
| PCIE_TX_CAP_N50 | TXC50-DIFF1 | PAIR | 8 | 5.38 | 5 | 10 | 5 | 50 | 6 | 33 | 12 | 12 | 12 | 12 | 6.62 | 85 Ohms | TOP=L2:L3=L2/L4:L6=L5/L7:BOTTOM=L7 |
| PCIE_TX_CAP_P50 | TXC50-DIFF1 | PAIR | 1 | 5.38 | 5 | 10 | 5 | 50 | 6 | 33 | 12 | 12 | 12 | 12 | 6.62 | 85 Ohms | TOP=L2:L3=L2/L4:L6=L5/L7:BOTTOM=L7 |
| PCIE_TX_CAP_P50 | TXC50-DIFF1 | PAIR | 2 | 5.5 | 5 | 10 | 5 | 50 | 6 | 20 | 12 | 12 | 12 | 12 | 7.5 | 85 Ohms | TOP=L2:L3=L2/L4:L6=L5/L7:BOTTOM=L7 |
| PCIE_TX_CAP_P50 | TXC50-DIFF1 | PAIR | 3 | 5.5 | 5 | 10 | 5 | 50 | 6 | 20 | 12 | 12 | 12 | 12 | 7.5 | 85 Ohms | TOP=L2:L3=L2/L4:L6=L5/L7:BOTTOM=L7 |
| PCIE_TX_CAP_P50 | TXC50-DIFF1 | PAIR | 4 | 5.5 | 5 | 10 | 5 | 50 | 6 | 20 | 12 | 12 | 12 | 12 | 7.5 | 85 Ohms | TOP=L2:L3=L2/L4:L6=L5/L7:BOTTOM=L7 |
| PCIE_TX_CAP_P50 | TXC50-DIFF1 | PAIR | 5 | 5.5 | 5 | 10 | 5 | 50 | 6 | 20 | 12 | 12 | 12 | 12 | 7.5 | 85 Ohms | TOP=L2:L3=L2/L4:L6=L5/L7:BOTTOM=L7 |
| PCIE_TX_CAP_P50 | TXC50-DIFF1 | PAIR | 6 | 5.5 | 5 | 10 | 5 | 50 | 6 | 20 | 12 | 12 | 12 | 12 | 7.5 | 85 Ohms | TOP=L2:L3=L2/L4:L6=L5/L7:BOTTOM=L7 |
| PCIE_TX_CAP_P50 | TXC50-DIFF1 | PAIR | 7 | 5.5 | 5 | 10 | 5 | 50 | 6 | 20 | 12 | 12 | 12 | 12 | 7.5 | 85 Ohms | TOP=L2:L3=L2/L4:L6=L5/L7:BOTTOM=L7 |
| PCIE_TX_CAP_P50 | TXC50-DIFF1 | PAIR | 8 | 5.38 | 5 | 10 | 5 | 50 | 6 | 33 | 12 | 12 | 12 | 12 | 6.62 | 85 Ohms | TOP=L2:L3=L2/L4:L6=L5/L7:BOTTOM=L7 |
| PCIE_TX_CAP_N51 | TXC51-DIFF1 | PAIR | 1 | 5.38 | 5 | 10 | 5 | 50 | 6 | 33 | 12 | 12 | 12 | 12 | 6.62 | 85 Ohms | TOP=L2:L3=L2/L4:L6=L5/L7:BOTTOM=L7 |
| PCIE_TX_CAP_N51 | TXC51-DIFF1 | PAIR | 2 | 5.5 | 5 | 10 | 5 | 50 | 6 | 20 | 12 | 12 | 12 | 12 | 7.5 | 85 Ohms | TOP=L2:L3=L2/L4:L6=L5/L7:BOTTOM=L7 |
| PCIE_TX_CAP_N51 | TXC51-DIFF1 | PAIR | 3 | 5.5 | 5 | 10 | 5 | 50 | 6 | 20 | 12 | 12 | 12 | 12 | 7.5 | 85 Ohms | TOP=L2:L3=L2/L4:L6=L5/L7:BOTTOM=L7 |
| PCIE_TX_CAP_N51 | TXC51-DIFF1 | PAIR | 4 | 5.5 | 5 | 10 | 5 | 50 | 6 | 20 | 12 | 12 | 12 | 12 | 7.5 | 85 Ohms | TOP=L2:L3=L2/L4:L6=L5/L7:BOTTOM=L7 |
| PCIE_TX_CAP_N51 | TXC51-DIFF1 | PAIR | 5 | 5.5 | 5 | 10 | 5 | 50 | 6 | 20 | 12 | 12 | 12 | 12 | 7.5 | 85 Ohms | TOP=L2:L3=L2/L4:L6=L5/L7:BOTTOM=L7 |
| PCIE_TX_CAP_N51 | TXC51-DIFF1 | PAIR | 6 | 5.5 | 5 | 10 | 5 | 50 | 6 | 20 | 12 | 12 | 12 | 12 | 7.5 | 85 Ohms | TOP=L2:L3=L2/L4:L6=L5/L7:BOTTOM=L7 |
| PCIE_TX_CAP_N51 | TXC51-DIFF1 | PAIR | 7 | 5.5 | 5 | 10 | 5 | 50 | 6 | 20 | 12 | 12 | 12 | 12 | 7.5 | 85 Ohms | TOP=L2:L3=L2/L4:L6=L5/L7:BOTTOM=L7 |
| PCIE_TX_CAP_N51 | TXC51-DIFF1 | PAIR | 8 | 5.38 | 5 | 10 | 5 | 50 | 6 | 33 | 12 | 12 | 12 | 12 | 6.62 | 85 Ohms | TOP=L2:L3=L2/L4:L6=L5/L7:BOTTOM=L7 |
| PCIE_TX_CAP_P51 | TXC51-DIFF1 | PAIR | 1 | 5.38 | 5 | 10 | 5 | 50 | 6 | 33 | 12 | 12 | 12 | 12 | 6.62 | 85 Ohms | TOP=L2:L3=L2/L4:L6=L5/L7:BOTTOM=L7 |
| PCIE_TX_CAP_P51 | TXC51-DIFF1 | PAIR | 2 | 5.5 | 5 | 10 | 5 | 50 | 6 | 20 | 12 | 12 | 12 | 12 | 7.5 | 85 Ohms | TOP=L2:L3=L2/L4:L6=L5/L7:BOTTOM=L7 |
| PCIE_TX_CAP_P51 | TXC51-DIFF1 | PAIR | 3 | 5.5 | 5 | 10 | 5 | 50 | 6 | 20 | 12 | 12 | 12 | 12 | 7.5 | 85 Ohms | TOP=L2:L3=L2/L4:L6=L5/L7:BOTTOM=L7 |
| PCIE_TX_CAP_P51 | TXC51-DIFF1 | PAIR | 4 | 5.5 | 5 | 10 | 5 | 50 | 6 | 20 | 12 | 12 | 12 | 12 | 7.5 | 85 Ohms | TOP=L2:L3=L2/L4:L6=L5/L7:BOTTOM=L7 |
| PCIE_TX_CAP_P51 | TXC51-DIFF1 | PAIR | 5 | 5.5 | 5 | 10 | 5 | 50 | 6 | 20 | 12 | 12 | 12 | 12 | 7.5 | 85 Ohms | TOP=L2:L3=L2/L4:L6=L5/L7:BOTTOM=L7 |
| PCIE_TX_CAP_P51 | TXC51-DIFF1 | PAIR | 6 | 5.5 | 5 | 10 | 5 | 50 | 6 | 20 | 12 | 12 | 12 | 12 | 7.5 | 85 Ohms | TOP=L2:L3=L2/L4:L6=L5/L7:BOTTOM=L7 |
| PCIE_TX_CAP_P51 | TXC51-DIFF1 | PAIR | 7 | 5.5 | 5 | 10 | 5 | 50 | 6 | 20 | 12 | 12 | 12 | 12 | 7.5 | 85 Ohms | TOP=L2:L3=L2/L4:L6=L5/L7:BOTTOM=L7 |
| PCIE_TX_CAP_P51 | TXC51-DIFF1 | PAIR | 8 | 5.38 | 5 | 10 | 5 | 50 | 6 | 33 | 12 | 12 | 12 | 12 | 6.62 | 85 Ohms | TOP=L2:L3=L2/L4:L6=L5/L7:BOTTOM=L7 |
| PCIE_TX_CAP_N52 | TXC52-DIFF1 | PAIR | 1 | 5.38 | 5 | 10 | 5 | 50 | 6 | 33 | 12 | 12 | 12 | 12 | 6.62 | 85 Ohms | TOP=L2:L3=L2/L4:L6=L5/L7:BOTTOM=L7 |
| PCIE_TX_CAP_N52 | TXC52-DIFF1 | PAIR | 2 | 5.5 | 5 | 10 | 5 | 50 | 6 | 20 | 12 | 12 | 12 | 12 | 7.5 | 85 Ohms | TOP=L2:L3=L2/L4:L6=L5/L7:BOTTOM=L7 |
| PCIE_TX_CAP_N52 | TXC52-DIFF1 | PAIR | 3 | 5.5 | 5 | 10 | 5 | 50 | 6 | 20 | 12 | 12 | 12 | 12 | 7.5 | 85 Ohms | TOP=L2:L3=L2/L4:L6=L5/L7:BOTTOM=L7 |
| PCIE_TX_CAP_N52 | TXC52-DIFF1 | PAIR | 4 | 5.5 | 5 | 10 | 5 | 50 | 6 | 20 | 12 | 12 | 12 | 12 | 7.5 | 85 Ohms | TOP=L2:L3=L2/L4:L6=L5/L7:BOTTOM=L7 |
| PCIE_TX_CAP_N52 | TXC52-DIFF1 | PAIR | 5 | 5.5 | 5 | 10 | 5 | 50 | 6 | 20 | 12 | 12 | 12 | 12 | 7.5 | 85 Ohms | TOP=L2:L3=L2/L4:L6=L5/L7:BOTTOM=L7 |
| PCIE_TX_CAP_N52 | TXC52-DIFF1 | PAIR | 6 | 5.5 | 5 | 10 | 5 | 50 | 6 | 20 | 12 | 12 | 12 | 12 | 7.5 | 85 Ohms | TOP=L2:L3=L2/L4:L6=L5/L7:BOTTOM=L7 |
| PCIE_TX_CAP_N52 | TXC52-DIFF1 | PAIR | 7 | 5.5 | 5 | 10 | 5 | 50 | 6 | 20 | 12 | 12 | 12 | 12 | 7.5 | 85 Ohms | TOP=L2:L3=L2/L4:L6=L5/L7:BOTTOM=L7 |
| PCIE_TX_CAP_N52 | TXC52-DIFF1 | PAIR | 8 | 5.38 | 5 | 10 | 5 | 50 | 6 | 33 | 12 | 12 | 12 | 12 | 6.62 | 85 Ohms | TOP=L2:L3=L2/L4:L6=L5/L7:BOTTOM=L7 |
| PCIE_TX_CAP_P52 | TXC52-DIFF1 | PAIR | 1 | 5.38 | 5 | 10 | 5 | 50 | 6 | 33 | 12 | 12 | 12 | 12 | 6.62 | 85 Ohms | TOP=L2:L3=L2/L4:L6=L5/L7:BOTTOM=L7 |
| PCIE_TX_CAP_P52 | TXC52-DIFF1 | PAIR | 2 | 5.5 | 5 | 10 | 5 | 50 | 6 | 20 | 12 | 12 | 12 | 12 | 7.5 | 85 Ohms | TOP=L2:L3=L2/L4:L6=L5/L7:BOTTOM=L7 |
| PCIE_TX_CAP_P52 | TXC52-DIFF1 | PAIR | 3 | 5.5 | 5 | 10 | 5 | 50 | 6 | 20 | 12 | 12 | 12 | 12 | 7.5 | 85 Ohms | TOP=L2:L3=L2/L4:L6=L5/L7:BOTTOM=L7 |
| PCIE_TX_CAP_P52 | TXC52-DIFF1 | PAIR | 4 | 5.5 | 5 | 10 | 5 | 50 | 6 | 20 | 12 | 12 | 12 | 12 | 7.5 | 85 Ohms | TOP=L2:L3=L2/L4:L6=L5/L7:BOTTOM=L7 |
| PCIE_TX_CAP_P52 | TXC52-DIFF1 | PAIR | 5 | 5.5 | 5 | 10 | 5 | 50 | 6 | 20 | 12 | 12 | 12 | 12 | 7.5 | 85 Ohms | TOP=L2:L3=L2/L4:L6=L5/L7:BOTTOM=L7 |
| PCIE_TX_CAP_P52 | TXC52-DIFF1 | PAIR | 6 | 5.5 | 5 | 10 | 5 | 50 | 6 | 20 | 12 | 12 | 12 | 12 | 7.5 | 85 Ohms | TOP=L2:L3=L2/L4:L6=L5/L7:BOTTOM=L7 |
| PCIE_TX_CAP_P52 | TXC52-DIFF1 | PAIR | 7 | 5.5 | 5 | 10 | 5 | 50 | 6 | 20 | 12 | 12 | 12 | 12 | 7.5 | 85 Ohms | TOP=L2:L3=L2/L4:L6=L5/L7:BOTTOM=L7 |
| PCIE_TX_CAP_P52 | TXC52-DIFF1 | PAIR | 8 | 5.38 | 5 | 10 | 5 | 50 | 6 | 33 | 12 | 12 | 12 | 12 | 6.62 | 85 Ohms | TOP=L2:L3=L2/L4:L6=L5/L7:BOTTOM=L7 |
| PCIE_TX_CAP_N53 | TXC53-DIFF1 | PAIR | 1 | 5.38 | 5 | 10 | 5 | 50 | 6 | 33 | 12 | 12 | 12 | 12 | 6.62 | 85 Ohms | TOP=L2:L3=L2/L4:L6=L5/L7:BOTTOM=L7 |
| PCIE_TX_CAP_N53 | TXC53-DIFF1 | PAIR | 2 | 5.5 | 5 | 10 | 5 | 50 | 6 | 20 | 12 | 12 | 12 | 12 | 7.5 | 85 Ohms | TOP=L2:L3=L2/L4:L6=L5/L7:BOTTOM=L7 |
| PCIE_TX_CAP_N53 | TXC53-DIFF1 | PAIR | 3 | 5.5 | 5 | 10 | 5 | 50 | 6 | 20 | 12 | 12 | 12 | 12 | 7.5 | 85 Ohms | TOP=L2:L3=L2/L4:L6=L5/L7:BOTTOM=L7 |
| PCIE_TX_CAP_N53 | TXC53-DIFF1 | PAIR | 4 | 5.5 | 5 | 10 | 5 | 50 | 6 | 20 | 12 | 12 | 12 | 12 | 7.5 | 85 Ohms | TOP=L2:L3=L2/L4:L6=L5/L7:BOTTOM=L7 |
| PCIE_TX_CAP_N53 | TXC53-DIFF1 | PAIR | 5 | 5.5 | 5 | 10 | 5 | 50 | 6 | 20 | 12 | 12 | 12 | 12 | 7.5 | 85 Ohms | TOP=L2:L3=L2/L4:L6=L5/L7:BOTTOM=L7 |
| PCIE_TX_CAP_N53 | TXC53-DIFF1 | PAIR | 6 | 5.5 | 5 | 10 | 5 | 50 | 6 | 20 | 12 | 12 | 12 | 12 | 7.5 | 85 Ohms | TOP=L2:L3=L2/L4:L6=L5/L7:BOTTOM=L7 |
| PCIE_TX_CAP_N53 | TXC53-DIFF1 | PAIR | 7 | 5.5 | 5 | 10 | 5 | 50 | 6 | 20 | 12 | 12 | 12 | 12 | 7.5 | 85 Ohms | TOP=L2:L3=L2/L4:L6=L5/L7:BOTTOM=L7 |
| PCIE_TX_CAP_N53 | TXC53-DIFF1 | PAIR | 8 | 5.38 | 5 | 10 | 5 | 50 | 6 | 33 | 12 | 12 | 12 | 12 | 6.62 | 85 Ohms | TOP=L2:L3=L2/L4:L6=L5/L7:BOTTOM=L7 |
| PCIE_TX_CAP_P53 | TXC53-DIFF1 | PAIR | 1 | 5.38 | 5 | 10 | 5 | 50 | 6 | 33 | 12 | 12 | 12 | 12 | 6.62 | 85 Ohms | TOP=L2:L3=L2/L4:L6=L5/L7:BOTTOM=L7 |
| PCIE_TX_CAP_P53 | TXC53-DIFF1 | PAIR | 2 | 5.5 | 5 | 10 | 5 | 50 | 6 | 20 | 12 | 12 | 12 | 12 | 7.5 | 85 Ohms | TOP=L2:L3=L2/L4:L6=L5/L7:BOTTOM=L7 |
| PCIE_TX_CAP_P53 | TXC53-DIFF1 | PAIR | 3 | 5.5 | 5 | 10 | 5 | 50 | 6 | 20 | 12 | 12 | 12 | 12 | 7.5 | 85 Ohms | TOP=L2:L3=L2/L4:L6=L5/L7:BOTTOM=L7 |
| PCIE_TX_CAP_P53 | TXC53-DIFF1 | PAIR | 4 | 5.5 | 5 | 10 | 5 | 50 | 6 | 20 | 12 | 12 | 12 | 12 | 7.5 | 85 Ohms | TOP=L2:L3=L2/L4:L6=L5/L7:BOTTOM=L7 |
| PCIE_TX_CAP_P53 | TXC53-DIFF1 | PAIR | 5 | 5.5 | 5 | 10 | 5 | 50 | 6 | 20 | 12 | 12 | 12 | 12 | 7.5 | 85 Ohms | TOP=L2:L3=L2/L4:L6=L5/L7:BOTTOM=L7 |
| PCIE_TX_CAP_P53 | TXC53-DIFF1 | PAIR | 6 | 5.5 | 5 | 10 | 5 | 50 | 6 | 20 | 12 | 12 | 12 | 12 | 7.5 | 85 Ohms | TOP=L2:L3=L2/L4:L6=L5/L7:BOTTOM=L7 |
| PCIE_TX_CAP_P53 | TXC53-DIFF1 | PAIR | 7 | 5.5 | 5 | 10 | 5 | 50 | 6 | 20 | 12 | 12 | 12 | 12 | 7.5 | 85 Ohms | TOP=L2:L3=L2/L4:L6=L5/L7:BOTTOM=L7 |
| PCIE_TX_CAP_P53 | TXC53-DIFF1 | PAIR | 8 | 5.38 | 5 | 10 | 5 | 50 | 6 | 33 | 12 | 12 | 12 | 12 | 6.62 | 85 Ohms | TOP=L2:L3=L2/L4:L6=L5/L7:BOTTOM=L7 |
| PCIE_TX_CAP_N54 | TXC54-DIFF1 | PAIR | 1 | 5.38 | 5 | 10 | 5 | 50 | 6 | 33 | 12 | 12 | 12 | 12 | 6.62 | 85 Ohms | TOP=L2:L3=L2/L4:L6=L5/L7:BOTTOM=L7 |
| PCIE_TX_CAP_N54 | TXC54-DIFF1 | PAIR | 2 | 5.5 | 5 | 10 | 5 | 50 | 6 | 20 | 12 | 12 | 12 | 12 | 7.5 | 85 Ohms | TOP=L2:L3=L2/L4:L6=L5/L7:BOTTOM=L7 |
| PCIE_TX_CAP_N54 | TXC54-DIFF1 | PAIR | 3 | 5.5 | 5 | 10 | 5 | 50 | 6 | 20 | 12 | 12 | 12 | 12 | 7.5 | 85 Ohms | TOP=L2:L3=L2/L4:L6=L5/L7:BOTTOM=L7 |
| PCIE_TX_CAP_N54 | TXC54-DIFF1 | PAIR | 4 | 5.5 | 5 | 10 | 5 | 50 | 6 | 20 | 12 | 12 | 12 | 12 | 7.5 | 85 Ohms | TOP=L2:L3=L2/L4:L6=L5/L7:BOTTOM=L7 |
| PCIE_TX_CAP_N54 | TXC54-DIFF1 | PAIR | 5 | 5.5 | 5 | 10 | 5 | 50 | 6 | 20 | 12 | 12 | 12 | 12 | 7.5 | 85 Ohms | TOP=L2:L3=L2/L4:L6=L5/L7:BOTTOM=L7 |
| PCIE_TX_CAP_N54 | TXC54-DIFF1 | PAIR | 6 | 5.5 | 5 | 10 | 5 | 50 | 6 | 20 | 12 | 12 | 12 | 12 | 7.5 | 85 Ohms | TOP=L2:L3=L2/L4:L6=L5/L7:BOTTOM=L7 |
| PCIE_TX_CAP_N54 | TXC54-DIFF1 | PAIR | 7 | 5.5 | 5 | 10 | 5 | 50 | 6 | 20 | 12 | 12 | 12 | 12 | 7.5 | 85 Ohms | TOP=L2:L3=L2/L4:L6=L5/L7:BOTTOM=L7 |
| PCIE_TX_CAP_N54 | TXC54-DIFF1 | PAIR | 8 | 5.38 | 5 | 10 | 5 | 50 | 6 | 33 | 12 | 12 | 12 | 12 | 6.62 | 85 Ohms | TOP=L2:L3=L2/L4:L6=L5/L7:BOTTOM=L7 |
| PCIE_TX_CAP_P54 | TXC54-DIFF1 | PAIR | 1 | 5.38 | 5 | 10 | 5 | 50 | 6 | 33 | 12 | 12 | 12 | 12 | 6.62 | 85 Ohms | TOP=L2:L3=L2/L4:L6=L5/L7:BOTTOM=L7 |
| PCIE_TX_CAP_P54 | TXC54-DIFF1 | PAIR | 2 | 5.5 | 5 | 10 | 5 | 50 | 6 | 20 | 12 | 12 | 12 | 12 | 7.5 | 85 Ohms | TOP=L2:L3=L2/L4:L6=L5/L7:BOTTOM=L7 |
| PCIE_TX_CAP_P54 | TXC54-DIFF1 | PAIR | 3 | 5.5 | 5 | 10 | 5 | 50 | 6 | 20 | 12 | 12 | 12 | 12 | 7.5 | 85 Ohms | TOP=L2:L3=L2/L4:L6=L5/L7:BOTTOM=L7 |
| PCIE_TX_CAP_P54 | TXC54-DIFF1 | PAIR | 4 | 5.5 | 5 | 10 | 5 | 50 | 6 | 20 | 12 | 12 | 12 | 12 | 7.5 | 85 Ohms | TOP=L2:L3=L2/L4:L6=L5/L7:BOTTOM=L7 |
| PCIE_TX_CAP_P54 | TXC54-DIFF1 | PAIR | 5 | 5.5 | 5 | 10 | 5 | 50 | 6 | 20 | 12 | 12 | 12 | 12 | 7.5 | 85 Ohms | TOP=L2:L3=L2/L4:L6=L5/L7:BOTTOM=L7 |
| PCIE_TX_CAP_P54 | TXC54-DIFF1 | PAIR | 6 | 5.5 | 5 | 10 | 5 | 50 | 6 | 20 | 12 | 12 | 12 | 12 | 7.5 | 85 Ohms | TOP=L2:L3=L2/L4:L6=L5/L7:BOTTOM=L7 |
| PCIE_TX_CAP_P54 | TXC54-DIFF1 | PAIR | 7 | 5.5 | 5 | 10 | 5 | 50 | 6 | 20 | 12 | 12 | 12 | 12 | 7.5 | 85 Ohms | TOP=L2:L3=L2/L4:L6=L5/L7:BOTTOM=L7 |
| PCIE_TX_CAP_P54 | TXC54-DIFF1 | PAIR | 8 | 5.38 | 5 | 10 | 5 | 50 | 6 | 33 | 12 | 12 | 12 | 12 | 6.62 | 85 Ohms | TOP=L2:L3=L2/L4:L6=L5/L7:BOTTOM=L7 |
| PCIE_TX_CAP_N55 | TXC55-DIFF1 | PAIR | 1 | 5.38 | 5 | 10 | 5 | 50 | 6 | 33 | 12 | 12 | 12 | 12 | 6.62 | 85 Ohms | TOP=L2:L3=L2/L4:L6=L5/L7:BOTTOM=L7 |
| PCIE_TX_CAP_N55 | TXC55-DIFF1 | PAIR | 2 | 5.5 | 5 | 10 | 5 | 50 | 6 | 20 | 12 | 12 | 12 | 12 | 7.5 | 85 Ohms | TOP=L2:L3=L2/L4:L6=L5/L7:BOTTOM=L7 |
| PCIE_TX_CAP_N55 | TXC55-DIFF1 | PAIR | 3 | 5.5 | 5 | 10 | 5 | 50 | 6 | 20 | 12 | 12 | 12 | 12 | 7.5 | 85 Ohms | TOP=L2:L3=L2/L4:L6=L5/L7:BOTTOM=L7 |
| PCIE_TX_CAP_N55 | TXC55-DIFF1 | PAIR | 4 | 5.5 | 5 | 10 | 5 | 50 | 6 | 20 | 12 | 12 | 12 | 12 | 7.5 | 85 Ohms | TOP=L2:L3=L2/L4:L6=L5/L7:BOTTOM=L7 |
| PCIE_TX_CAP_N55 | TXC55-DIFF1 | PAIR | 5 | 5.5 | 5 | 10 | 5 | 50 | 6 | 20 | 12 | 12 | 12 | 12 | 7.5 | 85 Ohms | TOP=L2:L3=L2/L4:L6=L5/L7:BOTTOM=L7 |
| PCIE_TX_CAP_N55 | TXC55-DIFF1 | PAIR | 6 | 5.5 | 5 | 10 | 5 | 50 | 6 | 20 | 12 | 12 | 12 | 12 | 7.5 | 85 Ohms | TOP=L2:L3=L2/L4:L6=L5/L7:BOTTOM=L7 |
| PCIE_TX_CAP_N55 | TXC55-DIFF1 | PAIR | 7 | 5.5 | 5 | 10 | 5 | 50 | 6 | 20 | 12 | 12 | 12 | 12 | 7.5 | 85 Ohms | TOP=L2:L3=L2/L4:L6=L5/L7:BOTTOM=L7 |
| PCIE_TX_CAP_N55 | TXC55-DIFF1 | PAIR | 8 | 5.38 | 5 | 10 | 5 | 50 | 6 | 33 | 12 | 12 | 12 | 12 | 6.62 | 85 Ohms | TOP=L2:L3=L2/L4:L6=L5/L7:BOTTOM=L7 |
| PCIE_TX_CAP_P55 | TXC55-DIFF1 | PAIR | 1 | 5.38 | 5 | 10 | 5 | 50 | 6 | 33 | 12 | 12 | 12 | 12 | 6.62 | 85 Ohms | TOP=L2:L3=L2/L4:L6=L5/L7:BOTTOM=L7 |
| PCIE_TX_CAP_P55 | TXC55-DIFF1 | PAIR | 2 | 5.5 | 5 | 10 | 5 | 50 | 6 | 20 | 12 | 12 | 12 | 12 | 7.5 | 85 Ohms | TOP=L2:L3=L2/L4:L6=L5/L7:BOTTOM=L7 |
| PCIE_TX_CAP_P55 | TXC55-DIFF1 | PAIR | 3 | 5.5 | 5 | 10 | 5 | 50 | 6 | 20 | 12 | 12 | 12 | 12 | 7.5 | 85 Ohms | TOP=L2:L3=L2/L4:L6=L5/L7:BOTTOM=L7 |
| PCIE_TX_CAP_P55 | TXC55-DIFF1 | PAIR | 4 | 5.5 | 5 | 10 | 5 | 50 | 6 | 20 | 12 | 12 | 12 | 12 | 7.5 | 85 Ohms | TOP=L2:L3=L2/L4:L6=L5/L7:BOTTOM=L7 |
| PCIE_TX_CAP_P55 | TXC55-DIFF1 | PAIR | 5 | 5.5 | 5 | 10 | 5 | 50 | 6 | 20 | 12 | 12 | 12 | 12 | 7.5 | 85 Ohms | TOP=L2:L3=L2/L4:L6=L5/L7:BOTTOM=L7 |
| PCIE_TX_CAP_P55 | TXC55-DIFF1 | PAIR | 6 | 5.5 | 5 | 10 | 5 | 50 | 6 | 20 | 12 | 12 | 12 | 12 | 7.5 | 85 Ohms | TOP=L2:L3=L2/L4:L6=L5/L7:BOTTOM=L7 |
| PCIE_TX_CAP_P55 | TXC55-DIFF1 | PAIR | 7 | 5.5 | 5 | 10 | 5 | 50 | 6 | 20 | 12 | 12 | 12 | 12 | 7.5 | 85 Ohms | TOP=L2:L3=L2/L4:L6=L5/L7:BOTTOM=L7 |
| PCIE_TX_CAP_P55 | TXC55-DIFF1 | PAIR | 8 | 5.38 | 5 | 10 | 5 | 50 | 6 | 33 | 12 | 12 | 12 | 12 | 6.62 | 85 Ohms | TOP=L2:L3=L2/L4:L6=L5/L7:BOTTOM=L7 |
| PCIE_TX_CAP_N56 | TXC56-DIFF1 | PAIR | 1 | 5.38 | 5 | 10 | 5 | 50 | 6 | 33 | 12 | 12 | 12 | 12 | 6.62 | 85 Ohms | TOP=L2:L3=L2/L4:L6=L5/L7:BOTTOM=L7 |
| PCIE_TX_CAP_N56 | TXC56-DIFF1 | PAIR | 2 | 5.5 | 5 | 10 | 5 | 50 | 6 | 20 | 12 | 12 | 12 | 12 | 7.5 | 85 Ohms | TOP=L2:L3=L2/L4:L6=L5/L7:BOTTOM=L7 |
| PCIE_TX_CAP_N56 | TXC56-DIFF1 | PAIR | 3 | 5.5 | 5 | 10 | 5 | 50 | 6 | 20 | 12 | 12 | 12 | 12 | 7.5 | 85 Ohms | TOP=L2:L3=L2/L4:L6=L5/L7:BOTTOM=L7 |
| PCIE_TX_CAP_N56 | TXC56-DIFF1 | PAIR | 4 | 5.5 | 5 | 10 | 5 | 50 | 6 | 20 | 12 | 12 | 12 | 12 | 7.5 | 85 Ohms | TOP=L2:L3=L2/L4:L6=L5/L7:BOTTOM=L7 |
| PCIE_TX_CAP_N56 | TXC56-DIFF1 | PAIR | 5 | 5.5 | 5 | 10 | 5 | 50 | 6 | 20 | 12 | 12 | 12 | 12 | 7.5 | 85 Ohms | TOP=L2:L3=L2/L4:L6=L5/L7:BOTTOM=L7 |
| PCIE_TX_CAP_N56 | TXC56-DIFF1 | PAIR | 6 | 5.5 | 5 | 10 | 5 | 50 | 6 | 20 | 12 | 12 | 12 | 12 | 7.5 | 85 Ohms | TOP=L2:L3=L2/L4:L6=L5/L7:BOTTOM=L7 |
| PCIE_TX_CAP_N56 | TXC56-DIFF1 | PAIR | 7 | 5.5 | 5 | 10 | 5 | 50 | 6 | 20 | 12 | 12 | 12 | 12 | 7.5 | 85 Ohms | TOP=L2:L3=L2/L4:L6=L5/L7:BOTTOM=L7 |
| PCIE_TX_CAP_N56 | TXC56-DIFF1 | PAIR | 8 | 5.38 | 5 | 10 | 5 | 50 | 6 | 33 | 12 | 12 | 12 | 12 | 6.62 | 85 Ohms | TOP=L2:L3=L2/L4:L6=L5/L7:BOTTOM=L7 |
| PCIE_TX_CAP_P56 | TXC56-DIFF1 | PAIR | 1 | 5.38 | 5 | 10 | 5 | 50 | 6 | 33 | 12 | 12 | 12 | 12 | 6.62 | 85 Ohms | TOP=L2:L3=L2/L4:L6=L5/L7:BOTTOM=L7 |
| PCIE_TX_CAP_P56 | TXC56-DIFF1 | PAIR | 2 | 5.5 | 5 | 10 | 5 | 50 | 6 | 20 | 12 | 12 | 12 | 12 | 7.5 | 85 Ohms | TOP=L2:L3=L2/L4:L6=L5/L7:BOTTOM=L7 |
| PCIE_TX_CAP_P56 | TXC56-DIFF1 | PAIR | 3 | 5.5 | 5 | 10 | 5 | 50 | 6 | 20 | 12 | 12 | 12 | 12 | 7.5 | 85 Ohms | TOP=L2:L3=L2/L4:L6=L5/L7:BOTTOM=L7 |
| PCIE_TX_CAP_P56 | TXC56-DIFF1 | PAIR | 4 | 5.5 | 5 | 10 | 5 | 50 | 6 | 20 | 12 | 12 | 12 | 12 | 7.5 | 85 Ohms | TOP=L2:L3=L2/L4:L6=L5/L7:BOTTOM=L7 |
| PCIE_TX_CAP_P56 | TXC56-DIFF1 | PAIR | 5 | 5.5 | 5 | 10 | 5 | 50 | 6 | 20 | 12 | 12 | 12 | 12 | 7.5 | 85 Ohms | TOP=L2:L3=L2/L4:L6=L5/L7:BOTTOM=L7 |
| PCIE_TX_CAP_P56 | TXC56-DIFF1 | PAIR | 6 | 5.5 | 5 | 10 | 5 | 50 | 6 | 20 | 12 | 12 | 12 | 12 | 7.5 | 85 Ohms | TOP=L2:L3=L2/L4:L6=L5/L7:BOTTOM=L7 |
| PCIE_TX_CAP_P56 | TXC56-DIFF1 | PAIR | 7 | 5.5 | 5 | 10 | 5 | 50 | 6 | 20 | 12 | 12 | 12 | 12 | 7.5 | 85 Ohms | TOP=L2:L3=L2/L4:L6=L5/L7:BOTTOM=L7 |
| PCIE_TX_CAP_P56 | TXC56-DIFF1 | PAIR | 8 | 5.38 | 5 | 10 | 5 | 50 | 6 | 33 | 12 | 12 | 12 | 12 | 6.62 | 85 Ohms | TOP=L2:L3=L2/L4:L6=L5/L7:BOTTOM=L7 |
| PCIE_TX_CAP_N57 | TXC57-DIFF1 | PAIR | 1 | 5.38 | 5 | 10 | 5 | 50 | 6 | 33 | 12 | 12 | 12 | 12 | 6.62 | 85 Ohms | TOP=L2:L3=L2/L4:L6=L5/L7:BOTTOM=L7 |
| PCIE_TX_CAP_N57 | TXC57-DIFF1 | PAIR | 2 | 5.5 | 5 | 10 | 5 | 50 | 6 | 20 | 12 | 12 | 12 | 12 | 7.5 | 85 Ohms | TOP=L2:L3=L2/L4:L6=L5/L7:BOTTOM=L7 |
| PCIE_TX_CAP_N57 | TXC57-DIFF1 | PAIR | 3 | 5.5 | 5 | 10 | 5 | 50 | 6 | 20 | 12 | 12 | 12 | 12 | 7.5 | 85 Ohms | TOP=L2:L3=L2/L4:L6=L5/L7:BOTTOM=L7 |
| PCIE_TX_CAP_N57 | TXC57-DIFF1 | PAIR | 4 | 5.5 | 5 | 10 | 5 | 50 | 6 | 20 | 12 | 12 | 12 | 12 | 7.5 | 85 Ohms | TOP=L2:L3=L2/L4:L6=L5/L7:BOTTOM=L7 |
| PCIE_TX_CAP_N57 | TXC57-DIFF1 | PAIR | 5 | 5.5 | 5 | 10 | 5 | 50 | 6 | 20 | 12 | 12 | 12 | 12 | 7.5 | 85 Ohms | TOP=L2:L3=L2/L4:L6=L5/L7:BOTTOM=L7 |
| PCIE_TX_CAP_N57 | TXC57-DIFF1 | PAIR | 6 | 5.5 | 5 | 10 | 5 | 50 | 6 | 20 | 12 | 12 | 12 | 12 | 7.5 | 85 Ohms | TOP=L2:L3=L2/L4:L6=L5/L7:BOTTOM=L7 |
| PCIE_TX_CAP_N57 | TXC57-DIFF1 | PAIR | 7 | 5.5 | 5 | 10 | 5 | 50 | 6 | 20 | 12 | 12 | 12 | 12 | 7.5 | 85 Ohms | TOP=L2:L3=L2/L4:L6=L5/L7:BOTTOM=L7 |
| PCIE_TX_CAP_N57 | TXC57-DIFF1 | PAIR | 8 | 5.38 | 5 | 10 | 5 | 50 | 6 | 33 | 12 | 12 | 12 | 12 | 6.62 | 85 Ohms | TOP=L2:L3=L2/L4:L6=L5/L7:BOTTOM=L7 |
| PCIE_TX_CAP_P57 | TXC57-DIFF1 | PAIR | 1 | 5.38 | 5 | 10 | 5 | 50 | 6 | 33 | 12 | 12 | 12 | 12 | 6.62 | 85 Ohms | TOP=L2:L3=L2/L4:L6=L5/L7:BOTTOM=L7 |
| PCIE_TX_CAP_P57 | TXC57-DIFF1 | PAIR | 2 | 5.5 | 5 | 10 | 5 | 50 | 6 | 20 | 12 | 12 | 12 | 12 | 7.5 | 85 Ohms | TOP=L2:L3=L2/L4:L6=L5/L7:BOTTOM=L7 |
| PCIE_TX_CAP_P57 | TXC57-DIFF1 | PAIR | 3 | 5.5 | 5 | 10 | 5 | 50 | 6 | 20 | 12 | 12 | 12 | 12 | 7.5 | 85 Ohms | TOP=L2:L3=L2/L4:L6=L5/L7:BOTTOM=L7 |
| PCIE_TX_CAP_P57 | TXC57-DIFF1 | PAIR | 4 | 5.5 | 5 | 10 | 5 | 50 | 6 | 20 | 12 | 12 | 12 | 12 | 7.5 | 85 Ohms | TOP=L2:L3=L2/L4:L6=L5/L7:BOTTOM=L7 |
| PCIE_TX_CAP_P57 | TXC57-DIFF1 | PAIR | 5 | 5.5 | 5 | 10 | 5 | 50 | 6 | 20 | 12 | 12 | 12 | 12 | 7.5 | 85 Ohms | TOP=L2:L3=L2/L4:L6=L5/L7:BOTTOM=L7 |
| PCIE_TX_CAP_P57 | TXC57-DIFF1 | PAIR | 6 | 5.5 | 5 | 10 | 5 | 50 | 6 | 20 | 12 | 12 | 12 | 12 | 7.5 | 85 Ohms | TOP=L2:L3=L2/L4:L6=L5/L7:BOTTOM=L7 |
| PCIE_TX_CAP_P57 | TXC57-DIFF1 | PAIR | 7 | 5.5 | 5 | 10 | 5 | 50 | 6 | 20 | 12 | 12 | 12 | 12 | 7.5 | 85 Ohms | TOP=L2:L3=L2/L4:L6=L5/L7:BOTTOM=L7 |
| PCIE_TX_CAP_P57 | TXC57-DIFF1 | PAIR | 8 | 5.38 | 5 | 10 | 5 | 50 | 6 | 33 | 12 | 12 | 12 | 12 | 6.62 | 85 Ohms | TOP=L2:L3=L2/L4:L6=L5/L7:BOTTOM=L7 |
| PCIE_TX_CAP_N58 | TXC58-DIFF1 | PAIR | 1 | 5.38 | 5 | 10 | 5 | 50 | 6 | 33 | 12 | 12 | 12 | 12 | 6.62 | 85 Ohms | TOP=L2:L3=L2/L4:L6=L5/L7:BOTTOM=L7 |
| PCIE_TX_CAP_N58 | TXC58-DIFF1 | PAIR | 2 | 5.5 | 5 | 10 | 5 | 50 | 6 | 20 | 12 | 12 | 12 | 12 | 7.5 | 85 Ohms | TOP=L2:L3=L2/L4:L6=L5/L7:BOTTOM=L7 |
| PCIE_TX_CAP_N58 | TXC58-DIFF1 | PAIR | 3 | 5.5 | 5 | 10 | 5 | 50 | 6 | 20 | 12 | 12 | 12 | 12 | 7.5 | 85 Ohms | TOP=L2:L3=L2/L4:L6=L5/L7:BOTTOM=L7 |
| PCIE_TX_CAP_N58 | TXC58-DIFF1 | PAIR | 4 | 5.5 | 5 | 10 | 5 | 50 | 6 | 20 | 12 | 12 | 12 | 12 | 7.5 | 85 Ohms | TOP=L2:L3=L2/L4:L6=L5/L7:BOTTOM=L7 |
| PCIE_TX_CAP_N58 | TXC58-DIFF1 | PAIR | 5 | 5.5 | 5 | 10 | 5 | 50 | 6 | 20 | 12 | 12 | 12 | 12 | 7.5 | 85 Ohms | TOP=L2:L3=L2/L4:L6=L5/L7:BOTTOM=L7 |
| PCIE_TX_CAP_N58 | TXC58-DIFF1 | PAIR | 6 | 5.5 | 5 | 10 | 5 | 50 | 6 | 20 | 12 | 12 | 12 | 12 | 7.5 | 85 Ohms | TOP=L2:L3=L2/L4:L6=L5/L7:BOTTOM=L7 |
| PCIE_TX_CAP_N58 | TXC58-DIFF1 | PAIR | 7 | 5.5 | 5 | 10 | 5 | 50 | 6 | 20 | 12 | 12 | 12 | 12 | 7.5 | 85 Ohms | TOP=L2:L3=L2/L4:L6=L5/L7:BOTTOM=L7 |
| PCIE_TX_CAP_N58 | TXC58-DIFF1 | PAIR | 8 | 5.38 | 5 | 10 | 5 | 50 | 6 | 33 | 12 | 12 | 12 | 12 | 6.62 | 85 Ohms | TOP=L2:L3=L2/L4:L6=L5/L7:BOTTOM=L7 |
| PCIE_TX_CAP_P58 | TXC58-DIFF1 | PAIR | 1 | 5.38 | 5 | 10 | 5 | 50 | 6 | 33 | 12 | 12 | 12 | 12 | 6.62 | 85 Ohms | TOP=L2:L3=L2/L4:L6=L5/L7:BOTTOM=L7 |
| PCIE_TX_CAP_P58 | TXC58-DIFF1 | PAIR | 2 | 5.5 | 5 | 10 | 5 | 50 | 6 | 20 | 12 | 12 | 12 | 12 | 7.5 | 85 Ohms | TOP=L2:L3=L2/L4:L6=L5/L7:BOTTOM=L7 |
| PCIE_TX_CAP_P58 | TXC58-DIFF1 | PAIR | 3 | 5.5 | 5 | 10 | 5 | 50 | 6 | 20 | 12 | 12 | 12 | 12 | 7.5 | 85 Ohms | TOP=L2:L3=L2/L4:L6=L5/L7:BOTTOM=L7 |
| PCIE_TX_CAP_P58 | TXC58-DIFF1 | PAIR | 4 | 5.5 | 5 | 10 | 5 | 50 | 6 | 20 | 12 | 12 | 12 | 12 | 7.5 | 85 Ohms | TOP=L2:L3=L2/L4:L6=L5/L7:BOTTOM=L7 |
| PCIE_TX_CAP_P58 | TXC58-DIFF1 | PAIR | 5 | 5.5 | 5 | 10 | 5 | 50 | 6 | 20 | 12 | 12 | 12 | 12 | 7.5 | 85 Ohms | TOP=L2:L3=L2/L4:L6=L5/L7:BOTTOM=L7 |
| PCIE_TX_CAP_P58 | TXC58-DIFF1 | PAIR | 6 | 5.5 | 5 | 10 | 5 | 50 | 6 | 20 | 12 | 12 | 12 | 12 | 7.5 | 85 Ohms | TOP=L2:L3=L2/L4:L6=L5/L7:BOTTOM=L7 |
| PCIE_TX_CAP_P58 | TXC58-DIFF1 | PAIR | 7 | 5.5 | 5 | 10 | 5 | 50 | 6 | 20 | 12 | 12 | 12 | 12 | 7.5 | 85 Ohms | TOP=L2:L3=L2/L4:L6=L5/L7:BOTTOM=L7 |
| PCIE_TX_CAP_P58 | TXC58-DIFF1 | PAIR | 8 | 5.38 | 5 | 10 | 5 | 50 | 6 | 33 | 12 | 12 | 12 | 12 | 6.62 | 85 Ohms | TOP=L2:L3=L2/L4:L6=L5/L7:BOTTOM=L7 |
| PCIE_TX_CAP_N59 | TXC59-DIFF1 | PAIR | 1 | 5.38 | 5 | 10 | 5 | 50 | 6 | 33 | 12 | 12 | 12 | 12 | 6.62 | 85 Ohms | TOP=L2:L3=L2/L4:L6=L5/L7:BOTTOM=L7 |
| PCIE_TX_CAP_N59 | TXC59-DIFF1 | PAIR | 2 | 5.5 | 5 | 10 | 5 | 50 | 6 | 20 | 12 | 12 | 12 | 12 | 7.5 | 85 Ohms | TOP=L2:L3=L2/L4:L6=L5/L7:BOTTOM=L7 |
| PCIE_TX_CAP_N59 | TXC59-DIFF1 | PAIR | 3 | 5.5 | 5 | 10 | 5 | 50 | 6 | 20 | 12 | 12 | 12 | 12 | 7.5 | 85 Ohms | TOP=L2:L3=L2/L4:L6=L5/L7:BOTTOM=L7 |
| PCIE_TX_CAP_N59 | TXC59-DIFF1 | PAIR | 4 | 5.5 | 5 | 10 | 5 | 50 | 6 | 20 | 12 | 12 | 12 | 12 | 7.5 | 85 Ohms | TOP=L2:L3=L2/L4:L6=L5/L7:BOTTOM=L7 |
| PCIE_TX_CAP_N59 | TXC59-DIFF1 | PAIR | 5 | 5.5 | 5 | 10 | 5 | 50 | 6 | 20 | 12 | 12 | 12 | 12 | 7.5 | 85 Ohms | TOP=L2:L3=L2/L4:L6=L5/L7:BOTTOM=L7 |
| PCIE_TX_CAP_N59 | TXC59-DIFF1 | PAIR | 6 | 5.5 | 5 | 10 | 5 | 50 | 6 | 20 | 12 | 12 | 12 | 12 | 7.5 | 85 Ohms | TOP=L2:L3=L2/L4:L6=L5/L7:BOTTOM=L7 |
| PCIE_TX_CAP_N59 | TXC59-DIFF1 | PAIR | 7 | 5.5 | 5 | 10 | 5 | 50 | 6 | 20 | 12 | 12 | 12 | 12 | 7.5 | 85 Ohms | TOP=L2:L3=L2/L4:L6=L5/L7:BOTTOM=L7 |
| PCIE_TX_CAP_N59 | TXC59-DIFF1 | PAIR | 8 | 5.38 | 5 | 10 | 5 | 50 | 6 | 33 | 12 | 12 | 12 | 12 | 6.62 | 85 Ohms | TOP=L2:L3=L2/L4:L6=L5/L7:BOTTOM=L7 |
| PCIE_TX_CAP_P59 | TXC59-DIFF1 | PAIR | 1 | 5.38 | 5 | 10 | 5 | 50 | 6 | 33 | 12 | 12 | 12 | 12 | 6.62 | 85 Ohms | TOP=L2:L3=L2/L4:L6=L5/L7:BOTTOM=L7 |
| PCIE_TX_CAP_P59 | TXC59-DIFF1 | PAIR | 2 | 5.5 | 5 | 10 | 5 | 50 | 6 | 20 | 12 | 12 | 12 | 12 | 7.5 | 85 Ohms | TOP=L2:L3=L2/L4:L6=L5/L7:BOTTOM=L7 |
| PCIE_TX_CAP_P59 | TXC59-DIFF1 | PAIR | 3 | 5.5 | 5 | 10 | 5 | 50 | 6 | 20 | 12 | 12 | 12 | 12 | 7.5 | 85 Ohms | TOP=L2:L3=L2/L4:L6=L5/L7:BOTTOM=L7 |
| PCIE_TX_CAP_P59 | TXC59-DIFF1 | PAIR | 4 | 5.5 | 5 | 10 | 5 | 50 | 6 | 20 | 12 | 12 | 12 | 12 | 7.5 | 85 Ohms | TOP=L2:L3=L2/L4:L6=L5/L7:BOTTOM=L7 |
| PCIE_TX_CAP_P59 | TXC59-DIFF1 | PAIR | 5 | 5.5 | 5 | 10 | 5 | 50 | 6 | 20 | 12 | 12 | 12 | 12 | 7.5 | 85 Ohms | TOP=L2:L3=L2/L4:L6=L5/L7:BOTTOM=L7 |
| PCIE_TX_CAP_P59 | TXC59-DIFF1 | PAIR | 6 | 5.5 | 5 | 10 | 5 | 50 | 6 | 20 | 12 | 12 | 12 | 12 | 7.5 | 85 Ohms | TOP=L2:L3=L2/L4:L6=L5/L7:BOTTOM=L7 |
| PCIE_TX_CAP_P59 | TXC59-DIFF1 | PAIR | 7 | 5.5 | 5 | 10 | 5 | 50 | 6 | 20 | 12 | 12 | 12 | 12 | 7.5 | 85 Ohms | TOP=L2:L3=L2/L4:L6=L5/L7:BOTTOM=L7 |
| PCIE_TX_CAP_P59 | TXC59-DIFF1 | PAIR | 8 | 5.38 | 5 | 10 | 5 | 50 | 6 | 33 | 12 | 12 | 12 | 12 | 6.62 | 85 Ohms | TOP=L2:L3=L2/L4:L6=L5/L7:BOTTOM=L7 |
| PCIE_TX_CAP_N5 | TXC5-DIFF1 | PAIR | 1 | 5.38 | 5 | 10 | 5 | 50 | 6 | 33 | 12 | 12 | 12 | 12 | 6.62 | 85 Ohms | TOP=L2:L3=L2/L4:L6=L5/L7:BOTTOM=L7 |
| PCIE_TX_CAP_N5 | TXC5-DIFF1 | PAIR | 2 | 5.5 | 5 | 10 | 5 | 50 | 6 | 20 | 12 | 12 | 12 | 12 | 7.5 | 85 Ohms | TOP=L2:L3=L2/L4:L6=L5/L7:BOTTOM=L7 |
| PCIE_TX_CAP_N5 | TXC5-DIFF1 | PAIR | 3 | 5.5 | 5 | 10 | 5 | 50 | 6 | 20 | 12 | 12 | 12 | 12 | 7.5 | 85 Ohms | TOP=L2:L3=L2/L4:L6=L5/L7:BOTTOM=L7 |
| PCIE_TX_CAP_N5 | TXC5-DIFF1 | PAIR | 4 | 5.5 | 5 | 10 | 5 | 50 | 6 | 20 | 12 | 12 | 12 | 12 | 7.5 | 85 Ohms | TOP=L2:L3=L2/L4:L6=L5/L7:BOTTOM=L7 |
| PCIE_TX_CAP_N5 | TXC5-DIFF1 | PAIR | 5 | 5.5 | 5 | 10 | 5 | 50 | 6 | 20 | 12 | 12 | 12 | 12 | 7.5 | 85 Ohms | TOP=L2:L3=L2/L4:L6=L5/L7:BOTTOM=L7 |
| PCIE_TX_CAP_N5 | TXC5-DIFF1 | PAIR | 6 | 5.5 | 5 | 10 | 5 | 50 | 6 | 20 | 12 | 12 | 12 | 12 | 7.5 | 85 Ohms | TOP=L2:L3=L2/L4:L6=L5/L7:BOTTOM=L7 |
| PCIE_TX_CAP_N5 | TXC5-DIFF1 | PAIR | 7 | 5.5 | 5 | 10 | 5 | 50 | 6 | 20 | 12 | 12 | 12 | 12 | 7.5 | 85 Ohms | TOP=L2:L3=L2/L4:L6=L5/L7:BOTTOM=L7 |
| PCIE_TX_CAP_N5 | TXC5-DIFF1 | PAIR | 8 | 5.38 | 5 | 10 | 5 | 50 | 6 | 33 | 12 | 12 | 12 | 12 | 6.62 | 85 Ohms | TOP=L2:L3=L2/L4:L6=L5/L7:BOTTOM=L7 |
| PCIE_TX_CAP_P5 | TXC5-DIFF1 | PAIR | 1 | 5.38 | 5 | 10 | 5 | 50 | 6 | 33 | 12 | 12 | 12 | 12 | 6.62 | 85 Ohms | TOP=L2:L3=L2/L4:L6=L5/L7:BOTTOM=L7 |
| PCIE_TX_CAP_P5 | TXC5-DIFF1 | PAIR | 2 | 5.5 | 5 | 10 | 5 | 50 | 6 | 20 | 12 | 12 | 12 | 12 | 7.5 | 85 Ohms | TOP=L2:L3=L2/L4:L6=L5/L7:BOTTOM=L7 |
| PCIE_TX_CAP_P5 | TXC5-DIFF1 | PAIR | 3 | 5.5 | 5 | 10 | 5 | 50 | 6 | 20 | 12 | 12 | 12 | 12 | 7.5 | 85 Ohms | TOP=L2:L3=L2/L4:L6=L5/L7:BOTTOM=L7 |
| PCIE_TX_CAP_P5 | TXC5-DIFF1 | PAIR | 4 | 5.5 | 5 | 10 | 5 | 50 | 6 | 20 | 12 | 12 | 12 | 12 | 7.5 | 85 Ohms | TOP=L2:L3=L2/L4:L6=L5/L7:BOTTOM=L7 |
| PCIE_TX_CAP_P5 | TXC5-DIFF1 | PAIR | 5 | 5.5 | 5 | 10 | 5 | 50 | 6 | 20 | 12 | 12 | 12 | 12 | 7.5 | 85 Ohms | TOP=L2:L3=L2/L4:L6=L5/L7:BOTTOM=L7 |
| PCIE_TX_CAP_P5 | TXC5-DIFF1 | PAIR | 6 | 5.5 | 5 | 10 | 5 | 50 | 6 | 20 | 12 | 12 | 12 | 12 | 7.5 | 85 Ohms | TOP=L2:L3=L2/L4:L6=L5/L7:BOTTOM=L7 |
| PCIE_TX_CAP_P5 | TXC5-DIFF1 | PAIR | 7 | 5.5 | 5 | 10 | 5 | 50 | 6 | 20 | 12 | 12 | 12 | 12 | 7.5 | 85 Ohms | TOP=L2:L3=L2/L4:L6=L5/L7:BOTTOM=L7 |
| PCIE_TX_CAP_P5 | TXC5-DIFF1 | PAIR | 8 | 5.38 | 5 | 10 | 5 | 50 | 6 | 33 | 12 | 12 | 12 | 12 | 6.62 | 85 Ohms | TOP=L2:L3=L2/L4:L6=L5/L7:BOTTOM=L7 |
| PCIE_TX_CAP_N60 | TXC60-DIFF1 | PAIR | 1 | 5.38 | 5 | 10 | 5 | 50 | 6 | 33 | 12 | 12 | 12 | 12 | 6.62 | 85 Ohms | TOP=L2:L3=L2/L4:L6=L5/L7:BOTTOM=L7 |
| PCIE_TX_CAP_N60 | TXC60-DIFF1 | PAIR | 2 | 5.5 | 5 | 10 | 5 | 50 | 6 | 20 | 12 | 12 | 12 | 12 | 7.5 | 85 Ohms | TOP=L2:L3=L2/L4:L6=L5/L7:BOTTOM=L7 |
| PCIE_TX_CAP_N60 | TXC60-DIFF1 | PAIR | 3 | 5.5 | 5 | 10 | 5 | 50 | 6 | 20 | 12 | 12 | 12 | 12 | 7.5 | 85 Ohms | TOP=L2:L3=L2/L4:L6=L5/L7:BOTTOM=L7 |
| PCIE_TX_CAP_N60 | TXC60-DIFF1 | PAIR | 4 | 5.5 | 5 | 10 | 5 | 50 | 6 | 20 | 12 | 12 | 12 | 12 | 7.5 | 85 Ohms | TOP=L2:L3=L2/L4:L6=L5/L7:BOTTOM=L7 |
| PCIE_TX_CAP_N60 | TXC60-DIFF1 | PAIR | 5 | 5.5 | 5 | 10 | 5 | 50 | 6 | 20 | 12 | 12 | 12 | 12 | 7.5 | 85 Ohms | TOP=L2:L3=L2/L4:L6=L5/L7:BOTTOM=L7 |
| PCIE_TX_CAP_N60 | TXC60-DIFF1 | PAIR | 6 | 5.5 | 5 | 10 | 5 | 50 | 6 | 20 | 12 | 12 | 12 | 12 | 7.5 | 85 Ohms | TOP=L2:L3=L2/L4:L6=L5/L7:BOTTOM=L7 |
| PCIE_TX_CAP_N60 | TXC60-DIFF1 | PAIR | 7 | 5.5 | 5 | 10 | 5 | 50 | 6 | 20 | 12 | 12 | 12 | 12 | 7.5 | 85 Ohms | TOP=L2:L3=L2/L4:L6=L5/L7:BOTTOM=L7 |
| PCIE_TX_CAP_N60 | TXC60-DIFF1 | PAIR | 8 | 5.38 | 5 | 10 | 5 | 50 | 6 | 33 | 12 | 12 | 12 | 12 | 6.62 | 85 Ohms | TOP=L2:L3=L2/L4:L6=L5/L7:BOTTOM=L7 |
| PCIE_TX_CAP_P60 | TXC60-DIFF1 | PAIR | 1 | 5.38 | 5 | 10 | 5 | 50 | 6 | 33 | 12 | 12 | 12 | 12 | 6.62 | 85 Ohms | TOP=L2:L3=L2/L4:L6=L5/L7:BOTTOM=L7 |
| PCIE_TX_CAP_P60 | TXC60-DIFF1 | PAIR | 2 | 5.5 | 5 | 10 | 5 | 50 | 6 | 20 | 12 | 12 | 12 | 12 | 7.5 | 85 Ohms | TOP=L2:L3=L2/L4:L6=L5/L7:BOTTOM=L7 |
| PCIE_TX_CAP_P60 | TXC60-DIFF1 | PAIR | 3 | 5.5 | 5 | 10 | 5 | 50 | 6 | 20 | 12 | 12 | 12 | 12 | 7.5 | 85 Ohms | TOP=L2:L3=L2/L4:L6=L5/L7:BOTTOM=L7 |
| PCIE_TX_CAP_P60 | TXC60-DIFF1 | PAIR | 4 | 5.5 | 5 | 10 | 5 | 50 | 6 | 20 | 12 | 12 | 12 | 12 | 7.5 | 85 Ohms | TOP=L2:L3=L2/L4:L6=L5/L7:BOTTOM=L7 |
| PCIE_TX_CAP_P60 | TXC60-DIFF1 | PAIR | 5 | 5.5 | 5 | 10 | 5 | 50 | 6 | 20 | 12 | 12 | 12 | 12 | 7.5 | 85 Ohms | TOP=L2:L3=L2/L4:L6=L5/L7:BOTTOM=L7 |
| PCIE_TX_CAP_P60 | TXC60-DIFF1 | PAIR | 6 | 5.5 | 5 | 10 | 5 | 50 | 6 | 20 | 12 | 12 | 12 | 12 | 7.5 | 85 Ohms | TOP=L2:L3=L2/L4:L6=L5/L7:BOTTOM=L7 |
| PCIE_TX_CAP_P60 | TXC60-DIFF1 | PAIR | 7 | 5.5 | 5 | 10 | 5 | 50 | 6 | 20 | 12 | 12 | 12 | 12 | 7.5 | 85 Ohms | TOP=L2:L3=L2/L4:L6=L5/L7:BOTTOM=L7 |
| PCIE_TX_CAP_P60 | TXC60-DIFF1 | PAIR | 8 | 5.38 | 5 | 10 | 5 | 50 | 6 | 33 | 12 | 12 | 12 | 12 | 6.62 | 85 Ohms | TOP=L2:L3=L2/L4:L6=L5/L7:BOTTOM=L7 |
| PCIE_TX_CAP_N61 | TXC61-DIFF1 | PAIR | 1 | 5.38 | 5 | 10 | 5 | 50 | 6 | 33 | 12 | 12 | 12 | 12 | 6.62 | 85 Ohms | TOP=L2:L3=L2/L4:L6=L5/L7:BOTTOM=L7 |
| PCIE_TX_CAP_N61 | TXC61-DIFF1 | PAIR | 2 | 5.5 | 5 | 10 | 5 | 50 | 6 | 20 | 12 | 12 | 12 | 12 | 7.5 | 85 Ohms | TOP=L2:L3=L2/L4:L6=L5/L7:BOTTOM=L7 |
| PCIE_TX_CAP_N61 | TXC61-DIFF1 | PAIR | 3 | 5.5 | 5 | 10 | 5 | 50 | 6 | 20 | 12 | 12 | 12 | 12 | 7.5 | 85 Ohms | TOP=L2:L3=L2/L4:L6=L5/L7:BOTTOM=L7 |
| PCIE_TX_CAP_N61 | TXC61-DIFF1 | PAIR | 4 | 5.5 | 5 | 10 | 5 | 50 | 6 | 20 | 12 | 12 | 12 | 12 | 7.5 | 85 Ohms | TOP=L2:L3=L2/L4:L6=L5/L7:BOTTOM=L7 |
| PCIE_TX_CAP_N61 | TXC61-DIFF1 | PAIR | 5 | 5.5 | 5 | 10 | 5 | 50 | 6 | 20 | 12 | 12 | 12 | 12 | 7.5 | 85 Ohms | TOP=L2:L3=L2/L4:L6=L5/L7:BOTTOM=L7 |
| PCIE_TX_CAP_N61 | TXC61-DIFF1 | PAIR | 6 | 5.5 | 5 | 10 | 5 | 50 | 6 | 20 | 12 | 12 | 12 | 12 | 7.5 | 85 Ohms | TOP=L2:L3=L2/L4:L6=L5/L7:BOTTOM=L7 |
| PCIE_TX_CAP_N61 | TXC61-DIFF1 | PAIR | 7 | 5.5 | 5 | 10 | 5 | 50 | 6 | 20 | 12 | 12 | 12 | 12 | 7.5 | 85 Ohms | TOP=L2:L3=L2/L4:L6=L5/L7:BOTTOM=L7 |
| PCIE_TX_CAP_N61 | TXC61-DIFF1 | PAIR | 8 | 5.38 | 5 | 10 | 5 | 50 | 6 | 33 | 12 | 12 | 12 | 12 | 6.62 | 85 Ohms | TOP=L2:L3=L2/L4:L6=L5/L7:BOTTOM=L7 |
| PCIE_TX_CAP_P61 | TXC61-DIFF1 | PAIR | 1 | 5.38 | 5 | 10 | 5 | 50 | 6 | 33 | 12 | 12 | 12 | 12 | 6.62 | 85 Ohms | TOP=L2:L3=L2/L4:L6=L5/L7:BOTTOM=L7 |
| PCIE_TX_CAP_P61 | TXC61-DIFF1 | PAIR | 2 | 5.5 | 5 | 10 | 5 | 50 | 6 | 20 | 12 | 12 | 12 | 12 | 7.5 | 85 Ohms | TOP=L2:L3=L2/L4:L6=L5/L7:BOTTOM=L7 |
| PCIE_TX_CAP_P61 | TXC61-DIFF1 | PAIR | 3 | 5.5 | 5 | 10 | 5 | 50 | 6 | 20 | 12 | 12 | 12 | 12 | 7.5 | 85 Ohms | TOP=L2:L3=L2/L4:L6=L5/L7:BOTTOM=L7 |
| PCIE_TX_CAP_P61 | TXC61-DIFF1 | PAIR | 4 | 5.5 | 5 | 10 | 5 | 50 | 6 | 20 | 12 | 12 | 12 | 12 | 7.5 | 85 Ohms | TOP=L2:L3=L2/L4:L6=L5/L7:BOTTOM=L7 |
| PCIE_TX_CAP_P61 | TXC61-DIFF1 | PAIR | 5 | 5.5 | 5 | 10 | 5 | 50 | 6 | 20 | 12 | 12 | 12 | 12 | 7.5 | 85 Ohms | TOP=L2:L3=L2/L4:L6=L5/L7:BOTTOM=L7 |
| PCIE_TX_CAP_P61 | TXC61-DIFF1 | PAIR | 6 | 5.5 | 5 | 10 | 5 | 50 | 6 | 20 | 12 | 12 | 12 | 12 | 7.5 | 85 Ohms | TOP=L2:L3=L2/L4:L6=L5/L7:BOTTOM=L7 |
| PCIE_TX_CAP_P61 | TXC61-DIFF1 | PAIR | 7 | 5.5 | 5 | 10 | 5 | 50 | 6 | 20 | 12 | 12 | 12 | 12 | 7.5 | 85 Ohms | TOP=L2:L3=L2/L4:L6=L5/L7:BOTTOM=L7 |
| PCIE_TX_CAP_P61 | TXC61-DIFF1 | PAIR | 8 | 5.38 | 5 | 10 | 5 | 50 | 6 | 33 | 12 | 12 | 12 | 12 | 6.62 | 85 Ohms | TOP=L2:L3=L2/L4:L6=L5/L7:BOTTOM=L7 |
| PCIE_TX_CAP_N62 | TXC62-DIFF1 | PAIR | 1 | 5.38 | 5 | 10 | 5 | 50 | 6 | 33 | 12 | 12 | 12 | 12 | 6.62 | 85 Ohms | TOP=L2:L3=L2/L4:L6=L5/L7:BOTTOM=L7 |
| PCIE_TX_CAP_N62 | TXC62-DIFF1 | PAIR | 2 | 5.5 | 5 | 10 | 5 | 50 | 6 | 20 | 12 | 12 | 12 | 12 | 7.5 | 85 Ohms | TOP=L2:L3=L2/L4:L6=L5/L7:BOTTOM=L7 |
| PCIE_TX_CAP_N62 | TXC62-DIFF1 | PAIR | 3 | 5.5 | 5 | 10 | 5 | 50 | 6 | 20 | 12 | 12 | 12 | 12 | 7.5 | 85 Ohms | TOP=L2:L3=L2/L4:L6=L5/L7:BOTTOM=L7 |
| PCIE_TX_CAP_N62 | TXC62-DIFF1 | PAIR | 4 | 5.5 | 5 | 10 | 5 | 50 | 6 | 20 | 12 | 12 | 12 | 12 | 7.5 | 85 Ohms | TOP=L2:L3=L2/L4:L6=L5/L7:BOTTOM=L7 |
| PCIE_TX_CAP_N62 | TXC62-DIFF1 | PAIR | 5 | 5.5 | 5 | 10 | 5 | 50 | 6 | 20 | 12 | 12 | 12 | 12 | 7.5 | 85 Ohms | TOP=L2:L3=L2/L4:L6=L5/L7:BOTTOM=L7 |
| PCIE_TX_CAP_N62 | TXC62-DIFF1 | PAIR | 6 | 5.5 | 5 | 10 | 5 | 50 | 6 | 20 | 12 | 12 | 12 | 12 | 7.5 | 85 Ohms | TOP=L2:L3=L2/L4:L6=L5/L7:BOTTOM=L7 |
| PCIE_TX_CAP_N62 | TXC62-DIFF1 | PAIR | 7 | 5.5 | 5 | 10 | 5 | 50 | 6 | 20 | 12 | 12 | 12 | 12 | 7.5 | 85 Ohms | TOP=L2:L3=L2/L4:L6=L5/L7:BOTTOM=L7 |
| PCIE_TX_CAP_N62 | TXC62-DIFF1 | PAIR | 8 | 5.38 | 5 | 10 | 5 | 50 | 6 | 33 | 12 | 12 | 12 | 12 | 6.62 | 85 Ohms | TOP=L2:L3=L2/L4:L6=L5/L7:BOTTOM=L7 |
| PCIE_TX_CAP_P62 | TXC62-DIFF1 | PAIR | 1 | 5.38 | 5 | 10 | 5 | 50 | 6 | 33 | 12 | 12 | 12 | 12 | 6.62 | 85 Ohms | TOP=L2:L3=L2/L4:L6=L5/L7:BOTTOM=L7 |
| PCIE_TX_CAP_P62 | TXC62-DIFF1 | PAIR | 2 | 5.5 | 5 | 10 | 5 | 50 | 6 | 20 | 12 | 12 | 12 | 12 | 7.5 | 85 Ohms | TOP=L2:L3=L2/L4:L6=L5/L7:BOTTOM=L7 |
| PCIE_TX_CAP_P62 | TXC62-DIFF1 | PAIR | 3 | 5.5 | 5 | 10 | 5 | 50 | 6 | 20 | 12 | 12 | 12 | 12 | 7.5 | 85 Ohms | TOP=L2:L3=L2/L4:L6=L5/L7:BOTTOM=L7 |
| PCIE_TX_CAP_P62 | TXC62-DIFF1 | PAIR | 4 | 5.5 | 5 | 10 | 5 | 50 | 6 | 20 | 12 | 12 | 12 | 12 | 7.5 | 85 Ohms | TOP=L2:L3=L2/L4:L6=L5/L7:BOTTOM=L7 |
| PCIE_TX_CAP_P62 | TXC62-DIFF1 | PAIR | 5 | 5.5 | 5 | 10 | 5 | 50 | 6 | 20 | 12 | 12 | 12 | 12 | 7.5 | 85 Ohms | TOP=L2:L3=L2/L4:L6=L5/L7:BOTTOM=L7 |
| PCIE_TX_CAP_P62 | TXC62-DIFF1 | PAIR | 6 | 5.5 | 5 | 10 | 5 | 50 | 6 | 20 | 12 | 12 | 12 | 12 | 7.5 | 85 Ohms | TOP=L2:L3=L2/L4:L6=L5/L7:BOTTOM=L7 |
| PCIE_TX_CAP_P62 | TXC62-DIFF1 | PAIR | 7 | 5.5 | 5 | 10 | 5 | 50 | 6 | 20 | 12 | 12 | 12 | 12 | 7.5 | 85 Ohms | TOP=L2:L3=L2/L4:L6=L5/L7:BOTTOM=L7 |
| PCIE_TX_CAP_P62 | TXC62-DIFF1 | PAIR | 8 | 5.38 | 5 | 10 | 5 | 50 | 6 | 33 | 12 | 12 | 12 | 12 | 6.62 | 85 Ohms | TOP=L2:L3=L2/L4:L6=L5/L7:BOTTOM=L7 |
| PCIE_TX_CAP_N63 | TXC63-DIFF1 | PAIR | 1 | 5.38 | 5 | 10 | 5 | 50 | 6 | 33 | 12 | 12 | 12 | 12 | 6.62 | 85 Ohms | TOP=L2:L3=L2/L4:L6=L5/L7:BOTTOM=L7 |
| PCIE_TX_CAP_N63 | TXC63-DIFF1 | PAIR | 2 | 5.5 | 5 | 10 | 5 | 50 | 6 | 20 | 12 | 12 | 12 | 12 | 7.5 | 85 Ohms | TOP=L2:L3=L2/L4:L6=L5/L7:BOTTOM=L7 |
| PCIE_TX_CAP_N63 | TXC63-DIFF1 | PAIR | 3 | 5.5 | 5 | 10 | 5 | 50 | 6 | 20 | 12 | 12 | 12 | 12 | 7.5 | 85 Ohms | TOP=L2:L3=L2/L4:L6=L5/L7:BOTTOM=L7 |
| PCIE_TX_CAP_N63 | TXC63-DIFF1 | PAIR | 4 | 5.5 | 5 | 10 | 5 | 50 | 6 | 20 | 12 | 12 | 12 | 12 | 7.5 | 85 Ohms | TOP=L2:L3=L2/L4:L6=L5/L7:BOTTOM=L7 |
| PCIE_TX_CAP_N63 | TXC63-DIFF1 | PAIR | 5 | 5.5 | 5 | 10 | 5 | 50 | 6 | 20 | 12 | 12 | 12 | 12 | 7.5 | 85 Ohms | TOP=L2:L3=L2/L4:L6=L5/L7:BOTTOM=L7 |
| PCIE_TX_CAP_N63 | TXC63-DIFF1 | PAIR | 6 | 5.5 | 5 | 10 | 5 | 50 | 6 | 20 | 12 | 12 | 12 | 12 | 7.5 | 85 Ohms | TOP=L2:L3=L2/L4:L6=L5/L7:BOTTOM=L7 |
| PCIE_TX_CAP_N63 | TXC63-DIFF1 | PAIR | 7 | 5.5 | 5 | 10 | 5 | 50 | 6 | 20 | 12 | 12 | 12 | 12 | 7.5 | 85 Ohms | TOP=L2:L3=L2/L4:L6=L5/L7:BOTTOM=L7 |
| PCIE_TX_CAP_N63 | TXC63-DIFF1 | PAIR | 8 | 5.38 | 5 | 10 | 5 | 50 | 6 | 33 | 12 | 12 | 12 | 12 | 6.62 | 85 Ohms | TOP=L2:L3=L2/L4:L6=L5/L7:BOTTOM=L7 |
| PCIE_TX_CAP_P63 | TXC63-DIFF1 | PAIR | 1 | 5.38 | 5 | 10 | 5 | 50 | 6 | 33 | 12 | 12 | 12 | 12 | 6.62 | 85 Ohms | TOP=L2:L3=L2/L4:L6=L5/L7:BOTTOM=L7 |
| PCIE_TX_CAP_P63 | TXC63-DIFF1 | PAIR | 2 | 5.5 | 5 | 10 | 5 | 50 | 6 | 20 | 12 | 12 | 12 | 12 | 7.5 | 85 Ohms | TOP=L2:L3=L2/L4:L6=L5/L7:BOTTOM=L7 |
| PCIE_TX_CAP_P63 | TXC63-DIFF1 | PAIR | 3 | 5.5 | 5 | 10 | 5 | 50 | 6 | 20 | 12 | 12 | 12 | 12 | 7.5 | 85 Ohms | TOP=L2:L3=L2/L4:L6=L5/L7:BOTTOM=L7 |
| PCIE_TX_CAP_P63 | TXC63-DIFF1 | PAIR | 4 | 5.5 | 5 | 10 | 5 | 50 | 6 | 20 | 12 | 12 | 12 | 12 | 7.5 | 85 Ohms | TOP=L2:L3=L2/L4:L6=L5/L7:BOTTOM=L7 |
| PCIE_TX_CAP_P63 | TXC63-DIFF1 | PAIR | 5 | 5.5 | 5 | 10 | 5 | 50 | 6 | 20 | 12 | 12 | 12 | 12 | 7.5 | 85 Ohms | TOP=L2:L3=L2/L4:L6=L5/L7:BOTTOM=L7 |
| PCIE_TX_CAP_P63 | TXC63-DIFF1 | PAIR | 6 | 5.5 | 5 | 10 | 5 | 50 | 6 | 20 | 12 | 12 | 12 | 12 | 7.5 | 85 Ohms | TOP=L2:L3=L2/L4:L6=L5/L7:BOTTOM=L7 |
| PCIE_TX_CAP_P63 | TXC63-DIFF1 | PAIR | 7 | 5.5 | 5 | 10 | 5 | 50 | 6 | 20 | 12 | 12 | 12 | 12 | 7.5 | 85 Ohms | TOP=L2:L3=L2/L4:L6=L5/L7:BOTTOM=L7 |
| PCIE_TX_CAP_P63 | TXC63-DIFF1 | PAIR | 8 | 5.38 | 5 | 10 | 5 | 50 | 6 | 33 | 12 | 12 | 12 | 12 | 6.62 | 85 Ohms | TOP=L2:L3=L2/L4:L6=L5/L7:BOTTOM=L7 |
| PCIE_TX_CAP_N64 | TXC64-DIFF1 | PAIR | 1 | 5.38 | 5 | 10 | 5 | 50 | 6 | 33 | 12 | 12 | 12 | 12 | 6.62 | 85 Ohms | TOP=L2:L3=L2/L4:L6=L5/L7:BOTTOM=L7 |
| PCIE_TX_CAP_N64 | TXC64-DIFF1 | PAIR | 2 | 5.5 | 5 | 10 | 5 | 50 | 6 | 20 | 12 | 12 | 12 | 12 | 7.5 | 85 Ohms | TOP=L2:L3=L2/L4:L6=L5/L7:BOTTOM=L7 |
| PCIE_TX_CAP_N64 | TXC64-DIFF1 | PAIR | 3 | 5.5 | 5 | 10 | 5 | 50 | 6 | 20 | 12 | 12 | 12 | 12 | 7.5 | 85 Ohms | TOP=L2:L3=L2/L4:L6=L5/L7:BOTTOM=L7 |
| PCIE_TX_CAP_N64 | TXC64-DIFF1 | PAIR | 4 | 5.5 | 5 | 10 | 5 | 50 | 6 | 20 | 12 | 12 | 12 | 12 | 7.5 | 85 Ohms | TOP=L2:L3=L2/L4:L6=L5/L7:BOTTOM=L7 |
| PCIE_TX_CAP_N64 | TXC64-DIFF1 | PAIR | 5 | 5.5 | 5 | 10 | 5 | 50 | 6 | 20 | 12 | 12 | 12 | 12 | 7.5 | 85 Ohms | TOP=L2:L3=L2/L4:L6=L5/L7:BOTTOM=L7 |
| PCIE_TX_CAP_N64 | TXC64-DIFF1 | PAIR | 6 | 5.5 | 5 | 10 | 5 | 50 | 6 | 20 | 12 | 12 | 12 | 12 | 7.5 | 85 Ohms | TOP=L2:L3=L2/L4:L6=L5/L7:BOTTOM=L7 |
| PCIE_TX_CAP_N64 | TXC64-DIFF1 | PAIR | 7 | 5.5 | 5 | 10 | 5 | 50 | 6 | 20 | 12 | 12 | 12 | 12 | 7.5 | 85 Ohms | TOP=L2:L3=L2/L4:L6=L5/L7:BOTTOM=L7 |
| PCIE_TX_CAP_N64 | TXC64-DIFF1 | PAIR | 8 | 5.38 | 5 | 10 | 5 | 50 | 6 | 33 | 12 | 12 | 12 | 12 | 6.62 | 85 Ohms | TOP=L2:L3=L2/L4:L6=L5/L7:BOTTOM=L7 |
| PCIE_TX_CAP_P64 | TXC64-DIFF1 | PAIR | 1 | 5.38 | 5 | 10 | 5 | 50 | 6 | 33 | 12 | 12 | 12 | 12 | 6.62 | 85 Ohms | TOP=L2:L3=L2/L4:L6=L5/L7:BOTTOM=L7 |
| PCIE_TX_CAP_P64 | TXC64-DIFF1 | PAIR | 2 | 5.5 | 5 | 10 | 5 | 50 | 6 | 20 | 12 | 12 | 12 | 12 | 7.5 | 85 Ohms | TOP=L2:L3=L2/L4:L6=L5/L7:BOTTOM=L7 |
| PCIE_TX_CAP_P64 | TXC64-DIFF1 | PAIR | 3 | 5.5 | 5 | 10 | 5 | 50 | 6 | 20 | 12 | 12 | 12 | 12 | 7.5 | 85 Ohms | TOP=L2:L3=L2/L4:L6=L5/L7:BOTTOM=L7 |
| PCIE_TX_CAP_P64 | TXC64-DIFF1 | PAIR | 4 | 5.5 | 5 | 10 | 5 | 50 | 6 | 20 | 12 | 12 | 12 | 12 | 7.5 | 85 Ohms | TOP=L2:L3=L2/L4:L6=L5/L7:BOTTOM=L7 |
| PCIE_TX_CAP_P64 | TXC64-DIFF1 | PAIR | 5 | 5.5 | 5 | 10 | 5 | 50 | 6 | 20 | 12 | 12 | 12 | 12 | 7.5 | 85 Ohms | TOP=L2:L3=L2/L4:L6=L5/L7:BOTTOM=L7 |
| PCIE_TX_CAP_P64 | TXC64-DIFF1 | PAIR | 6 | 5.5 | 5 | 10 | 5 | 50 | 6 | 20 | 12 | 12 | 12 | 12 | 7.5 | 85 Ohms | TOP=L2:L3=L2/L4:L6=L5/L7:BOTTOM=L7 |
| PCIE_TX_CAP_P64 | TXC64-DIFF1 | PAIR | 7 | 5.5 | 5 | 10 | 5 | 50 | 6 | 20 | 12 | 12 | 12 | 12 | 7.5 | 85 Ohms | TOP=L2:L3=L2/L4:L6=L5/L7:BOTTOM=L7 |
| PCIE_TX_CAP_P64 | TXC64-DIFF1 | PAIR | 8 | 5.38 | 5 | 10 | 5 | 50 | 6 | 33 | 12 | 12 | 12 | 12 | 6.62 | 85 Ohms | TOP=L2:L3=L2/L4:L6=L5/L7:BOTTOM=L7 |
| PCIE_TX_CAP_N65 | TXC65-DIFF1 | PAIR | 1 | 5.38 | 5 | 10 | 5 | 50 | 6 | 33 | 12 | 12 | 12 | 12 | 6.62 | 85 Ohms | TOP=L2:L3=L2/L4:L6=L5/L7:BOTTOM=L7 |
| PCIE_TX_CAP_N65 | TXC65-DIFF1 | PAIR | 2 | 5.5 | 5 | 10 | 5 | 50 | 6 | 20 | 12 | 12 | 12 | 12 | 7.5 | 85 Ohms | TOP=L2:L3=L2/L4:L6=L5/L7:BOTTOM=L7 |
| PCIE_TX_CAP_N65 | TXC65-DIFF1 | PAIR | 3 | 5.5 | 5 | 10 | 5 | 50 | 6 | 20 | 12 | 12 | 12 | 12 | 7.5 | 85 Ohms | TOP=L2:L3=L2/L4:L6=L5/L7:BOTTOM=L7 |
| PCIE_TX_CAP_N65 | TXC65-DIFF1 | PAIR | 4 | 5.5 | 5 | 10 | 5 | 50 | 6 | 20 | 12 | 12 | 12 | 12 | 7.5 | 85 Ohms | TOP=L2:L3=L2/L4:L6=L5/L7:BOTTOM=L7 |
| PCIE_TX_CAP_N65 | TXC65-DIFF1 | PAIR | 5 | 5.5 | 5 | 10 | 5 | 50 | 6 | 20 | 12 | 12 | 12 | 12 | 7.5 | 85 Ohms | TOP=L2:L3=L2/L4:L6=L5/L7:BOTTOM=L7 |
| PCIE_TX_CAP_N65 | TXC65-DIFF1 | PAIR | 6 | 5.5 | 5 | 10 | 5 | 50 | 6 | 20 | 12 | 12 | 12 | 12 | 7.5 | 85 Ohms | TOP=L2:L3=L2/L4:L6=L5/L7:BOTTOM=L7 |
| PCIE_TX_CAP_N65 | TXC65-DIFF1 | PAIR | 7 | 5.5 | 5 | 10 | 5 | 50 | 6 | 20 | 12 | 12 | 12 | 12 | 7.5 | 85 Ohms | TOP=L2:L3=L2/L4:L6=L5/L7:BOTTOM=L7 |
| PCIE_TX_CAP_N65 | TXC65-DIFF1 | PAIR | 8 | 5.38 | 5 | 10 | 5 | 50 | 6 | 33 | 12 | 12 | 12 | 12 | 6.62 | 85 Ohms | TOP=L2:L3=L2/L4:L6=L5/L7:BOTTOM=L7 |
| PCIE_TX_CAP_P65 | TXC65-DIFF1 | PAIR | 1 | 5.38 | 5 | 10 | 5 | 50 | 6 | 33 | 12 | 12 | 12 | 12 | 6.62 | 85 Ohms | TOP=L2:L3=L2/L4:L6=L5/L7:BOTTOM=L7 |
| PCIE_TX_CAP_P65 | TXC65-DIFF1 | PAIR | 2 | 5.5 | 5 | 10 | 5 | 50 | 6 | 20 | 12 | 12 | 12 | 12 | 7.5 | 85 Ohms | TOP=L2:L3=L2/L4:L6=L5/L7:BOTTOM=L7 |
| PCIE_TX_CAP_P65 | TXC65-DIFF1 | PAIR | 3 | 5.5 | 5 | 10 | 5 | 50 | 6 | 20 | 12 | 12 | 12 | 12 | 7.5 | 85 Ohms | TOP=L2:L3=L2/L4:L6=L5/L7:BOTTOM=L7 |
| PCIE_TX_CAP_P65 | TXC65-DIFF1 | PAIR | 4 | 5.5 | 5 | 10 | 5 | 50 | 6 | 20 | 12 | 12 | 12 | 12 | 7.5 | 85 Ohms | TOP=L2:L3=L2/L4:L6=L5/L7:BOTTOM=L7 |
| PCIE_TX_CAP_P65 | TXC65-DIFF1 | PAIR | 5 | 5.5 | 5 | 10 | 5 | 50 | 6 | 20 | 12 | 12 | 12 | 12 | 7.5 | 85 Ohms | TOP=L2:L3=L2/L4:L6=L5/L7:BOTTOM=L7 |
| PCIE_TX_CAP_P65 | TXC65-DIFF1 | PAIR | 6 | 5.5 | 5 | 10 | 5 | 50 | 6 | 20 | 12 | 12 | 12 | 12 | 7.5 | 85 Ohms | TOP=L2:L3=L2/L4:L6=L5/L7:BOTTOM=L7 |
| PCIE_TX_CAP_P65 | TXC65-DIFF1 | PAIR | 7 | 5.5 | 5 | 10 | 5 | 50 | 6 | 20 | 12 | 12 | 12 | 12 | 7.5 | 85 Ohms | TOP=L2:L3=L2/L4:L6=L5/L7:BOTTOM=L7 |
| PCIE_TX_CAP_P65 | TXC65-DIFF1 | PAIR | 8 | 5.38 | 5 | 10 | 5 | 50 | 6 | 33 | 12 | 12 | 12 | 12 | 6.62 | 85 Ohms | TOP=L2:L3=L2/L4:L6=L5/L7:BOTTOM=L7 |
| PCIE_TX_CAP_N66 | TXC66-DIFF1 | PAIR | 1 | 5.38 | 5 | 10 | 5 | 50 | 6 | 33 | 12 | 12 | 12 | 12 | 6.62 | 85 Ohms | TOP=L2:L3=L2/L4:L6=L5/L7:BOTTOM=L7 |
| PCIE_TX_CAP_N66 | TXC66-DIFF1 | PAIR | 2 | 5.5 | 5 | 10 | 5 | 50 | 6 | 20 | 12 | 12 | 12 | 12 | 7.5 | 85 Ohms | TOP=L2:L3=L2/L4:L6=L5/L7:BOTTOM=L7 |
| PCIE_TX_CAP_N66 | TXC66-DIFF1 | PAIR | 3 | 5.5 | 5 | 10 | 5 | 50 | 6 | 20 | 12 | 12 | 12 | 12 | 7.5 | 85 Ohms | TOP=L2:L3=L2/L4:L6=L5/L7:BOTTOM=L7 |
| PCIE_TX_CAP_N66 | TXC66-DIFF1 | PAIR | 4 | 5.5 | 5 | 10 | 5 | 50 | 6 | 20 | 12 | 12 | 12 | 12 | 7.5 | 85 Ohms | TOP=L2:L3=L2/L4:L6=L5/L7:BOTTOM=L7 |
| PCIE_TX_CAP_N66 | TXC66-DIFF1 | PAIR | 5 | 5.5 | 5 | 10 | 5 | 50 | 6 | 20 | 12 | 12 | 12 | 12 | 7.5 | 85 Ohms | TOP=L2:L3=L2/L4:L6=L5/L7:BOTTOM=L7 |
| PCIE_TX_CAP_N66 | TXC66-DIFF1 | PAIR | 6 | 5.5 | 5 | 10 | 5 | 50 | 6 | 20 | 12 | 12 | 12 | 12 | 7.5 | 85 Ohms | TOP=L2:L3=L2/L4:L6=L5/L7:BOTTOM=L7 |
| PCIE_TX_CAP_N66 | TXC66-DIFF1 | PAIR | 7 | 5.5 | 5 | 10 | 5 | 50 | 6 | 20 | 12 | 12 | 12 | 12 | 7.5 | 85 Ohms | TOP=L2:L3=L2/L4:L6=L5/L7:BOTTOM=L7 |
| PCIE_TX_CAP_N66 | TXC66-DIFF1 | PAIR | 8 | 5.38 | 5 | 10 | 5 | 50 | 6 | 33 | 12 | 12 | 12 | 12 | 6.62 | 85 Ohms | TOP=L2:L3=L2/L4:L6=L5/L7:BOTTOM=L7 |
| PCIE_TX_CAP_P66 | TXC66-DIFF1 | PAIR | 1 | 5.38 | 5 | 10 | 5 | 50 | 6 | 33 | 12 | 12 | 12 | 12 | 6.62 | 85 Ohms | TOP=L2:L3=L2/L4:L6=L5/L7:BOTTOM=L7 |
| PCIE_TX_CAP_P66 | TXC66-DIFF1 | PAIR | 2 | 5.5 | 5 | 10 | 5 | 50 | 6 | 20 | 12 | 12 | 12 | 12 | 7.5 | 85 Ohms | TOP=L2:L3=L2/L4:L6=L5/L7:BOTTOM=L7 |
| PCIE_TX_CAP_P66 | TXC66-DIFF1 | PAIR | 3 | 5.5 | 5 | 10 | 5 | 50 | 6 | 20 | 12 | 12 | 12 | 12 | 7.5 | 85 Ohms | TOP=L2:L3=L2/L4:L6=L5/L7:BOTTOM=L7 |
| PCIE_TX_CAP_P66 | TXC66-DIFF1 | PAIR | 4 | 5.5 | 5 | 10 | 5 | 50 | 6 | 20 | 12 | 12 | 12 | 12 | 7.5 | 85 Ohms | TOP=L2:L3=L2/L4:L6=L5/L7:BOTTOM=L7 |
| PCIE_TX_CAP_P66 | TXC66-DIFF1 | PAIR | 5 | 5.5 | 5 | 10 | 5 | 50 | 6 | 20 | 12 | 12 | 12 | 12 | 7.5 | 85 Ohms | TOP=L2:L3=L2/L4:L6=L5/L7:BOTTOM=L7 |
| PCIE_TX_CAP_P66 | TXC66-DIFF1 | PAIR | 6 | 5.5 | 5 | 10 | 5 | 50 | 6 | 20 | 12 | 12 | 12 | 12 | 7.5 | 85 Ohms | TOP=L2:L3=L2/L4:L6=L5/L7:BOTTOM=L7 |
| PCIE_TX_CAP_P66 | TXC66-DIFF1 | PAIR | 7 | 5.5 | 5 | 10 | 5 | 50 | 6 | 20 | 12 | 12 | 12 | 12 | 7.5 | 85 Ohms | TOP=L2:L3=L2/L4:L6=L5/L7:BOTTOM=L7 |
| PCIE_TX_CAP_P66 | TXC66-DIFF1 | PAIR | 8 | 5.38 | 5 | 10 | 5 | 50 | 6 | 33 | 12 | 12 | 12 | 12 | 6.62 | 85 Ohms | TOP=L2:L3=L2/L4:L6=L5/L7:BOTTOM=L7 |
| PCIE_TX_CAP_N67 | TXC67-DIFF1 | PAIR | 1 | 5.38 | 5 | 10 | 5 | 50 | 6 | 33 | 12 | 12 | 12 | 12 | 6.62 | 85 Ohms | TOP=L2:L3=L2/L4:L6=L5/L7:BOTTOM=L7 |
| PCIE_TX_CAP_N67 | TXC67-DIFF1 | PAIR | 2 | 5.5 | 5 | 10 | 5 | 50 | 6 | 20 | 12 | 12 | 12 | 12 | 7.5 | 85 Ohms | TOP=L2:L3=L2/L4:L6=L5/L7:BOTTOM=L7 |
| PCIE_TX_CAP_N67 | TXC67-DIFF1 | PAIR | 3 | 5.5 | 5 | 10 | 5 | 50 | 6 | 20 | 12 | 12 | 12 | 12 | 7.5 | 85 Ohms | TOP=L2:L3=L2/L4:L6=L5/L7:BOTTOM=L7 |
| PCIE_TX_CAP_N67 | TXC67-DIFF1 | PAIR | 4 | 5.5 | 5 | 10 | 5 | 50 | 6 | 20 | 12 | 12 | 12 | 12 | 7.5 | 85 Ohms | TOP=L2:L3=L2/L4:L6=L5/L7:BOTTOM=L7 |
| PCIE_TX_CAP_N67 | TXC67-DIFF1 | PAIR | 5 | 5.5 | 5 | 10 | 5 | 50 | 6 | 20 | 12 | 12 | 12 | 12 | 7.5 | 85 Ohms | TOP=L2:L3=L2/L4:L6=L5/L7:BOTTOM=L7 |
| PCIE_TX_CAP_N67 | TXC67-DIFF1 | PAIR | 6 | 5.5 | 5 | 10 | 5 | 50 | 6 | 20 | 12 | 12 | 12 | 12 | 7.5 | 85 Ohms | TOP=L2:L3=L2/L4:L6=L5/L7:BOTTOM=L7 |
| PCIE_TX_CAP_N67 | TXC67-DIFF1 | PAIR | 7 | 5.5 | 5 | 10 | 5 | 50 | 6 | 20 | 12 | 12 | 12 | 12 | 7.5 | 85 Ohms | TOP=L2:L3=L2/L4:L6=L5/L7:BOTTOM=L7 |
| PCIE_TX_CAP_N67 | TXC67-DIFF1 | PAIR | 8 | 5.38 | 5 | 10 | 5 | 50 | 6 | 33 | 12 | 12 | 12 | 12 | 6.62 | 85 Ohms | TOP=L2:L3=L2/L4:L6=L5/L7:BOTTOM=L7 |
| PCIE_TX_CAP_P67 | TXC67-DIFF1 | PAIR | 1 | 5.38 | 5 | 10 | 5 | 50 | 6 | 33 | 12 | 12 | 12 | 12 | 6.62 | 85 Ohms | TOP=L2:L3=L2/L4:L6=L5/L7:BOTTOM=L7 |
| PCIE_TX_CAP_P67 | TXC67-DIFF1 | PAIR | 2 | 5.5 | 5 | 10 | 5 | 50 | 6 | 20 | 12 | 12 | 12 | 12 | 7.5 | 85 Ohms | TOP=L2:L3=L2/L4:L6=L5/L7:BOTTOM=L7 |
| PCIE_TX_CAP_P67 | TXC67-DIFF1 | PAIR | 3 | 5.5 | 5 | 10 | 5 | 50 | 6 | 20 | 12 | 12 | 12 | 12 | 7.5 | 85 Ohms | TOP=L2:L3=L2/L4:L6=L5/L7:BOTTOM=L7 |
| PCIE_TX_CAP_P67 | TXC67-DIFF1 | PAIR | 4 | 5.5 | 5 | 10 | 5 | 50 | 6 | 20 | 12 | 12 | 12 | 12 | 7.5 | 85 Ohms | TOP=L2:L3=L2/L4:L6=L5/L7:BOTTOM=L7 |
| PCIE_TX_CAP_P67 | TXC67-DIFF1 | PAIR | 5 | 5.5 | 5 | 10 | 5 | 50 | 6 | 20 | 12 | 12 | 12 | 12 | 7.5 | 85 Ohms | TOP=L2:L3=L2/L4:L6=L5/L7:BOTTOM=L7 |
| PCIE_TX_CAP_P67 | TXC67-DIFF1 | PAIR | 6 | 5.5 | 5 | 10 | 5 | 50 | 6 | 20 | 12 | 12 | 12 | 12 | 7.5 | 85 Ohms | TOP=L2:L3=L2/L4:L6=L5/L7:BOTTOM=L7 |
| PCIE_TX_CAP_P67 | TXC67-DIFF1 | PAIR | 7 | 5.5 | 5 | 10 | 5 | 50 | 6 | 20 | 12 | 12 | 12 | 12 | 7.5 | 85 Ohms | TOP=L2:L3=L2/L4:L6=L5/L7:BOTTOM=L7 |
| PCIE_TX_CAP_P67 | TXC67-DIFF1 | PAIR | 8 | 5.38 | 5 | 10 | 5 | 50 | 6 | 33 | 12 | 12 | 12 | 12 | 6.62 | 85 Ohms | TOP=L2:L3=L2/L4:L6=L5/L7:BOTTOM=L7 |
| PCIE_TX_CAP_N68 | TXC68-DIFF1 | PAIR | 1 | 5.38 | 5 | 10 | 5 | 50 | 6 | 33 | 12 | 12 | 12 | 12 | 6.62 | 85 Ohms | TOP=L2:L3=L2/L4:L6=L5/L7:BOTTOM=L7 |
| PCIE_TX_CAP_N68 | TXC68-DIFF1 | PAIR | 2 | 5.5 | 5 | 10 | 5 | 50 | 6 | 20 | 12 | 12 | 12 | 12 | 7.5 | 85 Ohms | TOP=L2:L3=L2/L4:L6=L5/L7:BOTTOM=L7 |
| PCIE_TX_CAP_N68 | TXC68-DIFF1 | PAIR | 3 | 5.5 | 5 | 10 | 5 | 50 | 6 | 20 | 12 | 12 | 12 | 12 | 7.5 | 85 Ohms | TOP=L2:L3=L2/L4:L6=L5/L7:BOTTOM=L7 |
| PCIE_TX_CAP_N68 | TXC68-DIFF1 | PAIR | 4 | 5.5 | 5 | 10 | 5 | 50 | 6 | 20 | 12 | 12 | 12 | 12 | 7.5 | 85 Ohms | TOP=L2:L3=L2/L4:L6=L5/L7:BOTTOM=L7 |
| PCIE_TX_CAP_N68 | TXC68-DIFF1 | PAIR | 5 | 5.5 | 5 | 10 | 5 | 50 | 6 | 20 | 12 | 12 | 12 | 12 | 7.5 | 85 Ohms | TOP=L2:L3=L2/L4:L6=L5/L7:BOTTOM=L7 |
| PCIE_TX_CAP_N68 | TXC68-DIFF1 | PAIR | 6 | 5.5 | 5 | 10 | 5 | 50 | 6 | 20 | 12 | 12 | 12 | 12 | 7.5 | 85 Ohms | TOP=L2:L3=L2/L4:L6=L5/L7:BOTTOM=L7 |
| PCIE_TX_CAP_N68 | TXC68-DIFF1 | PAIR | 7 | 5.5 | 5 | 10 | 5 | 50 | 6 | 20 | 12 | 12 | 12 | 12 | 7.5 | 85 Ohms | TOP=L2:L3=L2/L4:L6=L5/L7:BOTTOM=L7 |
| PCIE_TX_CAP_N68 | TXC68-DIFF1 | PAIR | 8 | 5.38 | 5 | 10 | 5 | 50 | 6 | 33 | 12 | 12 | 12 | 12 | 6.62 | 85 Ohms | TOP=L2:L3=L2/L4:L6=L5/L7:BOTTOM=L7 |
| PCIE_TX_CAP_P68 | TXC68-DIFF1 | PAIR | 1 | 5.38 | 5 | 10 | 5 | 50 | 6 | 33 | 12 | 12 | 12 | 12 | 6.62 | 85 Ohms | TOP=L2:L3=L2/L4:L6=L5/L7:BOTTOM=L7 |
| PCIE_TX_CAP_P68 | TXC68-DIFF1 | PAIR | 2 | 5.5 | 5 | 10 | 5 | 50 | 6 | 20 | 12 | 12 | 12 | 12 | 7.5 | 85 Ohms | TOP=L2:L3=L2/L4:L6=L5/L7:BOTTOM=L7 |
| PCIE_TX_CAP_P68 | TXC68-DIFF1 | PAIR | 3 | 5.5 | 5 | 10 | 5 | 50 | 6 | 20 | 12 | 12 | 12 | 12 | 7.5 | 85 Ohms | TOP=L2:L3=L2/L4:L6=L5/L7:BOTTOM=L7 |
| PCIE_TX_CAP_P68 | TXC68-DIFF1 | PAIR | 4 | 5.5 | 5 | 10 | 5 | 50 | 6 | 20 | 12 | 12 | 12 | 12 | 7.5 | 85 Ohms | TOP=L2:L3=L2/L4:L6=L5/L7:BOTTOM=L7 |
| PCIE_TX_CAP_P68 | TXC68-DIFF1 | PAIR | 5 | 5.5 | 5 | 10 | 5 | 50 | 6 | 20 | 12 | 12 | 12 | 12 | 7.5 | 85 Ohms | TOP=L2:L3=L2/L4:L6=L5/L7:BOTTOM=L7 |
| PCIE_TX_CAP_P68 | TXC68-DIFF1 | PAIR | 6 | 5.5 | 5 | 10 | 5 | 50 | 6 | 20 | 12 | 12 | 12 | 12 | 7.5 | 85 Ohms | TOP=L2:L3=L2/L4:L6=L5/L7:BOTTOM=L7 |
| PCIE_TX_CAP_P68 | TXC68-DIFF1 | PAIR | 7 | 5.5 | 5 | 10 | 5 | 50 | 6 | 20 | 12 | 12 | 12 | 12 | 7.5 | 85 Ohms | TOP=L2:L3=L2/L4:L6=L5/L7:BOTTOM=L7 |
| PCIE_TX_CAP_P68 | TXC68-DIFF1 | PAIR | 8 | 5.38 | 5 | 10 | 5 | 50 | 6 | 33 | 12 | 12 | 12 | 12 | 6.62 | 85 Ohms | TOP=L2:L3=L2/L4:L6=L5/L7:BOTTOM=L7 |
| PCIE_TX_CAP_N69 | TXC69-DIFF1 | PAIR | 1 | 5.38 | 5 | 10 | 5 | 50 | 6 | 33 | 12 | 12 | 12 | 12 | 6.62 | 85 Ohms | TOP=L2:L3=L2/L4:L6=L5/L7:BOTTOM=L7 |
| PCIE_TX_CAP_N69 | TXC69-DIFF1 | PAIR | 2 | 5.5 | 5 | 10 | 5 | 50 | 6 | 20 | 12 | 12 | 12 | 12 | 7.5 | 85 Ohms | TOP=L2:L3=L2/L4:L6=L5/L7:BOTTOM=L7 |
| PCIE_TX_CAP_N69 | TXC69-DIFF1 | PAIR | 3 | 5.5 | 5 | 10 | 5 | 50 | 6 | 20 | 12 | 12 | 12 | 12 | 7.5 | 85 Ohms | TOP=L2:L3=L2/L4:L6=L5/L7:BOTTOM=L7 |
| PCIE_TX_CAP_N69 | TXC69-DIFF1 | PAIR | 4 | 5.5 | 5 | 10 | 5 | 50 | 6 | 20 | 12 | 12 | 12 | 12 | 7.5 | 85 Ohms | TOP=L2:L3=L2/L4:L6=L5/L7:BOTTOM=L7 |
| PCIE_TX_CAP_N69 | TXC69-DIFF1 | PAIR | 5 | 5.5 | 5 | 10 | 5 | 50 | 6 | 20 | 12 | 12 | 12 | 12 | 7.5 | 85 Ohms | TOP=L2:L3=L2/L4:L6=L5/L7:BOTTOM=L7 |
| PCIE_TX_CAP_N69 | TXC69-DIFF1 | PAIR | 6 | 5.5 | 5 | 10 | 5 | 50 | 6 | 20 | 12 | 12 | 12 | 12 | 7.5 | 85 Ohms | TOP=L2:L3=L2/L4:L6=L5/L7:BOTTOM=L7 |
| PCIE_TX_CAP_N69 | TXC69-DIFF1 | PAIR | 7 | 5.5 | 5 | 10 | 5 | 50 | 6 | 20 | 12 | 12 | 12 | 12 | 7.5 | 85 Ohms | TOP=L2:L3=L2/L4:L6=L5/L7:BOTTOM=L7 |
| PCIE_TX_CAP_N69 | TXC69-DIFF1 | PAIR | 8 | 5.38 | 5 | 10 | 5 | 50 | 6 | 33 | 12 | 12 | 12 | 12 | 6.62 | 85 Ohms | TOP=L2:L3=L2/L4:L6=L5/L7:BOTTOM=L7 |
| PCIE_TX_CAP_P69 | TXC69-DIFF1 | PAIR | 1 | 5.38 | 5 | 10 | 5 | 50 | 6 | 33 | 12 | 12 | 12 | 12 | 6.62 | 85 Ohms | TOP=L2:L3=L2/L4:L6=L5/L7:BOTTOM=L7 |
| PCIE_TX_CAP_P69 | TXC69-DIFF1 | PAIR | 2 | 5.5 | 5 | 10 | 5 | 50 | 6 | 20 | 12 | 12 | 12 | 12 | 7.5 | 85 Ohms | TOP=L2:L3=L2/L4:L6=L5/L7:BOTTOM=L7 |
| PCIE_TX_CAP_P69 | TXC69-DIFF1 | PAIR | 3 | 5.5 | 5 | 10 | 5 | 50 | 6 | 20 | 12 | 12 | 12 | 12 | 7.5 | 85 Ohms | TOP=L2:L3=L2/L4:L6=L5/L7:BOTTOM=L7 |
| PCIE_TX_CAP_P69 | TXC69-DIFF1 | PAIR | 4 | 5.5 | 5 | 10 | 5 | 50 | 6 | 20 | 12 | 12 | 12 | 12 | 7.5 | 85 Ohms | TOP=L2:L3=L2/L4:L6=L5/L7:BOTTOM=L7 |
| PCIE_TX_CAP_P69 | TXC69-DIFF1 | PAIR | 5 | 5.5 | 5 | 10 | 5 | 50 | 6 | 20 | 12 | 12 | 12 | 12 | 7.5 | 85 Ohms | TOP=L2:L3=L2/L4:L6=L5/L7:BOTTOM=L7 |
| PCIE_TX_CAP_P69 | TXC69-DIFF1 | PAIR | 6 | 5.5 | 5 | 10 | 5 | 50 | 6 | 20 | 12 | 12 | 12 | 12 | 7.5 | 85 Ohms | TOP=L2:L3=L2/L4:L6=L5/L7:BOTTOM=L7 |
| PCIE_TX_CAP_P69 | TXC69-DIFF1 | PAIR | 7 | 5.5 | 5 | 10 | 5 | 50 | 6 | 20 | 12 | 12 | 12 | 12 | 7.5 | 85 Ohms | TOP=L2:L3=L2/L4:L6=L5/L7:BOTTOM=L7 |
| PCIE_TX_CAP_P69 | TXC69-DIFF1 | PAIR | 8 | 5.38 | 5 | 10 | 5 | 50 | 6 | 33 | 12 | 12 | 12 | 12 | 6.62 | 85 Ohms | TOP=L2:L3=L2/L4:L6=L5/L7:BOTTOM=L7 |
| PCIE_TX_CAP_N6 | TXC6-DIFF1 | PAIR | 1 | 5.38 | 5 | 10 | 5 | 50 | 6 | 33 | 12 | 12 | 12 | 12 | 6.62 | 85 Ohms | TOP=L2:L3=L2/L4:L6=L5/L7:BOTTOM=L7 |
| PCIE_TX_CAP_N6 | TXC6-DIFF1 | PAIR | 2 | 5.5 | 5 | 10 | 5 | 50 | 6 | 20 | 12 | 12 | 12 | 12 | 7.5 | 85 Ohms | TOP=L2:L3=L2/L4:L6=L5/L7:BOTTOM=L7 |
| PCIE_TX_CAP_N6 | TXC6-DIFF1 | PAIR | 3 | 5.5 | 5 | 10 | 5 | 50 | 6 | 20 | 12 | 12 | 12 | 12 | 7.5 | 85 Ohms | TOP=L2:L3=L2/L4:L6=L5/L7:BOTTOM=L7 |
| PCIE_TX_CAP_N6 | TXC6-DIFF1 | PAIR | 4 | 5.5 | 5 | 10 | 5 | 50 | 6 | 20 | 12 | 12 | 12 | 12 | 7.5 | 85 Ohms | TOP=L2:L3=L2/L4:L6=L5/L7:BOTTOM=L7 |
| PCIE_TX_CAP_N6 | TXC6-DIFF1 | PAIR | 5 | 5.5 | 5 | 10 | 5 | 50 | 6 | 20 | 12 | 12 | 12 | 12 | 7.5 | 85 Ohms | TOP=L2:L3=L2/L4:L6=L5/L7:BOTTOM=L7 |
| PCIE_TX_CAP_N6 | TXC6-DIFF1 | PAIR | 6 | 5.5 | 5 | 10 | 5 | 50 | 6 | 20 | 12 | 12 | 12 | 12 | 7.5 | 85 Ohms | TOP=L2:L3=L2/L4:L6=L5/L7:BOTTOM=L7 |
| PCIE_TX_CAP_N6 | TXC6-DIFF1 | PAIR | 7 | 5.5 | 5 | 10 | 5 | 50 | 6 | 20 | 12 | 12 | 12 | 12 | 7.5 | 85 Ohms | TOP=L2:L3=L2/L4:L6=L5/L7:BOTTOM=L7 |
| PCIE_TX_CAP_N6 | TXC6-DIFF1 | PAIR | 8 | 5.38 | 5 | 10 | 5 | 50 | 6 | 33 | 12 | 12 | 12 | 12 | 6.62 | 85 Ohms | TOP=L2:L3=L2/L4:L6=L5/L7:BOTTOM=L7 |
| PCIE_TX_CAP_P6 | TXC6-DIFF1 | PAIR | 1 | 5.38 | 5 | 10 | 5 | 50 | 6 | 33 | 12 | 12 | 12 | 12 | 6.62 | 85 Ohms | TOP=L2:L3=L2/L4:L6=L5/L7:BOTTOM=L7 |
| PCIE_TX_CAP_P6 | TXC6-DIFF1 | PAIR | 2 | 5.5 | 5 | 10 | 5 | 50 | 6 | 20 | 12 | 12 | 12 | 12 | 7.5 | 85 Ohms | TOP=L2:L3=L2/L4:L6=L5/L7:BOTTOM=L7 |
| PCIE_TX_CAP_P6 | TXC6-DIFF1 | PAIR | 3 | 5.5 | 5 | 10 | 5 | 50 | 6 | 20 | 12 | 12 | 12 | 12 | 7.5 | 85 Ohms | TOP=L2:L3=L2/L4:L6=L5/L7:BOTTOM=L7 |
| PCIE_TX_CAP_P6 | TXC6-DIFF1 | PAIR | 4 | 5.5 | 5 | 10 | 5 | 50 | 6 | 20 | 12 | 12 | 12 | 12 | 7.5 | 85 Ohms | TOP=L2:L3=L2/L4:L6=L5/L7:BOTTOM=L7 |
| PCIE_TX_CAP_P6 | TXC6-DIFF1 | PAIR | 5 | 5.5 | 5 | 10 | 5 | 50 | 6 | 20 | 12 | 12 | 12 | 12 | 7.5 | 85 Ohms | TOP=L2:L3=L2/L4:L6=L5/L7:BOTTOM=L7 |
| PCIE_TX_CAP_P6 | TXC6-DIFF1 | PAIR | 6 | 5.5 | 5 | 10 | 5 | 50 | 6 | 20 | 12 | 12 | 12 | 12 | 7.5 | 85 Ohms | TOP=L2:L3=L2/L4:L6=L5/L7:BOTTOM=L7 |
| PCIE_TX_CAP_P6 | TXC6-DIFF1 | PAIR | 7 | 5.5 | 5 | 10 | 5 | 50 | 6 | 20 | 12 | 12 | 12 | 12 | 7.5 | 85 Ohms | TOP=L2:L3=L2/L4:L6=L5/L7:BOTTOM=L7 |
| PCIE_TX_CAP_P6 | TXC6-DIFF1 | PAIR | 8 | 5.38 | 5 | 10 | 5 | 50 | 6 | 33 | 12 | 12 | 12 | 12 | 6.62 | 85 Ohms | TOP=L2:L3=L2/L4:L6=L5/L7:BOTTOM=L7 |
| PCIE_TX_CAP_N70 | TXC70-DIFF1 | PAIR | 1 | 5.38 | 5 | 10 | 5 | 50 | 6 | 33 | 12 | 12 | 12 | 12 | 6.62 | 85 Ohms | TOP=L2:L3=L2/L4:L6=L5/L7:BOTTOM=L7 |
| PCIE_TX_CAP_N70 | TXC70-DIFF1 | PAIR | 2 | 5.5 | 5 | 10 | 5 | 50 | 6 | 20 | 12 | 12 | 12 | 12 | 7.5 | 85 Ohms | TOP=L2:L3=L2/L4:L6=L5/L7:BOTTOM=L7 |
| PCIE_TX_CAP_N70 | TXC70-DIFF1 | PAIR | 3 | 5.5 | 5 | 10 | 5 | 50 | 6 | 20 | 12 | 12 | 12 | 12 | 7.5 | 85 Ohms | TOP=L2:L3=L2/L4:L6=L5/L7:BOTTOM=L7 |
| PCIE_TX_CAP_N70 | TXC70-DIFF1 | PAIR | 4 | 5.5 | 5 | 10 | 5 | 50 | 6 | 20 | 12 | 12 | 12 | 12 | 7.5 | 85 Ohms | TOP=L2:L3=L2/L4:L6=L5/L7:BOTTOM=L7 |
| PCIE_TX_CAP_N70 | TXC70-DIFF1 | PAIR | 5 | 5.5 | 5 | 10 | 5 | 50 | 6 | 20 | 12 | 12 | 12 | 12 | 7.5 | 85 Ohms | TOP=L2:L3=L2/L4:L6=L5/L7:BOTTOM=L7 |
| PCIE_TX_CAP_N70 | TXC70-DIFF1 | PAIR | 6 | 5.5 | 5 | 10 | 5 | 50 | 6 | 20 | 12 | 12 | 12 | 12 | 7.5 | 85 Ohms | TOP=L2:L3=L2/L4:L6=L5/L7:BOTTOM=L7 |
| PCIE_TX_CAP_N70 | TXC70-DIFF1 | PAIR | 7 | 5.5 | 5 | 10 | 5 | 50 | 6 | 20 | 12 | 12 | 12 | 12 | 7.5 | 85 Ohms | TOP=L2:L3=L2/L4:L6=L5/L7:BOTTOM=L7 |
| PCIE_TX_CAP_N70 | TXC70-DIFF1 | PAIR | 8 | 5.38 | 5 | 10 | 5 | 50 | 6 | 33 | 12 | 12 | 12 | 12 | 6.62 | 85 Ohms | TOP=L2:L3=L2/L4:L6=L5/L7:BOTTOM=L7 |
| PCIE_TX_CAP_P70 | TXC70-DIFF1 | PAIR | 1 | 5.38 | 5 | 10 | 5 | 50 | 6 | 33 | 12 | 12 | 12 | 12 | 6.62 | 85 Ohms | TOP=L2:L3=L2/L4:L6=L5/L7:BOTTOM=L7 |
| PCIE_TX_CAP_P70 | TXC70-DIFF1 | PAIR | 2 | 5.5 | 5 | 10 | 5 | 50 | 6 | 20 | 12 | 12 | 12 | 12 | 7.5 | 85 Ohms | TOP=L2:L3=L2/L4:L6=L5/L7:BOTTOM=L7 |
| PCIE_TX_CAP_P70 | TXC70-DIFF1 | PAIR | 3 | 5.5 | 5 | 10 | 5 | 50 | 6 | 20 | 12 | 12 | 12 | 12 | 7.5 | 85 Ohms | TOP=L2:L3=L2/L4:L6=L5/L7:BOTTOM=L7 |
| PCIE_TX_CAP_P70 | TXC70-DIFF1 | PAIR | 4 | 5.5 | 5 | 10 | 5 | 50 | 6 | 20 | 12 | 12 | 12 | 12 | 7.5 | 85 Ohms | TOP=L2:L3=L2/L4:L6=L5/L7:BOTTOM=L7 |
| PCIE_TX_CAP_P70 | TXC70-DIFF1 | PAIR | 5 | 5.5 | 5 | 10 | 5 | 50 | 6 | 20 | 12 | 12 | 12 | 12 | 7.5 | 85 Ohms | TOP=L2:L3=L2/L4:L6=L5/L7:BOTTOM=L7 |
| PCIE_TX_CAP_P70 | TXC70-DIFF1 | PAIR | 6 | 5.5 | 5 | 10 | 5 | 50 | 6 | 20 | 12 | 12 | 12 | 12 | 7.5 | 85 Ohms | TOP=L2:L3=L2/L4:L6=L5/L7:BOTTOM=L7 |
| PCIE_TX_CAP_P70 | TXC70-DIFF1 | PAIR | 7 | 5.5 | 5 | 10 | 5 | 50 | 6 | 20 | 12 | 12 | 12 | 12 | 7.5 | 85 Ohms | TOP=L2:L3=L2/L4:L6=L5/L7:BOTTOM=L7 |
| PCIE_TX_CAP_P70 | TXC70-DIFF1 | PAIR | 8 | 5.38 | 5 | 10 | 5 | 50 | 6 | 33 | 12 | 12 | 12 | 12 | 6.62 | 85 Ohms | TOP=L2:L3=L2/L4:L6=L5/L7:BOTTOM=L7 |
| PCIE_TX_CAP_N71 | TXC71-DIFF1 | PAIR | 1 | 5.38 | 5 | 10 | 5 | 50 | 6 | 33 | 12 | 12 | 12 | 12 | 6.62 | 85 Ohms | TOP=L2:L3=L2/L4:L6=L5/L7:BOTTOM=L7 |
| PCIE_TX_CAP_N71 | TXC71-DIFF1 | PAIR | 2 | 5.5 | 5 | 10 | 5 | 50 | 6 | 20 | 12 | 12 | 12 | 12 | 7.5 | 85 Ohms | TOP=L2:L3=L2/L4:L6=L5/L7:BOTTOM=L7 |
| PCIE_TX_CAP_N71 | TXC71-DIFF1 | PAIR | 3 | 5.5 | 5 | 10 | 5 | 50 | 6 | 20 | 12 | 12 | 12 | 12 | 7.5 | 85 Ohms | TOP=L2:L3=L2/L4:L6=L5/L7:BOTTOM=L7 |
| PCIE_TX_CAP_N71 | TXC71-DIFF1 | PAIR | 4 | 5.5 | 5 | 10 | 5 | 50 | 6 | 20 | 12 | 12 | 12 | 12 | 7.5 | 85 Ohms | TOP=L2:L3=L2/L4:L6=L5/L7:BOTTOM=L7 |
| PCIE_TX_CAP_N71 | TXC71-DIFF1 | PAIR | 5 | 5.5 | 5 | 10 | 5 | 50 | 6 | 20 | 12 | 12 | 12 | 12 | 7.5 | 85 Ohms | TOP=L2:L3=L2/L4:L6=L5/L7:BOTTOM=L7 |
| PCIE_TX_CAP_N71 | TXC71-DIFF1 | PAIR | 6 | 5.5 | 5 | 10 | 5 | 50 | 6 | 20 | 12 | 12 | 12 | 12 | 7.5 | 85 Ohms | TOP=L2:L3=L2/L4:L6=L5/L7:BOTTOM=L7 |
| PCIE_TX_CAP_N71 | TXC71-DIFF1 | PAIR | 7 | 5.5 | 5 | 10 | 5 | 50 | 6 | 20 | 12 | 12 | 12 | 12 | 7.5 | 85 Ohms | TOP=L2:L3=L2/L4:L6=L5/L7:BOTTOM=L7 |
| PCIE_TX_CAP_N71 | TXC71-DIFF1 | PAIR | 8 | 5.38 | 5 | 10 | 5 | 50 | 6 | 33 | 12 | 12 | 12 | 12 | 6.62 | 85 Ohms | TOP=L2:L3=L2/L4:L6=L5/L7:BOTTOM=L7 |
| PCIE_TX_CAP_P71 | TXC71-DIFF1 | PAIR | 1 | 5.38 | 5 | 10 | 5 | 50 | 6 | 33 | 12 | 12 | 12 | 12 | 6.62 | 85 Ohms | TOP=L2:L3=L2/L4:L6=L5/L7:BOTTOM=L7 |
| PCIE_TX_CAP_P71 | TXC71-DIFF1 | PAIR | 2 | 5.5 | 5 | 10 | 5 | 50 | 6 | 20 | 12 | 12 | 12 | 12 | 7.5 | 85 Ohms | TOP=L2:L3=L2/L4:L6=L5/L7:BOTTOM=L7 |
| PCIE_TX_CAP_P71 | TXC71-DIFF1 | PAIR | 3 | 5.5 | 5 | 10 | 5 | 50 | 6 | 20 | 12 | 12 | 12 | 12 | 7.5 | 85 Ohms | TOP=L2:L3=L2/L4:L6=L5/L7:BOTTOM=L7 |
| PCIE_TX_CAP_P71 | TXC71-DIFF1 | PAIR | 4 | 5.5 | 5 | 10 | 5 | 50 | 6 | 20 | 12 | 12 | 12 | 12 | 7.5 | 85 Ohms | TOP=L2:L3=L2/L4:L6=L5/L7:BOTTOM=L7 |
| PCIE_TX_CAP_P71 | TXC71-DIFF1 | PAIR | 5 | 5.5 | 5 | 10 | 5 | 50 | 6 | 20 | 12 | 12 | 12 | 12 | 7.5 | 85 Ohms | TOP=L2:L3=L2/L4:L6=L5/L7:BOTTOM=L7 |
| PCIE_TX_CAP_P71 | TXC71-DIFF1 | PAIR | 6 | 5.5 | 5 | 10 | 5 | 50 | 6 | 20 | 12 | 12 | 12 | 12 | 7.5 | 85 Ohms | TOP=L2:L3=L2/L4:L6=L5/L7:BOTTOM=L7 |
| PCIE_TX_CAP_P71 | TXC71-DIFF1 | PAIR | 7 | 5.5 | 5 | 10 | 5 | 50 | 6 | 20 | 12 | 12 | 12 | 12 | 7.5 | 85 Ohms | TOP=L2:L3=L2/L4:L6=L5/L7:BOTTOM=L7 |
| PCIE_TX_CAP_P71 | TXC71-DIFF1 | PAIR | 8 | 5.38 | 5 | 10 | 5 | 50 | 6 | 33 | 12 | 12 | 12 | 12 | 6.62 | 85 Ohms | TOP=L2:L3=L2/L4:L6=L5/L7:BOTTOM=L7 |
| PCIE_TX_CAP_N72 | TXC72-DIFF1 | PAIR | 1 | 5.38 | 5 | 10 | 5 | 50 | 6 | 33 | 12 | 12 | 12 | 12 | 6.62 | 85 Ohms | TOP=L2:L3=L2/L4:L6=L5/L7:BOTTOM=L7 |
| PCIE_TX_CAP_N72 | TXC72-DIFF1 | PAIR | 2 | 5.5 | 5 | 10 | 5 | 50 | 6 | 20 | 12 | 12 | 12 | 12 | 7.5 | 85 Ohms | TOP=L2:L3=L2/L4:L6=L5/L7:BOTTOM=L7 |
| PCIE_TX_CAP_N72 | TXC72-DIFF1 | PAIR | 3 | 5.5 | 5 | 10 | 5 | 50 | 6 | 20 | 12 | 12 | 12 | 12 | 7.5 | 85 Ohms | TOP=L2:L3=L2/L4:L6=L5/L7:BOTTOM=L7 |
| PCIE_TX_CAP_N72 | TXC72-DIFF1 | PAIR | 4 | 5.5 | 5 | 10 | 5 | 50 | 6 | 20 | 12 | 12 | 12 | 12 | 7.5 | 85 Ohms | TOP=L2:L3=L2/L4:L6=L5/L7:BOTTOM=L7 |
| PCIE_TX_CAP_N72 | TXC72-DIFF1 | PAIR | 5 | 5.5 | 5 | 10 | 5 | 50 | 6 | 20 | 12 | 12 | 12 | 12 | 7.5 | 85 Ohms | TOP=L2:L3=L2/L4:L6=L5/L7:BOTTOM=L7 |
| PCIE_TX_CAP_N72 | TXC72-DIFF1 | PAIR | 6 | 5.5 | 5 | 10 | 5 | 50 | 6 | 20 | 12 | 12 | 12 | 12 | 7.5 | 85 Ohms | TOP=L2:L3=L2/L4:L6=L5/L7:BOTTOM=L7 |
| PCIE_TX_CAP_N72 | TXC72-DIFF1 | PAIR | 7 | 5.5 | 5 | 10 | 5 | 50 | 6 | 20 | 12 | 12 | 12 | 12 | 7.5 | 85 Ohms | TOP=L2:L3=L2/L4:L6=L5/L7:BOTTOM=L7 |
| PCIE_TX_CAP_N72 | TXC72-DIFF1 | PAIR | 8 | 5.38 | 5 | 10 | 5 | 50 | 6 | 33 | 12 | 12 | 12 | 12 | 6.62 | 85 Ohms | TOP=L2:L3=L2/L4:L6=L5/L7:BOTTOM=L7 |
| PCIE_TX_CAP_P72 | TXC72-DIFF1 | PAIR | 1 | 5.38 | 5 | 10 | 5 | 50 | 6 | 33 | 12 | 12 | 12 | 12 | 6.62 | 85 Ohms | TOP=L2:L3=L2/L4:L6=L5/L7:BOTTOM=L7 |
| PCIE_TX_CAP_P72 | TXC72-DIFF1 | PAIR | 2 | 5.5 | 5 | 10 | 5 | 50 | 6 | 20 | 12 | 12 | 12 | 12 | 7.5 | 85 Ohms | TOP=L2:L3=L2/L4:L6=L5/L7:BOTTOM=L7 |
| PCIE_TX_CAP_P72 | TXC72-DIFF1 | PAIR | 3 | 5.5 | 5 | 10 | 5 | 50 | 6 | 20 | 12 | 12 | 12 | 12 | 7.5 | 85 Ohms | TOP=L2:L3=L2/L4:L6=L5/L7:BOTTOM=L7 |
| PCIE_TX_CAP_P72 | TXC72-DIFF1 | PAIR | 4 | 5.5 | 5 | 10 | 5 | 50 | 6 | 20 | 12 | 12 | 12 | 12 | 7.5 | 85 Ohms | TOP=L2:L3=L2/L4:L6=L5/L7:BOTTOM=L7 |
| PCIE_TX_CAP_P72 | TXC72-DIFF1 | PAIR | 5 | 5.5 | 5 | 10 | 5 | 50 | 6 | 20 | 12 | 12 | 12 | 12 | 7.5 | 85 Ohms | TOP=L2:L3=L2/L4:L6=L5/L7:BOTTOM=L7 |
| PCIE_TX_CAP_P72 | TXC72-DIFF1 | PAIR | 6 | 5.5 | 5 | 10 | 5 | 50 | 6 | 20 | 12 | 12 | 12 | 12 | 7.5 | 85 Ohms | TOP=L2:L3=L2/L4:L6=L5/L7:BOTTOM=L7 |
| PCIE_TX_CAP_P72 | TXC72-DIFF1 | PAIR | 7 | 5.5 | 5 | 10 | 5 | 50 | 6 | 20 | 12 | 12 | 12 | 12 | 7.5 | 85 Ohms | TOP=L2:L3=L2/L4:L6=L5/L7:BOTTOM=L7 |
| PCIE_TX_CAP_P72 | TXC72-DIFF1 | PAIR | 8 | 5.38 | 5 | 10 | 5 | 50 | 6 | 33 | 12 | 12 | 12 | 12 | 6.62 | 85 Ohms | TOP=L2:L3=L2/L4:L6=L5/L7:BOTTOM=L7 |
| PCIE_TX_CAP_N73 | TXC73-DIFF1 | PAIR | 1 | 5.38 | 5 | 10 | 5 | 50 | 6 | 33 | 12 | 12 | 12 | 12 | 6.62 | 85 Ohms | TOP=L2:L3=L2/L4:L6=L5/L7:BOTTOM=L7 |
| PCIE_TX_CAP_N73 | TXC73-DIFF1 | PAIR | 2 | 5.5 | 5 | 10 | 5 | 50 | 6 | 20 | 12 | 12 | 12 | 12 | 7.5 | 85 Ohms | TOP=L2:L3=L2/L4:L6=L5/L7:BOTTOM=L7 |
| PCIE_TX_CAP_N73 | TXC73-DIFF1 | PAIR | 3 | 5.5 | 5 | 10 | 5 | 50 | 6 | 20 | 12 | 12 | 12 | 12 | 7.5 | 85 Ohms | TOP=L2:L3=L2/L4:L6=L5/L7:BOTTOM=L7 |
| PCIE_TX_CAP_N73 | TXC73-DIFF1 | PAIR | 4 | 5.5 | 5 | 10 | 5 | 50 | 6 | 20 | 12 | 12 | 12 | 12 | 7.5 | 85 Ohms | TOP=L2:L3=L2/L4:L6=L5/L7:BOTTOM=L7 |
| PCIE_TX_CAP_N73 | TXC73-DIFF1 | PAIR | 5 | 5.5 | 5 | 10 | 5 | 50 | 6 | 20 | 12 | 12 | 12 | 12 | 7.5 | 85 Ohms | TOP=L2:L3=L2/L4:L6=L5/L7:BOTTOM=L7 |
| PCIE_TX_CAP_N73 | TXC73-DIFF1 | PAIR | 6 | 5.5 | 5 | 10 | 5 | 50 | 6 | 20 | 12 | 12 | 12 | 12 | 7.5 | 85 Ohms | TOP=L2:L3=L2/L4:L6=L5/L7:BOTTOM=L7 |
| PCIE_TX_CAP_N73 | TXC73-DIFF1 | PAIR | 7 | 5.5 | 5 | 10 | 5 | 50 | 6 | 20 | 12 | 12 | 12 | 12 | 7.5 | 85 Ohms | TOP=L2:L3=L2/L4:L6=L5/L7:BOTTOM=L7 |
| PCIE_TX_CAP_N73 | TXC73-DIFF1 | PAIR | 8 | 5.38 | 5 | 10 | 5 | 50 | 6 | 33 | 12 | 12 | 12 | 12 | 6.62 | 85 Ohms | TOP=L2:L3=L2/L4:L6=L5/L7:BOTTOM=L7 |
| PCIE_TX_CAP_P73 | TXC73-DIFF1 | PAIR | 1 | 5.38 | 5 | 10 | 5 | 50 | 6 | 33 | 12 | 12 | 12 | 12 | 6.62 | 85 Ohms | TOP=L2:L3=L2/L4:L6=L5/L7:BOTTOM=L7 |
| PCIE_TX_CAP_P73 | TXC73-DIFF1 | PAIR | 2 | 5.5 | 5 | 10 | 5 | 50 | 6 | 20 | 12 | 12 | 12 | 12 | 7.5 | 85 Ohms | TOP=L2:L3=L2/L4:L6=L5/L7:BOTTOM=L7 |
| PCIE_TX_CAP_P73 | TXC73-DIFF1 | PAIR | 3 | 5.5 | 5 | 10 | 5 | 50 | 6 | 20 | 12 | 12 | 12 | 12 | 7.5 | 85 Ohms | TOP=L2:L3=L2/L4:L6=L5/L7:BOTTOM=L7 |
| PCIE_TX_CAP_P73 | TXC73-DIFF1 | PAIR | 4 | 5.5 | 5 | 10 | 5 | 50 | 6 | 20 | 12 | 12 | 12 | 12 | 7.5 | 85 Ohms | TOP=L2:L3=L2/L4:L6=L5/L7:BOTTOM=L7 |
| PCIE_TX_CAP_P73 | TXC73-DIFF1 | PAIR | 5 | 5.5 | 5 | 10 | 5 | 50 | 6 | 20 | 12 | 12 | 12 | 12 | 7.5 | 85 Ohms | TOP=L2:L3=L2/L4:L6=L5/L7:BOTTOM=L7 |
| PCIE_TX_CAP_P73 | TXC73-DIFF1 | PAIR | 6 | 5.5 | 5 | 10 | 5 | 50 | 6 | 20 | 12 | 12 | 12 | 12 | 7.5 | 85 Ohms | TOP=L2:L3=L2/L4:L6=L5/L7:BOTTOM=L7 |
| PCIE_TX_CAP_P73 | TXC73-DIFF1 | PAIR | 7 | 5.5 | 5 | 10 | 5 | 50 | 6 | 20 | 12 | 12 | 12 | 12 | 7.5 | 85 Ohms | TOP=L2:L3=L2/L4:L6=L5/L7:BOTTOM=L7 |
| PCIE_TX_CAP_P73 | TXC73-DIFF1 | PAIR | 8 | 5.38 | 5 | 10 | 5 | 50 | 6 | 33 | 12 | 12 | 12 | 12 | 6.62 | 85 Ohms | TOP=L2:L3=L2/L4:L6=L5/L7:BOTTOM=L7 |
| PCIE_TX_CAP_N74 | TXC74-DIFF1 | PAIR | 1 | 5.38 | 5 | 10 | 5 | 50 | 6 | 33 | 12 | 12 | 12 | 12 | 6.62 | 85 Ohms | TOP=L2:L3=L2/L4:L6=L5/L7:BOTTOM=L7 |
| PCIE_TX_CAP_N74 | TXC74-DIFF1 | PAIR | 2 | 5.5 | 5 | 10 | 5 | 50 | 6 | 20 | 12 | 12 | 12 | 12 | 7.5 | 85 Ohms | TOP=L2:L3=L2/L4:L6=L5/L7:BOTTOM=L7 |
| PCIE_TX_CAP_N74 | TXC74-DIFF1 | PAIR | 3 | 5.5 | 5 | 10 | 5 | 50 | 6 | 20 | 12 | 12 | 12 | 12 | 7.5 | 85 Ohms | TOP=L2:L3=L2/L4:L6=L5/L7:BOTTOM=L7 |
| PCIE_TX_CAP_N74 | TXC74-DIFF1 | PAIR | 4 | 5.5 | 5 | 10 | 5 | 50 | 6 | 20 | 12 | 12 | 12 | 12 | 7.5 | 85 Ohms | TOP=L2:L3=L2/L4:L6=L5/L7:BOTTOM=L7 |
| PCIE_TX_CAP_N74 | TXC74-DIFF1 | PAIR | 5 | 5.5 | 5 | 10 | 5 | 50 | 6 | 20 | 12 | 12 | 12 | 12 | 7.5 | 85 Ohms | TOP=L2:L3=L2/L4:L6=L5/L7:BOTTOM=L7 |
| PCIE_TX_CAP_N74 | TXC74-DIFF1 | PAIR | 6 | 5.5 | 5 | 10 | 5 | 50 | 6 | 20 | 12 | 12 | 12 | 12 | 7.5 | 85 Ohms | TOP=L2:L3=L2/L4:L6=L5/L7:BOTTOM=L7 |
| PCIE_TX_CAP_N74 | TXC74-DIFF1 | PAIR | 7 | 5.5 | 5 | 10 | 5 | 50 | 6 | 20 | 12 | 12 | 12 | 12 | 7.5 | 85 Ohms | TOP=L2:L3=L2/L4:L6=L5/L7:BOTTOM=L7 |
| PCIE_TX_CAP_N74 | TXC74-DIFF1 | PAIR | 8 | 5.38 | 5 | 10 | 5 | 50 | 6 | 33 | 12 | 12 | 12 | 12 | 6.62 | 85 Ohms | TOP=L2:L3=L2/L4:L6=L5/L7:BOTTOM=L7 |
| PCIE_TX_CAP_P74 | TXC74-DIFF1 | PAIR | 1 | 5.38 | 5 | 10 | 5 | 50 | 6 | 33 | 12 | 12 | 12 | 12 | 6.62 | 85 Ohms | TOP=L2:L3=L2/L4:L6=L5/L7:BOTTOM=L7 |
| PCIE_TX_CAP_P74 | TXC74-DIFF1 | PAIR | 2 | 5.5 | 5 | 10 | 5 | 50 | 6 | 20 | 12 | 12 | 12 | 12 | 7.5 | 85 Ohms | TOP=L2:L3=L2/L4:L6=L5/L7:BOTTOM=L7 |
| PCIE_TX_CAP_P74 | TXC74-DIFF1 | PAIR | 3 | 5.5 | 5 | 10 | 5 | 50 | 6 | 20 | 12 | 12 | 12 | 12 | 7.5 | 85 Ohms | TOP=L2:L3=L2/L4:L6=L5/L7:BOTTOM=L7 |
| PCIE_TX_CAP_P74 | TXC74-DIFF1 | PAIR | 4 | 5.5 | 5 | 10 | 5 | 50 | 6 | 20 | 12 | 12 | 12 | 12 | 7.5 | 85 Ohms | TOP=L2:L3=L2/L4:L6=L5/L7:BOTTOM=L7 |
| PCIE_TX_CAP_P74 | TXC74-DIFF1 | PAIR | 5 | 5.5 | 5 | 10 | 5 | 50 | 6 | 20 | 12 | 12 | 12 | 12 | 7.5 | 85 Ohms | TOP=L2:L3=L2/L4:L6=L5/L7:BOTTOM=L7 |
| PCIE_TX_CAP_P74 | TXC74-DIFF1 | PAIR | 6 | 5.5 | 5 | 10 | 5 | 50 | 6 | 20 | 12 | 12 | 12 | 12 | 7.5 | 85 Ohms | TOP=L2:L3=L2/L4:L6=L5/L7:BOTTOM=L7 |
| PCIE_TX_CAP_P74 | TXC74-DIFF1 | PAIR | 7 | 5.5 | 5 | 10 | 5 | 50 | 6 | 20 | 12 | 12 | 12 | 12 | 7.5 | 85 Ohms | TOP=L2:L3=L2/L4:L6=L5/L7:BOTTOM=L7 |
| PCIE_TX_CAP_P74 | TXC74-DIFF1 | PAIR | 8 | 5.38 | 5 | 10 | 5 | 50 | 6 | 33 | 12 | 12 | 12 | 12 | 6.62 | 85 Ohms | TOP=L2:L3=L2/L4:L6=L5/L7:BOTTOM=L7 |
| PCIE_TX_CAP_N75 | TXC75-DIFF1 | PAIR | 1 | 5.38 | 5 | 10 | 5 | 50 | 6 | 33 | 12 | 12 | 12 | 12 | 6.62 | 85 Ohms | TOP=L2:L3=L2/L4:L6=L5/L7:BOTTOM=L7 |
| PCIE_TX_CAP_N75 | TXC75-DIFF1 | PAIR | 2 | 5.5 | 5 | 10 | 5 | 50 | 6 | 20 | 12 | 12 | 12 | 12 | 7.5 | 85 Ohms | TOP=L2:L3=L2/L4:L6=L5/L7:BOTTOM=L7 |
| PCIE_TX_CAP_N75 | TXC75-DIFF1 | PAIR | 3 | 5.5 | 5 | 10 | 5 | 50 | 6 | 20 | 12 | 12 | 12 | 12 | 7.5 | 85 Ohms | TOP=L2:L3=L2/L4:L6=L5/L7:BOTTOM=L7 |
| PCIE_TX_CAP_N75 | TXC75-DIFF1 | PAIR | 4 | 5.5 | 5 | 10 | 5 | 50 | 6 | 20 | 12 | 12 | 12 | 12 | 7.5 | 85 Ohms | TOP=L2:L3=L2/L4:L6=L5/L7:BOTTOM=L7 |
| PCIE_TX_CAP_N75 | TXC75-DIFF1 | PAIR | 5 | 5.5 | 5 | 10 | 5 | 50 | 6 | 20 | 12 | 12 | 12 | 12 | 7.5 | 85 Ohms | TOP=L2:L3=L2/L4:L6=L5/L7:BOTTOM=L7 |
| PCIE_TX_CAP_N75 | TXC75-DIFF1 | PAIR | 6 | 5.5 | 5 | 10 | 5 | 50 | 6 | 20 | 12 | 12 | 12 | 12 | 7.5 | 85 Ohms | TOP=L2:L3=L2/L4:L6=L5/L7:BOTTOM=L7 |
| PCIE_TX_CAP_N75 | TXC75-DIFF1 | PAIR | 7 | 5.5 | 5 | 10 | 5 | 50 | 6 | 20 | 12 | 12 | 12 | 12 | 7.5 | 85 Ohms | TOP=L2:L3=L2/L4:L6=L5/L7:BOTTOM=L7 |
| PCIE_TX_CAP_N75 | TXC75-DIFF1 | PAIR | 8 | 5.38 | 5 | 10 | 5 | 50 | 6 | 33 | 12 | 12 | 12 | 12 | 6.62 | 85 Ohms | TOP=L2:L3=L2/L4:L6=L5/L7:BOTTOM=L7 |
| PCIE_TX_CAP_P75 | TXC75-DIFF1 | PAIR | 1 | 5.38 | 5 | 10 | 5 | 50 | 6 | 33 | 12 | 12 | 12 | 12 | 6.62 | 85 Ohms | TOP=L2:L3=L2/L4:L6=L5/L7:BOTTOM=L7 |
| PCIE_TX_CAP_P75 | TXC75-DIFF1 | PAIR | 2 | 5.5 | 5 | 10 | 5 | 50 | 6 | 20 | 12 | 12 | 12 | 12 | 7.5 | 85 Ohms | TOP=L2:L3=L2/L4:L6=L5/L7:BOTTOM=L7 |
| PCIE_TX_CAP_P75 | TXC75-DIFF1 | PAIR | 3 | 5.5 | 5 | 10 | 5 | 50 | 6 | 20 | 12 | 12 | 12 | 12 | 7.5 | 85 Ohms | TOP=L2:L3=L2/L4:L6=L5/L7:BOTTOM=L7 |
| PCIE_TX_CAP_P75 | TXC75-DIFF1 | PAIR | 4 | 5.5 | 5 | 10 | 5 | 50 | 6 | 20 | 12 | 12 | 12 | 12 | 7.5 | 85 Ohms | TOP=L2:L3=L2/L4:L6=L5/L7:BOTTOM=L7 |
| PCIE_TX_CAP_P75 | TXC75-DIFF1 | PAIR | 5 | 5.5 | 5 | 10 | 5 | 50 | 6 | 20 | 12 | 12 | 12 | 12 | 7.5 | 85 Ohms | TOP=L2:L3=L2/L4:L6=L5/L7:BOTTOM=L7 |
| PCIE_TX_CAP_P75 | TXC75-DIFF1 | PAIR | 6 | 5.5 | 5 | 10 | 5 | 50 | 6 | 20 | 12 | 12 | 12 | 12 | 7.5 | 85 Ohms | TOP=L2:L3=L2/L4:L6=L5/L7:BOTTOM=L7 |
| PCIE_TX_CAP_P75 | TXC75-DIFF1 | PAIR | 7 | 5.5 | 5 | 10 | 5 | 50 | 6 | 20 | 12 | 12 | 12 | 12 | 7.5 | 85 Ohms | TOP=L2:L3=L2/L4:L6=L5/L7:BOTTOM=L7 |
| PCIE_TX_CAP_P75 | TXC75-DIFF1 | PAIR | 8 | 5.38 | 5 | 10 | 5 | 50 | 6 | 33 | 12 | 12 | 12 | 12 | 6.62 | 85 Ohms | TOP=L2:L3=L2/L4:L6=L5/L7:BOTTOM=L7 |
| PCIE_TX_CAP_N76 | TXC76-DIFF1 | PAIR | 1 | 5.38 | 5 | 10 | 5 | 50 | 6 | 33 | 12 | 12 | 12 | 12 | 6.62 | 85 Ohms | TOP=L2:L3=L2/L4:L6=L5/L7:BOTTOM=L7 |
| PCIE_TX_CAP_N76 | TXC76-DIFF1 | PAIR | 2 | 5.5 | 5 | 10 | 5 | 50 | 6 | 20 | 12 | 12 | 12 | 12 | 7.5 | 85 Ohms | TOP=L2:L3=L2/L4:L6=L5/L7:BOTTOM=L7 |
| PCIE_TX_CAP_N76 | TXC76-DIFF1 | PAIR | 3 | 5.5 | 5 | 10 | 5 | 50 | 6 | 20 | 12 | 12 | 12 | 12 | 7.5 | 85 Ohms | TOP=L2:L3=L2/L4:L6=L5/L7:BOTTOM=L7 |
| PCIE_TX_CAP_N76 | TXC76-DIFF1 | PAIR | 4 | 5.5 | 5 | 10 | 5 | 50 | 6 | 20 | 12 | 12 | 12 | 12 | 7.5 | 85 Ohms | TOP=L2:L3=L2/L4:L6=L5/L7:BOTTOM=L7 |
| PCIE_TX_CAP_N76 | TXC76-DIFF1 | PAIR | 5 | 5.5 | 5 | 10 | 5 | 50 | 6 | 20 | 12 | 12 | 12 | 12 | 7.5 | 85 Ohms | TOP=L2:L3=L2/L4:L6=L5/L7:BOTTOM=L7 |
| PCIE_TX_CAP_N76 | TXC76-DIFF1 | PAIR | 6 | 5.5 | 5 | 10 | 5 | 50 | 6 | 20 | 12 | 12 | 12 | 12 | 7.5 | 85 Ohms | TOP=L2:L3=L2/L4:L6=L5/L7:BOTTOM=L7 |
| PCIE_TX_CAP_N76 | TXC76-DIFF1 | PAIR | 7 | 5.5 | 5 | 10 | 5 | 50 | 6 | 20 | 12 | 12 | 12 | 12 | 7.5 | 85 Ohms | TOP=L2:L3=L2/L4:L6=L5/L7:BOTTOM=L7 |
| PCIE_TX_CAP_N76 | TXC76-DIFF1 | PAIR | 8 | 5.38 | 5 | 10 | 5 | 50 | 6 | 33 | 12 | 12 | 12 | 12 | 6.62 | 85 Ohms | TOP=L2:L3=L2/L4:L6=L5/L7:BOTTOM=L7 |
| PCIE_TX_CAP_P76 | TXC76-DIFF1 | PAIR | 1 | 5.38 | 5 | 10 | 5 | 50 | 6 | 33 | 12 | 12 | 12 | 12 | 6.62 | 85 Ohms | TOP=L2:L3=L2/L4:L6=L5/L7:BOTTOM=L7 |
| PCIE_TX_CAP_P76 | TXC76-DIFF1 | PAIR | 2 | 5.5 | 5 | 10 | 5 | 50 | 6 | 20 | 12 | 12 | 12 | 12 | 7.5 | 85 Ohms | TOP=L2:L3=L2/L4:L6=L5/L7:BOTTOM=L7 |
| PCIE_TX_CAP_P76 | TXC76-DIFF1 | PAIR | 3 | 5.5 | 5 | 10 | 5 | 50 | 6 | 20 | 12 | 12 | 12 | 12 | 7.5 | 85 Ohms | TOP=L2:L3=L2/L4:L6=L5/L7:BOTTOM=L7 |
| PCIE_TX_CAP_P76 | TXC76-DIFF1 | PAIR | 4 | 5.5 | 5 | 10 | 5 | 50 | 6 | 20 | 12 | 12 | 12 | 12 | 7.5 | 85 Ohms | TOP=L2:L3=L2/L4:L6=L5/L7:BOTTOM=L7 |
| PCIE_TX_CAP_P76 | TXC76-DIFF1 | PAIR | 5 | 5.5 | 5 | 10 | 5 | 50 | 6 | 20 | 12 | 12 | 12 | 12 | 7.5 | 85 Ohms | TOP=L2:L3=L2/L4:L6=L5/L7:BOTTOM=L7 |
| PCIE_TX_CAP_P76 | TXC76-DIFF1 | PAIR | 6 | 5.5 | 5 | 10 | 5 | 50 | 6 | 20 | 12 | 12 | 12 | 12 | 7.5 | 85 Ohms | TOP=L2:L3=L2/L4:L6=L5/L7:BOTTOM=L7 |
| PCIE_TX_CAP_P76 | TXC76-DIFF1 | PAIR | 7 | 5.5 | 5 | 10 | 5 | 50 | 6 | 20 | 12 | 12 | 12 | 12 | 7.5 | 85 Ohms | TOP=L2:L3=L2/L4:L6=L5/L7:BOTTOM=L7 |
| PCIE_TX_CAP_P76 | TXC76-DIFF1 | PAIR | 8 | 5.38 | 5 | 10 | 5 | 50 | 6 | 33 | 12 | 12 | 12 | 12 | 6.62 | 85 Ohms | TOP=L2:L3=L2/L4:L6=L5/L7:BOTTOM=L7 |
| PCIE_TX_CAP_N78 | TXC78-DIFF1 | PAIR | 1 | 5.38 | 5 | 10 | 5 | 50 | 6 | 33 | 12 | 12 | 12 | 12 | 6.62 | 85 Ohms | TOP=L2:L3=L2/L4:L6=L5/L7:BOTTOM=L7 |
| PCIE_TX_CAP_N78 | TXC78-DIFF1 | PAIR | 2 | 5.5 | 5 | 10 | 5 | 50 | 6 | 20 | 12 | 12 | 12 | 12 | 7.5 | 85 Ohms | TOP=L2:L3=L2/L4:L6=L5/L7:BOTTOM=L7 |
| PCIE_TX_CAP_N78 | TXC78-DIFF1 | PAIR | 3 | 5.5 | 5 | 10 | 5 | 50 | 6 | 20 | 12 | 12 | 12 | 12 | 7.5 | 85 Ohms | TOP=L2:L3=L2/L4:L6=L5/L7:BOTTOM=L7 |
| PCIE_TX_CAP_N78 | TXC78-DIFF1 | PAIR | 4 | 5.5 | 5 | 10 | 5 | 50 | 6 | 20 | 12 | 12 | 12 | 12 | 7.5 | 85 Ohms | TOP=L2:L3=L2/L4:L6=L5/L7:BOTTOM=L7 |
| PCIE_TX_CAP_N78 | TXC78-DIFF1 | PAIR | 5 | 5.5 | 5 | 10 | 5 | 50 | 6 | 20 | 12 | 12 | 12 | 12 | 7.5 | 85 Ohms | TOP=L2:L3=L2/L4:L6=L5/L7:BOTTOM=L7 |
| PCIE_TX_CAP_N78 | TXC78-DIFF1 | PAIR | 6 | 5.5 | 5 | 10 | 5 | 50 | 6 | 20 | 12 | 12 | 12 | 12 | 7.5 | 85 Ohms | TOP=L2:L3=L2/L4:L6=L5/L7:BOTTOM=L7 |
| PCIE_TX_CAP_N78 | TXC78-DIFF1 | PAIR | 7 | 5.5 | 5 | 10 | 5 | 50 | 6 | 20 | 12 | 12 | 12 | 12 | 7.5 | 85 Ohms | TOP=L2:L3=L2/L4:L6=L5/L7:BOTTOM=L7 |
| PCIE_TX_CAP_N78 | TXC78-DIFF1 | PAIR | 8 | 5.38 | 5 | 10 | 5 | 50 | 6 | 33 | 12 | 12 | 12 | 12 | 6.62 | 85 Ohms | TOP=L2:L3=L2/L4:L6=L5/L7:BOTTOM=L7 |
| PCIE_TX_CAP_P78 | TXC78-DIFF1 | PAIR | 1 | 5.38 | 5 | 10 | 5 | 50 | 6 | 33 | 12 | 12 | 12 | 12 | 6.62 | 85 Ohms | TOP=L2:L3=L2/L4:L6=L5/L7:BOTTOM=L7 |
| PCIE_TX_CAP_P78 | TXC78-DIFF1 | PAIR | 2 | 5.5 | 5 | 10 | 5 | 50 | 6 | 20 | 12 | 12 | 12 | 12 | 7.5 | 85 Ohms | TOP=L2:L3=L2/L4:L6=L5/L7:BOTTOM=L7 |
| PCIE_TX_CAP_P78 | TXC78-DIFF1 | PAIR | 3 | 5.5 | 5 | 10 | 5 | 50 | 6 | 20 | 12 | 12 | 12 | 12 | 7.5 | 85 Ohms | TOP=L2:L3=L2/L4:L6=L5/L7:BOTTOM=L7 |
| PCIE_TX_CAP_P78 | TXC78-DIFF1 | PAIR | 4 | 5.5 | 5 | 10 | 5 | 50 | 6 | 20 | 12 | 12 | 12 | 12 | 7.5 | 85 Ohms | TOP=L2:L3=L2/L4:L6=L5/L7:BOTTOM=L7 |
| PCIE_TX_CAP_P78 | TXC78-DIFF1 | PAIR | 5 | 5.5 | 5 | 10 | 5 | 50 | 6 | 20 | 12 | 12 | 12 | 12 | 7.5 | 85 Ohms | TOP=L2:L3=L2/L4:L6=L5/L7:BOTTOM=L7 |
| PCIE_TX_CAP_P78 | TXC78-DIFF1 | PAIR | 6 | 5.5 | 5 | 10 | 5 | 50 | 6 | 20 | 12 | 12 | 12 | 12 | 7.5 | 85 Ohms | TOP=L2:L3=L2/L4:L6=L5/L7:BOTTOM=L7 |
| PCIE_TX_CAP_P78 | TXC78-DIFF1 | PAIR | 7 | 5.5 | 5 | 10 | 5 | 50 | 6 | 20 | 12 | 12 | 12 | 12 | 7.5 | 85 Ohms | TOP=L2:L3=L2/L4:L6=L5/L7:BOTTOM=L7 |
| PCIE_TX_CAP_P78 | TXC78-DIFF1 | PAIR | 8 | 5.38 | 5 | 10 | 5 | 50 | 6 | 33 | 12 | 12 | 12 | 12 | 6.62 | 85 Ohms | TOP=L2:L3=L2/L4:L6=L5/L7:BOTTOM=L7 |
| PCIE_TX_CAP_N7 | TXC7-DIFF1 | PAIR | 1 | 5.38 | 5 | 10 | 5 | 50 | 6 | 33 | 12 | 12 | 12 | 12 | 6.62 | 85 Ohms | TOP=L2:L3=L2/L4:L6=L5/L7:BOTTOM=L7 |
| PCIE_TX_CAP_N7 | TXC7-DIFF1 | PAIR | 2 | 5.5 | 5 | 10 | 5 | 50 | 6 | 20 | 12 | 12 | 12 | 12 | 7.5 | 85 Ohms | TOP=L2:L3=L2/L4:L6=L5/L7:BOTTOM=L7 |
| PCIE_TX_CAP_N7 | TXC7-DIFF1 | PAIR | 3 | 5.5 | 5 | 10 | 5 | 50 | 6 | 20 | 12 | 12 | 12 | 12 | 7.5 | 85 Ohms | TOP=L2:L3=L2/L4:L6=L5/L7:BOTTOM=L7 |
| PCIE_TX_CAP_N7 | TXC7-DIFF1 | PAIR | 4 | 5.5 | 5 | 10 | 5 | 50 | 6 | 20 | 12 | 12 | 12 | 12 | 7.5 | 85 Ohms | TOP=L2:L3=L2/L4:L6=L5/L7:BOTTOM=L7 |
| PCIE_TX_CAP_N7 | TXC7-DIFF1 | PAIR | 5 | 5.5 | 5 | 10 | 5 | 50 | 6 | 20 | 12 | 12 | 12 | 12 | 7.5 | 85 Ohms | TOP=L2:L3=L2/L4:L6=L5/L7:BOTTOM=L7 |
| PCIE_TX_CAP_N7 | TXC7-DIFF1 | PAIR | 6 | 5.5 | 5 | 10 | 5 | 50 | 6 | 20 | 12 | 12 | 12 | 12 | 7.5 | 85 Ohms | TOP=L2:L3=L2/L4:L6=L5/L7:BOTTOM=L7 |
| PCIE_TX_CAP_N7 | TXC7-DIFF1 | PAIR | 7 | 5.5 | 5 | 10 | 5 | 50 | 6 | 20 | 12 | 12 | 12 | 12 | 7.5 | 85 Ohms | TOP=L2:L3=L2/L4:L6=L5/L7:BOTTOM=L7 |
| PCIE_TX_CAP_N7 | TXC7-DIFF1 | PAIR | 8 | 5.38 | 5 | 10 | 5 | 50 | 6 | 33 | 12 | 12 | 12 | 12 | 6.62 | 85 Ohms | TOP=L2:L3=L2/L4:L6=L5/L7:BOTTOM=L7 |
| PCIE_TX_CAP_P7 | TXC7-DIFF1 | PAIR | 1 | 5.38 | 5 | 10 | 5 | 50 | 6 | 33 | 12 | 12 | 12 | 12 | 6.62 | 85 Ohms | TOP=L2:L3=L2/L4:L6=L5/L7:BOTTOM=L7 |
| PCIE_TX_CAP_P7 | TXC7-DIFF1 | PAIR | 2 | 5.5 | 5 | 10 | 5 | 50 | 6 | 20 | 12 | 12 | 12 | 12 | 7.5 | 85 Ohms | TOP=L2:L3=L2/L4:L6=L5/L7:BOTTOM=L7 |
| PCIE_TX_CAP_P7 | TXC7-DIFF1 | PAIR | 3 | 5.5 | 5 | 10 | 5 | 50 | 6 | 20 | 12 | 12 | 12 | 12 | 7.5 | 85 Ohms | TOP=L2:L3=L2/L4:L6=L5/L7:BOTTOM=L7 |
| PCIE_TX_CAP_P7 | TXC7-DIFF1 | PAIR | 4 | 5.5 | 5 | 10 | 5 | 50 | 6 | 20 | 12 | 12 | 12 | 12 | 7.5 | 85 Ohms | TOP=L2:L3=L2/L4:L6=L5/L7:BOTTOM=L7 |
| PCIE_TX_CAP_P7 | TXC7-DIFF1 | PAIR | 5 | 5.5 | 5 | 10 | 5 | 50 | 6 | 20 | 12 | 12 | 12 | 12 | 7.5 | 85 Ohms | TOP=L2:L3=L2/L4:L6=L5/L7:BOTTOM=L7 |
| PCIE_TX_CAP_P7 | TXC7-DIFF1 | PAIR | 6 | 5.5 | 5 | 10 | 5 | 50 | 6 | 20 | 12 | 12 | 12 | 12 | 7.5 | 85 Ohms | TOP=L2:L3=L2/L4:L6=L5/L7:BOTTOM=L7 |
| PCIE_TX_CAP_P7 | TXC7-DIFF1 | PAIR | 7 | 5.5 | 5 | 10 | 5 | 50 | 6 | 20 | 12 | 12 | 12 | 12 | 7.5 | 85 Ohms | TOP=L2:L3=L2/L4:L6=L5/L7:BOTTOM=L7 |
| PCIE_TX_CAP_P7 | TXC7-DIFF1 | PAIR | 8 | 5.38 | 5 | 10 | 5 | 50 | 6 | 33 | 12 | 12 | 12 | 12 | 6.62 | 85 Ohms | TOP=L2:L3=L2/L4:L6=L5/L7:BOTTOM=L7 |
| PCIE_TX_CAP_N80 | TXC80-DIFF1 | PAIR | 1 | 5.38 | 5 | 10 | 5 | 50 | 6 | 33 | 12 | 12 | 12 | 12 | 6.62 | 85 Ohms | TOP=L2:L3=L2/L4:L6=L5/L7:BOTTOM=L7 |
| PCIE_TX_CAP_N80 | TXC80-DIFF1 | PAIR | 2 | 5.5 | 5 | 10 | 5 | 50 | 6 | 20 | 12 | 12 | 12 | 12 | 7.5 | 85 Ohms | TOP=L2:L3=L2/L4:L6=L5/L7:BOTTOM=L7 |
| PCIE_TX_CAP_N80 | TXC80-DIFF1 | PAIR | 3 | 5.5 | 5 | 10 | 5 | 50 | 6 | 20 | 12 | 12 | 12 | 12 | 7.5 | 85 Ohms | TOP=L2:L3=L2/L4:L6=L5/L7:BOTTOM=L7 |
| PCIE_TX_CAP_N80 | TXC80-DIFF1 | PAIR | 4 | 5.5 | 5 | 10 | 5 | 50 | 6 | 20 | 12 | 12 | 12 | 12 | 7.5 | 85 Ohms | TOP=L2:L3=L2/L4:L6=L5/L7:BOTTOM=L7 |
| PCIE_TX_CAP_N80 | TXC80-DIFF1 | PAIR | 5 | 5.5 | 5 | 10 | 5 | 50 | 6 | 20 | 12 | 12 | 12 | 12 | 7.5 | 85 Ohms | TOP=L2:L3=L2/L4:L6=L5/L7:BOTTOM=L7 |
| PCIE_TX_CAP_N80 | TXC80-DIFF1 | PAIR | 6 | 5.5 | 5 | 10 | 5 | 50 | 6 | 20 | 12 | 12 | 12 | 12 | 7.5 | 85 Ohms | TOP=L2:L3=L2/L4:L6=L5/L7:BOTTOM=L7 |
| PCIE_TX_CAP_N80 | TXC80-DIFF1 | PAIR | 7 | 5.5 | 5 | 10 | 5 | 50 | 6 | 20 | 12 | 12 | 12 | 12 | 7.5 | 85 Ohms | TOP=L2:L3=L2/L4:L6=L5/L7:BOTTOM=L7 |
| PCIE_TX_CAP_N80 | TXC80-DIFF1 | PAIR | 8 | 5.38 | 5 | 10 | 5 | 50 | 6 | 33 | 12 | 12 | 12 | 12 | 6.62 | 85 Ohms | TOP=L2:L3=L2/L4:L6=L5/L7:BOTTOM=L7 |
| PCIE_TX_CAP_P80 | TXC80-DIFF1 | PAIR | 1 | 5.38 | 5 | 10 | 5 | 50 | 6 | 33 | 12 | 12 | 12 | 12 | 6.62 | 85 Ohms | TOP=L2:L3=L2/L4:L6=L5/L7:BOTTOM=L7 |
| PCIE_TX_CAP_P80 | TXC80-DIFF1 | PAIR | 2 | 5.5 | 5 | 10 | 5 | 50 | 6 | 20 | 12 | 12 | 12 | 12 | 7.5 | 85 Ohms | TOP=L2:L3=L2/L4:L6=L5/L7:BOTTOM=L7 |
| PCIE_TX_CAP_P80 | TXC80-DIFF1 | PAIR | 3 | 5.5 | 5 | 10 | 5 | 50 | 6 | 20 | 12 | 12 | 12 | 12 | 7.5 | 85 Ohms | TOP=L2:L3=L2/L4:L6=L5/L7:BOTTOM=L7 |
| PCIE_TX_CAP_P80 | TXC80-DIFF1 | PAIR | 4 | 5.5 | 5 | 10 | 5 | 50 | 6 | 20 | 12 | 12 | 12 | 12 | 7.5 | 85 Ohms | TOP=L2:L3=L2/L4:L6=L5/L7:BOTTOM=L7 |
| PCIE_TX_CAP_P80 | TXC80-DIFF1 | PAIR | 5 | 5.5 | 5 | 10 | 5 | 50 | 6 | 20 | 12 | 12 | 12 | 12 | 7.5 | 85 Ohms | TOP=L2:L3=L2/L4:L6=L5/L7:BOTTOM=L7 |
| PCIE_TX_CAP_P80 | TXC80-DIFF1 | PAIR | 6 | 5.5 | 5 | 10 | 5 | 50 | 6 | 20 | 12 | 12 | 12 | 12 | 7.5 | 85 Ohms | TOP=L2:L3=L2/L4:L6=L5/L7:BOTTOM=L7 |
| PCIE_TX_CAP_P80 | TXC80-DIFF1 | PAIR | 7 | 5.5 | 5 | 10 | 5 | 50 | 6 | 20 | 12 | 12 | 12 | 12 | 7.5 | 85 Ohms | TOP=L2:L3=L2/L4:L6=L5/L7:BOTTOM=L7 |
| PCIE_TX_CAP_P80 | TXC80-DIFF1 | PAIR | 8 | 5.38 | 5 | 10 | 5 | 50 | 6 | 33 | 12 | 12 | 12 | 12 | 6.62 | 85 Ohms | TOP=L2:L3=L2/L4:L6=L5/L7:BOTTOM=L7 |
| PCIE_TX_CAP_N81 | TXC81-DIFF1 | PAIR | 1 | 5.38 | 5 | 10 | 5 | 50 | 6 | 33 | 12 | 12 | 12 | 12 | 6.62 | 85 Ohms | TOP=L2:L3=L2/L4:L6=L5/L7:BOTTOM=L7 |
| PCIE_TX_CAP_N81 | TXC81-DIFF1 | PAIR | 2 | 5.5 | 5 | 10 | 5 | 50 | 6 | 20 | 12 | 12 | 12 | 12 | 7.5 | 85 Ohms | TOP=L2:L3=L2/L4:L6=L5/L7:BOTTOM=L7 |
| PCIE_TX_CAP_N81 | TXC81-DIFF1 | PAIR | 3 | 5.5 | 5 | 10 | 5 | 50 | 6 | 20 | 12 | 12 | 12 | 12 | 7.5 | 85 Ohms | TOP=L2:L3=L2/L4:L6=L5/L7:BOTTOM=L7 |
| PCIE_TX_CAP_N81 | TXC81-DIFF1 | PAIR | 4 | 5.5 | 5 | 10 | 5 | 50 | 6 | 20 | 12 | 12 | 12 | 12 | 7.5 | 85 Ohms | TOP=L2:L3=L2/L4:L6=L5/L7:BOTTOM=L7 |
| PCIE_TX_CAP_N81 | TXC81-DIFF1 | PAIR | 5 | 5.5 | 5 | 10 | 5 | 50 | 6 | 20 | 12 | 12 | 12 | 12 | 7.5 | 85 Ohms | TOP=L2:L3=L2/L4:L6=L5/L7:BOTTOM=L7 |
| PCIE_TX_CAP_N81 | TXC81-DIFF1 | PAIR | 6 | 5.5 | 5 | 10 | 5 | 50 | 6 | 20 | 12 | 12 | 12 | 12 | 7.5 | 85 Ohms | TOP=L2:L3=L2/L4:L6=L5/L7:BOTTOM=L7 |
| PCIE_TX_CAP_N81 | TXC81-DIFF1 | PAIR | 7 | 5.5 | 5 | 10 | 5 | 50 | 6 | 20 | 12 | 12 | 12 | 12 | 7.5 | 85 Ohms | TOP=L2:L3=L2/L4:L6=L5/L7:BOTTOM=L7 |
| PCIE_TX_CAP_N81 | TXC81-DIFF1 | PAIR | 8 | 5.38 | 5 | 10 | 5 | 50 | 6 | 33 | 12 | 12 | 12 | 12 | 6.62 | 85 Ohms | TOP=L2:L3=L2/L4:L6=L5/L7:BOTTOM=L7 |
| PCIE_TX_CAP_P81 | TXC81-DIFF1 | PAIR | 1 | 5.38 | 5 | 10 | 5 | 50 | 6 | 33 | 12 | 12 | 12 | 12 | 6.62 | 85 Ohms | TOP=L2:L3=L2/L4:L6=L5/L7:BOTTOM=L7 |
| PCIE_TX_CAP_P81 | TXC81-DIFF1 | PAIR | 2 | 5.5 | 5 | 10 | 5 | 50 | 6 | 20 | 12 | 12 | 12 | 12 | 7.5 | 85 Ohms | TOP=L2:L3=L2/L4:L6=L5/L7:BOTTOM=L7 |
| PCIE_TX_CAP_P81 | TXC81-DIFF1 | PAIR | 3 | 5.5 | 5 | 10 | 5 | 50 | 6 | 20 | 12 | 12 | 12 | 12 | 7.5 | 85 Ohms | TOP=L2:L3=L2/L4:L6=L5/L7:BOTTOM=L7 |
| PCIE_TX_CAP_P81 | TXC81-DIFF1 | PAIR | 4 | 5.5 | 5 | 10 | 5 | 50 | 6 | 20 | 12 | 12 | 12 | 12 | 7.5 | 85 Ohms | TOP=L2:L3=L2/L4:L6=L5/L7:BOTTOM=L7 |
| PCIE_TX_CAP_P81 | TXC81-DIFF1 | PAIR | 5 | 5.5 | 5 | 10 | 5 | 50 | 6 | 20 | 12 | 12 | 12 | 12 | 7.5 | 85 Ohms | TOP=L2:L3=L2/L4:L6=L5/L7:BOTTOM=L7 |
| PCIE_TX_CAP_P81 | TXC81-DIFF1 | PAIR | 6 | 5.5 | 5 | 10 | 5 | 50 | 6 | 20 | 12 | 12 | 12 | 12 | 7.5 | 85 Ohms | TOP=L2:L3=L2/L4:L6=L5/L7:BOTTOM=L7 |
| PCIE_TX_CAP_P81 | TXC81-DIFF1 | PAIR | 7 | 5.5 | 5 | 10 | 5 | 50 | 6 | 20 | 12 | 12 | 12 | 12 | 7.5 | 85 Ohms | TOP=L2:L3=L2/L4:L6=L5/L7:BOTTOM=L7 |
| PCIE_TX_CAP_P81 | TXC81-DIFF1 | PAIR | 8 | 5.38 | 5 | 10 | 5 | 50 | 6 | 33 | 12 | 12 | 12 | 12 | 6.62 | 85 Ohms | TOP=L2:L3=L2/L4:L6=L5/L7:BOTTOM=L7 |
| PCIE_TX_CAP_N82 | TXC82-DIFF1 | PAIR | 1 | 5.38 | 5 | 10 | 5 | 50 | 6 | 33 | 12 | 12 | 12 | 12 | 6.62 | 85 Ohms | TOP=L2:L3=L2/L4:L6=L5/L7:BOTTOM=L7 |
| PCIE_TX_CAP_N82 | TXC82-DIFF1 | PAIR | 2 | 5.5 | 5 | 10 | 5 | 50 | 6 | 20 | 12 | 12 | 12 | 12 | 7.5 | 85 Ohms | TOP=L2:L3=L2/L4:L6=L5/L7:BOTTOM=L7 |
| PCIE_TX_CAP_N82 | TXC82-DIFF1 | PAIR | 3 | 5.5 | 5 | 10 | 5 | 50 | 6 | 20 | 12 | 12 | 12 | 12 | 7.5 | 85 Ohms | TOP=L2:L3=L2/L4:L6=L5/L7:BOTTOM=L7 |
| PCIE_TX_CAP_N82 | TXC82-DIFF1 | PAIR | 4 | 5.5 | 5 | 10 | 5 | 50 | 6 | 20 | 12 | 12 | 12 | 12 | 7.5 | 85 Ohms | TOP=L2:L3=L2/L4:L6=L5/L7:BOTTOM=L7 |
| PCIE_TX_CAP_N82 | TXC82-DIFF1 | PAIR | 5 | 5.5 | 5 | 10 | 5 | 50 | 6 | 20 | 12 | 12 | 12 | 12 | 7.5 | 85 Ohms | TOP=L2:L3=L2/L4:L6=L5/L7:BOTTOM=L7 |
| PCIE_TX_CAP_N82 | TXC82-DIFF1 | PAIR | 6 | 5.5 | 5 | 10 | 5 | 50 | 6 | 20 | 12 | 12 | 12 | 12 | 7.5 | 85 Ohms | TOP=L2:L3=L2/L4:L6=L5/L7:BOTTOM=L7 |
| PCIE_TX_CAP_N82 | TXC82-DIFF1 | PAIR | 7 | 5.5 | 5 | 10 | 5 | 50 | 6 | 20 | 12 | 12 | 12 | 12 | 7.5 | 85 Ohms | TOP=L2:L3=L2/L4:L6=L5/L7:BOTTOM=L7 |
| PCIE_TX_CAP_N82 | TXC82-DIFF1 | PAIR | 8 | 5.38 | 5 | 10 | 5 | 50 | 6 | 33 | 12 | 12 | 12 | 12 | 6.62 | 85 Ohms | TOP=L2:L3=L2/L4:L6=L5/L7:BOTTOM=L7 |
| PCIE_TX_CAP_P82 | TXC82-DIFF1 | PAIR | 1 | 5.38 | 5 | 10 | 5 | 50 | 6 | 33 | 12 | 12 | 12 | 12 | 6.62 | 85 Ohms | TOP=L2:L3=L2/L4:L6=L5/L7:BOTTOM=L7 |
| PCIE_TX_CAP_P82 | TXC82-DIFF1 | PAIR | 2 | 5.5 | 5 | 10 | 5 | 50 | 6 | 20 | 12 | 12 | 12 | 12 | 7.5 | 85 Ohms | TOP=L2:L3=L2/L4:L6=L5/L7:BOTTOM=L7 |
| PCIE_TX_CAP_P82 | TXC82-DIFF1 | PAIR | 3 | 5.5 | 5 | 10 | 5 | 50 | 6 | 20 | 12 | 12 | 12 | 12 | 7.5 | 85 Ohms | TOP=L2:L3=L2/L4:L6=L5/L7:BOTTOM=L7 |
| PCIE_TX_CAP_P82 | TXC82-DIFF1 | PAIR | 4 | 5.5 | 5 | 10 | 5 | 50 | 6 | 20 | 12 | 12 | 12 | 12 | 7.5 | 85 Ohms | TOP=L2:L3=L2/L4:L6=L5/L7:BOTTOM=L7 |
| PCIE_TX_CAP_P82 | TXC82-DIFF1 | PAIR | 5 | 5.5 | 5 | 10 | 5 | 50 | 6 | 20 | 12 | 12 | 12 | 12 | 7.5 | 85 Ohms | TOP=L2:L3=L2/L4:L6=L5/L7:BOTTOM=L7 |
| PCIE_TX_CAP_P82 | TXC82-DIFF1 | PAIR | 6 | 5.5 | 5 | 10 | 5 | 50 | 6 | 20 | 12 | 12 | 12 | 12 | 7.5 | 85 Ohms | TOP=L2:L3=L2/L4:L6=L5/L7:BOTTOM=L7 |
| PCIE_TX_CAP_P82 | TXC82-DIFF1 | PAIR | 7 | 5.5 | 5 | 10 | 5 | 50 | 6 | 20 | 12 | 12 | 12 | 12 | 7.5 | 85 Ohms | TOP=L2:L3=L2/L4:L6=L5/L7:BOTTOM=L7 |
| PCIE_TX_CAP_P82 | TXC82-DIFF1 | PAIR | 8 | 5.38 | 5 | 10 | 5 | 50 | 6 | 33 | 12 | 12 | 12 | 12 | 6.62 | 85 Ohms | TOP=L2:L3=L2/L4:L6=L5/L7:BOTTOM=L7 |
| PCIE_TX_CAP_N83 | TXC83-DIFF1 | PAIR | 1 | 5.38 | 5 | 10 | 5 | 50 | 6 | 33 | 12 | 12 | 12 | 12 | 6.62 | 85 Ohms | TOP=L2:L3=L2/L4:L6=L5/L7:BOTTOM=L7 |
| PCIE_TX_CAP_N83 | TXC83-DIFF1 | PAIR | 2 | 5.5 | 5 | 10 | 5 | 50 | 6 | 20 | 12 | 12 | 12 | 12 | 7.5 | 85 Ohms | TOP=L2:L3=L2/L4:L6=L5/L7:BOTTOM=L7 |
| PCIE_TX_CAP_N83 | TXC83-DIFF1 | PAIR | 3 | 5.5 | 5 | 10 | 5 | 50 | 6 | 20 | 12 | 12 | 12 | 12 | 7.5 | 85 Ohms | TOP=L2:L3=L2/L4:L6=L5/L7:BOTTOM=L7 |
| PCIE_TX_CAP_N83 | TXC83-DIFF1 | PAIR | 4 | 5.5 | 5 | 10 | 5 | 50 | 6 | 20 | 12 | 12 | 12 | 12 | 7.5 | 85 Ohms | TOP=L2:L3=L2/L4:L6=L5/L7:BOTTOM=L7 |
| PCIE_TX_CAP_N83 | TXC83-DIFF1 | PAIR | 5 | 5.5 | 5 | 10 | 5 | 50 | 6 | 20 | 12 | 12 | 12 | 12 | 7.5 | 85 Ohms | TOP=L2:L3=L2/L4:L6=L5/L7:BOTTOM=L7 |
| PCIE_TX_CAP_N83 | TXC83-DIFF1 | PAIR | 6 | 5.5 | 5 | 10 | 5 | 50 | 6 | 20 | 12 | 12 | 12 | 12 | 7.5 | 85 Ohms | TOP=L2:L3=L2/L4:L6=L5/L7:BOTTOM=L7 |
| PCIE_TX_CAP_N83 | TXC83-DIFF1 | PAIR | 7 | 5.5 | 5 | 10 | 5 | 50 | 6 | 20 | 12 | 12 | 12 | 12 | 7.5 | 85 Ohms | TOP=L2:L3=L2/L4:L6=L5/L7:BOTTOM=L7 |
| PCIE_TX_CAP_N83 | TXC83-DIFF1 | PAIR | 8 | 5.38 | 5 | 10 | 5 | 50 | 6 | 33 | 12 | 12 | 12 | 12 | 6.62 | 85 Ohms | TOP=L2:L3=L2/L4:L6=L5/L7:BOTTOM=L7 |
| PCIE_TX_CAP_P83 | TXC83-DIFF1 | PAIR | 1 | 5.38 | 5 | 10 | 5 | 50 | 6 | 33 | 12 | 12 | 12 | 12 | 6.62 | 85 Ohms | TOP=L2:L3=L2/L4:L6=L5/L7:BOTTOM=L7 |
| PCIE_TX_CAP_P83 | TXC83-DIFF1 | PAIR | 2 | 5.5 | 5 | 10 | 5 | 50 | 6 | 20 | 12 | 12 | 12 | 12 | 7.5 | 85 Ohms | TOP=L2:L3=L2/L4:L6=L5/L7:BOTTOM=L7 |
| PCIE_TX_CAP_P83 | TXC83-DIFF1 | PAIR | 3 | 5.5 | 5 | 10 | 5 | 50 | 6 | 20 | 12 | 12 | 12 | 12 | 7.5 | 85 Ohms | TOP=L2:L3=L2/L4:L6=L5/L7:BOTTOM=L7 |
| PCIE_TX_CAP_P83 | TXC83-DIFF1 | PAIR | 4 | 5.5 | 5 | 10 | 5 | 50 | 6 | 20 | 12 | 12 | 12 | 12 | 7.5 | 85 Ohms | TOP=L2:L3=L2/L4:L6=L5/L7:BOTTOM=L7 |
| PCIE_TX_CAP_P83 | TXC83-DIFF1 | PAIR | 5 | 5.5 | 5 | 10 | 5 | 50 | 6 | 20 | 12 | 12 | 12 | 12 | 7.5 | 85 Ohms | TOP=L2:L3=L2/L4:L6=L5/L7:BOTTOM=L7 |
| PCIE_TX_CAP_P83 | TXC83-DIFF1 | PAIR | 6 | 5.5 | 5 | 10 | 5 | 50 | 6 | 20 | 12 | 12 | 12 | 12 | 7.5 | 85 Ohms | TOP=L2:L3=L2/L4:L6=L5/L7:BOTTOM=L7 |
| PCIE_TX_CAP_P83 | TXC83-DIFF1 | PAIR | 7 | 5.5 | 5 | 10 | 5 | 50 | 6 | 20 | 12 | 12 | 12 | 12 | 7.5 | 85 Ohms | TOP=L2:L3=L2/L4:L6=L5/L7:BOTTOM=L7 |
| PCIE_TX_CAP_P83 | TXC83-DIFF1 | PAIR | 8 | 5.38 | 5 | 10 | 5 | 50 | 6 | 33 | 12 | 12 | 12 | 12 | 6.62 | 85 Ohms | TOP=L2:L3=L2/L4:L6=L5/L7:BOTTOM=L7 |
| PCIE_TX_CAP_N84 | TXC84-DIFF1 | PAIR | 1 | 5.38 | 5 | 10 | 5 | 50 | 6 | 33 | 12 | 12 | 12 | 12 | 6.62 | 85 Ohms | TOP=L2:L3=L2/L4:L6=L5/L7:BOTTOM=L7 |
| PCIE_TX_CAP_N84 | TXC84-DIFF1 | PAIR | 2 | 5.5 | 5 | 10 | 5 | 50 | 6 | 20 | 12 | 12 | 12 | 12 | 7.5 | 85 Ohms | TOP=L2:L3=L2/L4:L6=L5/L7:BOTTOM=L7 |
| PCIE_TX_CAP_N84 | TXC84-DIFF1 | PAIR | 3 | 5.5 | 5 | 10 | 5 | 50 | 6 | 20 | 12 | 12 | 12 | 12 | 7.5 | 85 Ohms | TOP=L2:L3=L2/L4:L6=L5/L7:BOTTOM=L7 |
| PCIE_TX_CAP_N84 | TXC84-DIFF1 | PAIR | 4 | 5.5 | 5 | 10 | 5 | 50 | 6 | 20 | 12 | 12 | 12 | 12 | 7.5 | 85 Ohms | TOP=L2:L3=L2/L4:L6=L5/L7:BOTTOM=L7 |
| PCIE_TX_CAP_N84 | TXC84-DIFF1 | PAIR | 5 | 5.5 | 5 | 10 | 5 | 50 | 6 | 20 | 12 | 12 | 12 | 12 | 7.5 | 85 Ohms | TOP=L2:L3=L2/L4:L6=L5/L7:BOTTOM=L7 |
| PCIE_TX_CAP_N84 | TXC84-DIFF1 | PAIR | 6 | 5.5 | 5 | 10 | 5 | 50 | 6 | 20 | 12 | 12 | 12 | 12 | 7.5 | 85 Ohms | TOP=L2:L3=L2/L4:L6=L5/L7:BOTTOM=L7 |
| PCIE_TX_CAP_N84 | TXC84-DIFF1 | PAIR | 7 | 5.5 | 5 | 10 | 5 | 50 | 6 | 20 | 12 | 12 | 12 | 12 | 7.5 | 85 Ohms | TOP=L2:L3=L2/L4:L6=L5/L7:BOTTOM=L7 |
| PCIE_TX_CAP_N84 | TXC84-DIFF1 | PAIR | 8 | 5.38 | 5 | 10 | 5 | 50 | 6 | 33 | 12 | 12 | 12 | 12 | 6.62 | 85 Ohms | TOP=L2:L3=L2/L4:L6=L5/L7:BOTTOM=L7 |
| PCIE_TX_CAP_P84 | TXC84-DIFF1 | PAIR | 1 | 5.38 | 5 | 10 | 5 | 50 | 6 | 33 | 12 | 12 | 12 | 12 | 6.62 | 85 Ohms | TOP=L2:L3=L2/L4:L6=L5/L7:BOTTOM=L7 |
| PCIE_TX_CAP_P84 | TXC84-DIFF1 | PAIR | 2 | 5.5 | 5 | 10 | 5 | 50 | 6 | 20 | 12 | 12 | 12 | 12 | 7.5 | 85 Ohms | TOP=L2:L3=L2/L4:L6=L5/L7:BOTTOM=L7 |
| PCIE_TX_CAP_P84 | TXC84-DIFF1 | PAIR | 3 | 5.5 | 5 | 10 | 5 | 50 | 6 | 20 | 12 | 12 | 12 | 12 | 7.5 | 85 Ohms | TOP=L2:L3=L2/L4:L6=L5/L7:BOTTOM=L7 |
| PCIE_TX_CAP_P84 | TXC84-DIFF1 | PAIR | 4 | 5.5 | 5 | 10 | 5 | 50 | 6 | 20 | 12 | 12 | 12 | 12 | 7.5 | 85 Ohms | TOP=L2:L3=L2/L4:L6=L5/L7:BOTTOM=L7 |
| PCIE_TX_CAP_P84 | TXC84-DIFF1 | PAIR | 5 | 5.5 | 5 | 10 | 5 | 50 | 6 | 20 | 12 | 12 | 12 | 12 | 7.5 | 85 Ohms | TOP=L2:L3=L2/L4:L6=L5/L7:BOTTOM=L7 |
| PCIE_TX_CAP_P84 | TXC84-DIFF1 | PAIR | 6 | 5.5 | 5 | 10 | 5 | 50 | 6 | 20 | 12 | 12 | 12 | 12 | 7.5 | 85 Ohms | TOP=L2:L3=L2/L4:L6=L5/L7:BOTTOM=L7 |
| PCIE_TX_CAP_P84 | TXC84-DIFF1 | PAIR | 7 | 5.5 | 5 | 10 | 5 | 50 | 6 | 20 | 12 | 12 | 12 | 12 | 7.5 | 85 Ohms | TOP=L2:L3=L2/L4:L6=L5/L7:BOTTOM=L7 |
| PCIE_TX_CAP_P84 | TXC84-DIFF1 | PAIR | 8 | 5.38 | 5 | 10 | 5 | 50 | 6 | 33 | 12 | 12 | 12 | 12 | 6.62 | 85 Ohms | TOP=L2:L3=L2/L4:L6=L5/L7:BOTTOM=L7 |
| PCIE_TX_CAP_N85 | TXC85-DIFF1 | PAIR | 1 | 5.38 | 5 | 10 | 5 | 50 | 6 | 33 | 12 | 12 | 12 | 12 | 6.62 | 85 Ohms | TOP=L2:L3=L2/L4:L6=L5/L7:BOTTOM=L7 |
| PCIE_TX_CAP_N85 | TXC85-DIFF1 | PAIR | 2 | 5.5 | 5 | 10 | 5 | 50 | 6 | 20 | 12 | 12 | 12 | 12 | 7.5 | 85 Ohms | TOP=L2:L3=L2/L4:L6=L5/L7:BOTTOM=L7 |
| PCIE_TX_CAP_N85 | TXC85-DIFF1 | PAIR | 3 | 5.5 | 5 | 10 | 5 | 50 | 6 | 20 | 12 | 12 | 12 | 12 | 7.5 | 85 Ohms | TOP=L2:L3=L2/L4:L6=L5/L7:BOTTOM=L7 |
| PCIE_TX_CAP_N85 | TXC85-DIFF1 | PAIR | 4 | 5.5 | 5 | 10 | 5 | 50 | 6 | 20 | 12 | 12 | 12 | 12 | 7.5 | 85 Ohms | TOP=L2:L3=L2/L4:L6=L5/L7:BOTTOM=L7 |
| PCIE_TX_CAP_N85 | TXC85-DIFF1 | PAIR | 5 | 5.5 | 5 | 10 | 5 | 50 | 6 | 20 | 12 | 12 | 12 | 12 | 7.5 | 85 Ohms | TOP=L2:L3=L2/L4:L6=L5/L7:BOTTOM=L7 |
| PCIE_TX_CAP_N85 | TXC85-DIFF1 | PAIR | 6 | 5.5 | 5 | 10 | 5 | 50 | 6 | 20 | 12 | 12 | 12 | 12 | 7.5 | 85 Ohms | TOP=L2:L3=L2/L4:L6=L5/L7:BOTTOM=L7 |
| PCIE_TX_CAP_N85 | TXC85-DIFF1 | PAIR | 7 | 5.5 | 5 | 10 | 5 | 50 | 6 | 20 | 12 | 12 | 12 | 12 | 7.5 | 85 Ohms | TOP=L2:L3=L2/L4:L6=L5/L7:BOTTOM=L7 |
| PCIE_TX_CAP_N85 | TXC85-DIFF1 | PAIR | 8 | 5.38 | 5 | 10 | 5 | 50 | 6 | 33 | 12 | 12 | 12 | 12 | 6.62 | 85 Ohms | TOP=L2:L3=L2/L4:L6=L5/L7:BOTTOM=L7 |
| PCIE_TX_CAP_P85 | TXC85-DIFF1 | PAIR | 1 | 5.38 | 5 | 10 | 5 | 50 | 6 | 33 | 12 | 12 | 12 | 12 | 6.62 | 85 Ohms | TOP=L2:L3=L2/L4:L6=L5/L7:BOTTOM=L7 |
| PCIE_TX_CAP_P85 | TXC85-DIFF1 | PAIR | 2 | 5.5 | 5 | 10 | 5 | 50 | 6 | 20 | 12 | 12 | 12 | 12 | 7.5 | 85 Ohms | TOP=L2:L3=L2/L4:L6=L5/L7:BOTTOM=L7 |
| PCIE_TX_CAP_P85 | TXC85-DIFF1 | PAIR | 3 | 5.5 | 5 | 10 | 5 | 50 | 6 | 20 | 12 | 12 | 12 | 12 | 7.5 | 85 Ohms | TOP=L2:L3=L2/L4:L6=L5/L7:BOTTOM=L7 |
| PCIE_TX_CAP_P85 | TXC85-DIFF1 | PAIR | 4 | 5.5 | 5 | 10 | 5 | 50 | 6 | 20 | 12 | 12 | 12 | 12 | 7.5 | 85 Ohms | TOP=L2:L3=L2/L4:L6=L5/L7:BOTTOM=L7 |
| PCIE_TX_CAP_P85 | TXC85-DIFF1 | PAIR | 5 | 5.5 | 5 | 10 | 5 | 50 | 6 | 20 | 12 | 12 | 12 | 12 | 7.5 | 85 Ohms | TOP=L2:L3=L2/L4:L6=L5/L7:BOTTOM=L7 |
| PCIE_TX_CAP_P85 | TXC85-DIFF1 | PAIR | 6 | 5.5 | 5 | 10 | 5 | 50 | 6 | 20 | 12 | 12 | 12 | 12 | 7.5 | 85 Ohms | TOP=L2:L3=L2/L4:L6=L5/L7:BOTTOM=L7 |
| PCIE_TX_CAP_P85 | TXC85-DIFF1 | PAIR | 7 | 5.5 | 5 | 10 | 5 | 50 | 6 | 20 | 12 | 12 | 12 | 12 | 7.5 | 85 Ohms | TOP=L2:L3=L2/L4:L6=L5/L7:BOTTOM=L7 |
| PCIE_TX_CAP_P85 | TXC85-DIFF1 | PAIR | 8 | 5.38 | 5 | 10 | 5 | 50 | 6 | 33 | 12 | 12 | 12 | 12 | 6.62 | 85 Ohms | TOP=L2:L3=L2/L4:L6=L5/L7:BOTTOM=L7 |
| PCIE_TX_CAP_N86 | TXC86-DIFF1 | PAIR | 1 | 5.38 | 5 | 10 | 5 | 50 | 6 | 33 | 12 | 12 | 12 | 12 | 6.62 | 85 Ohms | TOP=L2:L3=L2/L4:L6=L5/L7:BOTTOM=L7 |
| PCIE_TX_CAP_N86 | TXC86-DIFF1 | PAIR | 2 | 5.5 | 5 | 10 | 5 | 50 | 6 | 20 | 12 | 12 | 12 | 12 | 7.5 | 85 Ohms | TOP=L2:L3=L2/L4:L6=L5/L7:BOTTOM=L7 |
| PCIE_TX_CAP_N86 | TXC86-DIFF1 | PAIR | 3 | 5.5 | 5 | 10 | 5 | 50 | 6 | 20 | 12 | 12 | 12 | 12 | 7.5 | 85 Ohms | TOP=L2:L3=L2/L4:L6=L5/L7:BOTTOM=L7 |
| PCIE_TX_CAP_N86 | TXC86-DIFF1 | PAIR | 4 | 5.5 | 5 | 10 | 5 | 50 | 6 | 20 | 12 | 12 | 12 | 12 | 7.5 | 85 Ohms | TOP=L2:L3=L2/L4:L6=L5/L7:BOTTOM=L7 |
| PCIE_TX_CAP_N86 | TXC86-DIFF1 | PAIR | 5 | 5.5 | 5 | 10 | 5 | 50 | 6 | 20 | 12 | 12 | 12 | 12 | 7.5 | 85 Ohms | TOP=L2:L3=L2/L4:L6=L5/L7:BOTTOM=L7 |
| PCIE_TX_CAP_N86 | TXC86-DIFF1 | PAIR | 6 | 5.5 | 5 | 10 | 5 | 50 | 6 | 20 | 12 | 12 | 12 | 12 | 7.5 | 85 Ohms | TOP=L2:L3=L2/L4:L6=L5/L7:BOTTOM=L7 |
| PCIE_TX_CAP_N86 | TXC86-DIFF1 | PAIR | 7 | 5.5 | 5 | 10 | 5 | 50 | 6 | 20 | 12 | 12 | 12 | 12 | 7.5 | 85 Ohms | TOP=L2:L3=L2/L4:L6=L5/L7:BOTTOM=L7 |
| PCIE_TX_CAP_N86 | TXC86-DIFF1 | PAIR | 8 | 5.38 | 5 | 10 | 5 | 50 | 6 | 33 | 12 | 12 | 12 | 12 | 6.62 | 85 Ohms | TOP=L2:L3=L2/L4:L6=L5/L7:BOTTOM=L7 |
| PCIE_TX_CAP_P86 | TXC86-DIFF1 | PAIR | 1 | 5.38 | 5 | 10 | 5 | 50 | 6 | 33 | 12 | 12 | 12 | 12 | 6.62 | 85 Ohms | TOP=L2:L3=L2/L4:L6=L5/L7:BOTTOM=L7 |
| PCIE_TX_CAP_P86 | TXC86-DIFF1 | PAIR | 2 | 5.5 | 5 | 10 | 5 | 50 | 6 | 20 | 12 | 12 | 12 | 12 | 7.5 | 85 Ohms | TOP=L2:L3=L2/L4:L6=L5/L7:BOTTOM=L7 |
| PCIE_TX_CAP_P86 | TXC86-DIFF1 | PAIR | 3 | 5.5 | 5 | 10 | 5 | 50 | 6 | 20 | 12 | 12 | 12 | 12 | 7.5 | 85 Ohms | TOP=L2:L3=L2/L4:L6=L5/L7:BOTTOM=L7 |
| PCIE_TX_CAP_P86 | TXC86-DIFF1 | PAIR | 4 | 5.5 | 5 | 10 | 5 | 50 | 6 | 20 | 12 | 12 | 12 | 12 | 7.5 | 85 Ohms | TOP=L2:L3=L2/L4:L6=L5/L7:BOTTOM=L7 |
| PCIE_TX_CAP_P86 | TXC86-DIFF1 | PAIR | 5 | 5.5 | 5 | 10 | 5 | 50 | 6 | 20 | 12 | 12 | 12 | 12 | 7.5 | 85 Ohms | TOP=L2:L3=L2/L4:L6=L5/L7:BOTTOM=L7 |
| PCIE_TX_CAP_P86 | TXC86-DIFF1 | PAIR | 6 | 5.5 | 5 | 10 | 5 | 50 | 6 | 20 | 12 | 12 | 12 | 12 | 7.5 | 85 Ohms | TOP=L2:L3=L2/L4:L6=L5/L7:BOTTOM=L7 |
| PCIE_TX_CAP_P86 | TXC86-DIFF1 | PAIR | 7 | 5.5 | 5 | 10 | 5 | 50 | 6 | 20 | 12 | 12 | 12 | 12 | 7.5 | 85 Ohms | TOP=L2:L3=L2/L4:L6=L5/L7:BOTTOM=L7 |
| PCIE_TX_CAP_P86 | TXC86-DIFF1 | PAIR | 8 | 5.38 | 5 | 10 | 5 | 50 | 6 | 33 | 12 | 12 | 12 | 12 | 6.62 | 85 Ohms | TOP=L2:L3=L2/L4:L6=L5/L7:BOTTOM=L7 |
| PCIE_TX_CAP_N87 | TXC87-DIFF1 | PAIR | 1 | 5.38 | 5 | 10 | 5 | 50 | 6 | 33 | 12 | 12 | 12 | 12 | 6.62 | 85 Ohms | TOP=L2:L3=L2/L4:L6=L5/L7:BOTTOM=L7 |
| PCIE_TX_CAP_N87 | TXC87-DIFF1 | PAIR | 2 | 5.5 | 5 | 10 | 5 | 50 | 6 | 20 | 12 | 12 | 12 | 12 | 7.5 | 85 Ohms | TOP=L2:L3=L2/L4:L6=L5/L7:BOTTOM=L7 |
| PCIE_TX_CAP_N87 | TXC87-DIFF1 | PAIR | 3 | 5.5 | 5 | 10 | 5 | 50 | 6 | 20 | 12 | 12 | 12 | 12 | 7.5 | 85 Ohms | TOP=L2:L3=L2/L4:L6=L5/L7:BOTTOM=L7 |
| PCIE_TX_CAP_N87 | TXC87-DIFF1 | PAIR | 4 | 5.5 | 5 | 10 | 5 | 50 | 6 | 20 | 12 | 12 | 12 | 12 | 7.5 | 85 Ohms | TOP=L2:L3=L2/L4:L6=L5/L7:BOTTOM=L7 |
| PCIE_TX_CAP_N87 | TXC87-DIFF1 | PAIR | 5 | 5.5 | 5 | 10 | 5 | 50 | 6 | 20 | 12 | 12 | 12 | 12 | 7.5 | 85 Ohms | TOP=L2:L3=L2/L4:L6=L5/L7:BOTTOM=L7 |
| PCIE_TX_CAP_N87 | TXC87-DIFF1 | PAIR | 6 | 5.5 | 5 | 10 | 5 | 50 | 6 | 20 | 12 | 12 | 12 | 12 | 7.5 | 85 Ohms | TOP=L2:L3=L2/L4:L6=L5/L7:BOTTOM=L7 |
| PCIE_TX_CAP_N87 | TXC87-DIFF1 | PAIR | 7 | 5.5 | 5 | 10 | 5 | 50 | 6 | 20 | 12 | 12 | 12 | 12 | 7.5 | 85 Ohms | TOP=L2:L3=L2/L4:L6=L5/L7:BOTTOM=L7 |
| PCIE_TX_CAP_N87 | TXC87-DIFF1 | PAIR | 8 | 5.38 | 5 | 10 | 5 | 50 | 6 | 33 | 12 | 12 | 12 | 12 | 6.62 | 85 Ohms | TOP=L2:L3=L2/L4:L6=L5/L7:BOTTOM=L7 |
| PCIE_TX_CAP_P87 | TXC87-DIFF1 | PAIR | 1 | 5.38 | 5 | 10 | 5 | 50 | 6 | 33 | 12 | 12 | 12 | 12 | 6.62 | 85 Ohms | TOP=L2:L3=L2/L4:L6=L5/L7:BOTTOM=L7 |
| PCIE_TX_CAP_P87 | TXC87-DIFF1 | PAIR | 2 | 5.5 | 5 | 10 | 5 | 50 | 6 | 20 | 12 | 12 | 12 | 12 | 7.5 | 85 Ohms | TOP=L2:L3=L2/L4:L6=L5/L7:BOTTOM=L7 |
| PCIE_TX_CAP_P87 | TXC87-DIFF1 | PAIR | 3 | 5.5 | 5 | 10 | 5 | 50 | 6 | 20 | 12 | 12 | 12 | 12 | 7.5 | 85 Ohms | TOP=L2:L3=L2/L4:L6=L5/L7:BOTTOM=L7 |
| PCIE_TX_CAP_P87 | TXC87-DIFF1 | PAIR | 4 | 5.5 | 5 | 10 | 5 | 50 | 6 | 20 | 12 | 12 | 12 | 12 | 7.5 | 85 Ohms | TOP=L2:L3=L2/L4:L6=L5/L7:BOTTOM=L7 |
| PCIE_TX_CAP_P87 | TXC87-DIFF1 | PAIR | 5 | 5.5 | 5 | 10 | 5 | 50 | 6 | 20 | 12 | 12 | 12 | 12 | 7.5 | 85 Ohms | TOP=L2:L3=L2/L4:L6=L5/L7:BOTTOM=L7 |
| PCIE_TX_CAP_P87 | TXC87-DIFF1 | PAIR | 6 | 5.5 | 5 | 10 | 5 | 50 | 6 | 20 | 12 | 12 | 12 | 12 | 7.5 | 85 Ohms | TOP=L2:L3=L2/L4:L6=L5/L7:BOTTOM=L7 |
| PCIE_TX_CAP_P87 | TXC87-DIFF1 | PAIR | 7 | 5.5 | 5 | 10 | 5 | 50 | 6 | 20 | 12 | 12 | 12 | 12 | 7.5 | 85 Ohms | TOP=L2:L3=L2/L4:L6=L5/L7:BOTTOM=L7 |
| PCIE_TX_CAP_P87 | TXC87-DIFF1 | PAIR | 8 | 5.38 | 5 | 10 | 5 | 50 | 6 | 33 | 12 | 12 | 12 | 12 | 6.62 | 85 Ohms | TOP=L2:L3=L2/L4:L6=L5/L7:BOTTOM=L7 |
| PCIE_TX_CAP_N88 | TXC88-DIFF1 | PAIR | 1 | 5.38 | 5 | 10 | 5 | 50 | 6 | 33 | 12 | 12 | 12 | 12 | 6.62 | 85 Ohms | TOP=L2:L3=L2/L4:L6=L5/L7:BOTTOM=L7 |
| PCIE_TX_CAP_N88 | TXC88-DIFF1 | PAIR | 2 | 5.5 | 5 | 10 | 5 | 50 | 6 | 20 | 12 | 12 | 12 | 12 | 7.5 | 85 Ohms | TOP=L2:L3=L2/L4:L6=L5/L7:BOTTOM=L7 |
| PCIE_TX_CAP_N88 | TXC88-DIFF1 | PAIR | 3 | 5.5 | 5 | 10 | 5 | 50 | 6 | 20 | 12 | 12 | 12 | 12 | 7.5 | 85 Ohms | TOP=L2:L3=L2/L4:L6=L5/L7:BOTTOM=L7 |
| PCIE_TX_CAP_N88 | TXC88-DIFF1 | PAIR | 4 | 5.5 | 5 | 10 | 5 | 50 | 6 | 20 | 12 | 12 | 12 | 12 | 7.5 | 85 Ohms | TOP=L2:L3=L2/L4:L6=L5/L7:BOTTOM=L7 |
| PCIE_TX_CAP_N88 | TXC88-DIFF1 | PAIR | 5 | 5.5 | 5 | 10 | 5 | 50 | 6 | 20 | 12 | 12 | 12 | 12 | 7.5 | 85 Ohms | TOP=L2:L3=L2/L4:L6=L5/L7:BOTTOM=L7 |
| PCIE_TX_CAP_N88 | TXC88-DIFF1 | PAIR | 6 | 5.5 | 5 | 10 | 5 | 50 | 6 | 20 | 12 | 12 | 12 | 12 | 7.5 | 85 Ohms | TOP=L2:L3=L2/L4:L6=L5/L7:BOTTOM=L7 |
| PCIE_TX_CAP_N88 | TXC88-DIFF1 | PAIR | 7 | 5.5 | 5 | 10 | 5 | 50 | 6 | 20 | 12 | 12 | 12 | 12 | 7.5 | 85 Ohms | TOP=L2:L3=L2/L4:L6=L5/L7:BOTTOM=L7 |
| PCIE_TX_CAP_N88 | TXC88-DIFF1 | PAIR | 8 | 5.38 | 5 | 10 | 5 | 50 | 6 | 33 | 12 | 12 | 12 | 12 | 6.62 | 85 Ohms | TOP=L2:L3=L2/L4:L6=L5/L7:BOTTOM=L7 |
| PCIE_TX_CAP_P88 | TXC88-DIFF1 | PAIR | 1 | 5.38 | 5 | 10 | 5 | 50 | 6 | 33 | 12 | 12 | 12 | 12 | 6.62 | 85 Ohms | TOP=L2:L3=L2/L4:L6=L5/L7:BOTTOM=L7 |
| PCIE_TX_CAP_P88 | TXC88-DIFF1 | PAIR | 2 | 5.5 | 5 | 10 | 5 | 50 | 6 | 20 | 12 | 12 | 12 | 12 | 7.5 | 85 Ohms | TOP=L2:L3=L2/L4:L6=L5/L7:BOTTOM=L7 |
| PCIE_TX_CAP_P88 | TXC88-DIFF1 | PAIR | 3 | 5.5 | 5 | 10 | 5 | 50 | 6 | 20 | 12 | 12 | 12 | 12 | 7.5 | 85 Ohms | TOP=L2:L3=L2/L4:L6=L5/L7:BOTTOM=L7 |
| PCIE_TX_CAP_P88 | TXC88-DIFF1 | PAIR | 4 | 5.5 | 5 | 10 | 5 | 50 | 6 | 20 | 12 | 12 | 12 | 12 | 7.5 | 85 Ohms | TOP=L2:L3=L2/L4:L6=L5/L7:BOTTOM=L7 |
| PCIE_TX_CAP_P88 | TXC88-DIFF1 | PAIR | 5 | 5.5 | 5 | 10 | 5 | 50 | 6 | 20 | 12 | 12 | 12 | 12 | 7.5 | 85 Ohms | TOP=L2:L3=L2/L4:L6=L5/L7:BOTTOM=L7 |
| PCIE_TX_CAP_P88 | TXC88-DIFF1 | PAIR | 6 | 5.5 | 5 | 10 | 5 | 50 | 6 | 20 | 12 | 12 | 12 | 12 | 7.5 | 85 Ohms | TOP=L2:L3=L2/L4:L6=L5/L7:BOTTOM=L7 |
| PCIE_TX_CAP_P88 | TXC88-DIFF1 | PAIR | 7 | 5.5 | 5 | 10 | 5 | 50 | 6 | 20 | 12 | 12 | 12 | 12 | 7.5 | 85 Ohms | TOP=L2:L3=L2/L4:L6=L5/L7:BOTTOM=L7 |
| PCIE_TX_CAP_P88 | TXC88-DIFF1 | PAIR | 8 | 5.38 | 5 | 10 | 5 | 50 | 6 | 33 | 12 | 12 | 12 | 12 | 6.62 | 85 Ohms | TOP=L2:L3=L2/L4:L6=L5/L7:BOTTOM=L7 |
| PCIE_TX_CAP_N89 | TXC89-DIFF1 | PAIR | 1 | 5.38 | 5 | 10 | 5 | 50 | 6 | 33 | 12 | 12 | 12 | 12 | 6.62 | 85 Ohms | TOP=L2:L3=L2/L4:L6=L5/L7:BOTTOM=L7 |
| PCIE_TX_CAP_N89 | TXC89-DIFF1 | PAIR | 2 | 5.5 | 5 | 10 | 5 | 50 | 6 | 20 | 12 | 12 | 12 | 12 | 7.5 | 85 Ohms | TOP=L2:L3=L2/L4:L6=L5/L7:BOTTOM=L7 |
| PCIE_TX_CAP_N89 | TXC89-DIFF1 | PAIR | 3 | 5.5 | 5 | 10 | 5 | 50 | 6 | 20 | 12 | 12 | 12 | 12 | 7.5 | 85 Ohms | TOP=L2:L3=L2/L4:L6=L5/L7:BOTTOM=L7 |
| PCIE_TX_CAP_N89 | TXC89-DIFF1 | PAIR | 4 | 5.5 | 5 | 10 | 5 | 50 | 6 | 20 | 12 | 12 | 12 | 12 | 7.5 | 85 Ohms | TOP=L2:L3=L2/L4:L6=L5/L7:BOTTOM=L7 |
| PCIE_TX_CAP_N89 | TXC89-DIFF1 | PAIR | 5 | 5.5 | 5 | 10 | 5 | 50 | 6 | 20 | 12 | 12 | 12 | 12 | 7.5 | 85 Ohms | TOP=L2:L3=L2/L4:L6=L5/L7:BOTTOM=L7 |
| PCIE_TX_CAP_N89 | TXC89-DIFF1 | PAIR | 6 | 5.5 | 5 | 10 | 5 | 50 | 6 | 20 | 12 | 12 | 12 | 12 | 7.5 | 85 Ohms | TOP=L2:L3=L2/L4:L6=L5/L7:BOTTOM=L7 |
| PCIE_TX_CAP_N89 | TXC89-DIFF1 | PAIR | 7 | 5.5 | 5 | 10 | 5 | 50 | 6 | 20 | 12 | 12 | 12 | 12 | 7.5 | 85 Ohms | TOP=L2:L3=L2/L4:L6=L5/L7:BOTTOM=L7 |
| PCIE_TX_CAP_N89 | TXC89-DIFF1 | PAIR | 8 | 5.38 | 5 | 10 | 5 | 50 | 6 | 33 | 12 | 12 | 12 | 12 | 6.62 | 85 Ohms | TOP=L2:L3=L2/L4:L6=L5/L7:BOTTOM=L7 |
| PCIE_TX_CAP_P89 | TXC89-DIFF1 | PAIR | 1 | 5.38 | 5 | 10 | 5 | 50 | 6 | 33 | 12 | 12 | 12 | 12 | 6.62 | 85 Ohms | TOP=L2:L3=L2/L4:L6=L5/L7:BOTTOM=L7 |
| PCIE_TX_CAP_P89 | TXC89-DIFF1 | PAIR | 2 | 5.5 | 5 | 10 | 5 | 50 | 6 | 20 | 12 | 12 | 12 | 12 | 7.5 | 85 Ohms | TOP=L2:L3=L2/L4:L6=L5/L7:BOTTOM=L7 |
| PCIE_TX_CAP_P89 | TXC89-DIFF1 | PAIR | 3 | 5.5 | 5 | 10 | 5 | 50 | 6 | 20 | 12 | 12 | 12 | 12 | 7.5 | 85 Ohms | TOP=L2:L3=L2/L4:L6=L5/L7:BOTTOM=L7 |
| PCIE_TX_CAP_P89 | TXC89-DIFF1 | PAIR | 4 | 5.5 | 5 | 10 | 5 | 50 | 6 | 20 | 12 | 12 | 12 | 12 | 7.5 | 85 Ohms | TOP=L2:L3=L2/L4:L6=L5/L7:BOTTOM=L7 |
| PCIE_TX_CAP_P89 | TXC89-DIFF1 | PAIR | 5 | 5.5 | 5 | 10 | 5 | 50 | 6 | 20 | 12 | 12 | 12 | 12 | 7.5 | 85 Ohms | TOP=L2:L3=L2/L4:L6=L5/L7:BOTTOM=L7 |
| PCIE_TX_CAP_P89 | TXC89-DIFF1 | PAIR | 6 | 5.5 | 5 | 10 | 5 | 50 | 6 | 20 | 12 | 12 | 12 | 12 | 7.5 | 85 Ohms | TOP=L2:L3=L2/L4:L6=L5/L7:BOTTOM=L7 |
| PCIE_TX_CAP_P89 | TXC89-DIFF1 | PAIR | 7 | 5.5 | 5 | 10 | 5 | 50 | 6 | 20 | 12 | 12 | 12 | 12 | 7.5 | 85 Ohms | TOP=L2:L3=L2/L4:L6=L5/L7:BOTTOM=L7 |
| PCIE_TX_CAP_P89 | TXC89-DIFF1 | PAIR | 8 | 5.38 | 5 | 10 | 5 | 50 | 6 | 33 | 12 | 12 | 12 | 12 | 6.62 | 85 Ohms | TOP=L2:L3=L2/L4:L6=L5/L7:BOTTOM=L7 |
| PCIE_TX_CAP_N8 | TXC8-DIFF1 | PAIR | 1 | 5.38 | 5 | 10 | 5 | 50 | 6 | 33 | 12 | 12 | 12 | 12 | 6.62 | 85 Ohms | TOP=L2:L3=L2/L4:L6=L5/L7:BOTTOM=L7 |
| PCIE_TX_CAP_N8 | TXC8-DIFF1 | PAIR | 2 | 5.5 | 5 | 10 | 5 | 50 | 6 | 20 | 12 | 12 | 12 | 12 | 7.5 | 85 Ohms | TOP=L2:L3=L2/L4:L6=L5/L7:BOTTOM=L7 |
| PCIE_TX_CAP_N8 | TXC8-DIFF1 | PAIR | 3 | 5.5 | 5 | 10 | 5 | 50 | 6 | 20 | 12 | 12 | 12 | 12 | 7.5 | 85 Ohms | TOP=L2:L3=L2/L4:L6=L5/L7:BOTTOM=L7 |
| PCIE_TX_CAP_N8 | TXC8-DIFF1 | PAIR | 4 | 5.5 | 5 | 10 | 5 | 50 | 6 | 20 | 12 | 12 | 12 | 12 | 7.5 | 85 Ohms | TOP=L2:L3=L2/L4:L6=L5/L7:BOTTOM=L7 |
| PCIE_TX_CAP_N8 | TXC8-DIFF1 | PAIR | 5 | 5.5 | 5 | 10 | 5 | 50 | 6 | 20 | 12 | 12 | 12 | 12 | 7.5 | 85 Ohms | TOP=L2:L3=L2/L4:L6=L5/L7:BOTTOM=L7 |
| PCIE_TX_CAP_N8 | TXC8-DIFF1 | PAIR | 6 | 5.5 | 5 | 10 | 5 | 50 | 6 | 20 | 12 | 12 | 12 | 12 | 7.5 | 85 Ohms | TOP=L2:L3=L2/L4:L6=L5/L7:BOTTOM=L7 |
| PCIE_TX_CAP_N8 | TXC8-DIFF1 | PAIR | 7 | 5.5 | 5 | 10 | 5 | 50 | 6 | 20 | 12 | 12 | 12 | 12 | 7.5 | 85 Ohms | TOP=L2:L3=L2/L4:L6=L5/L7:BOTTOM=L7 |
| PCIE_TX_CAP_N8 | TXC8-DIFF1 | PAIR | 8 | 5.38 | 5 | 10 | 5 | 50 | 6 | 33 | 12 | 12 | 12 | 12 | 6.62 | 85 Ohms | TOP=L2:L3=L2/L4:L6=L5/L7:BOTTOM=L7 |
| PCIE_TX_CAP_P8 | TXC8-DIFF1 | PAIR | 1 | 5.38 | 5 | 10 | 5 | 50 | 6 | 33 | 12 | 12 | 12 | 12 | 6.62 | 85 Ohms | TOP=L2:L3=L2/L4:L6=L5/L7:BOTTOM=L7 |
| PCIE_TX_CAP_P8 | TXC8-DIFF1 | PAIR | 2 | 5.5 | 5 | 10 | 5 | 50 | 6 | 20 | 12 | 12 | 12 | 12 | 7.5 | 85 Ohms | TOP=L2:L3=L2/L4:L6=L5/L7:BOTTOM=L7 |
| PCIE_TX_CAP_P8 | TXC8-DIFF1 | PAIR | 3 | 5.5 | 5 | 10 | 5 | 50 | 6 | 20 | 12 | 12 | 12 | 12 | 7.5 | 85 Ohms | TOP=L2:L3=L2/L4:L6=L5/L7:BOTTOM=L7 |
| PCIE_TX_CAP_P8 | TXC8-DIFF1 | PAIR | 4 | 5.5 | 5 | 10 | 5 | 50 | 6 | 20 | 12 | 12 | 12 | 12 | 7.5 | 85 Ohms | TOP=L2:L3=L2/L4:L6=L5/L7:BOTTOM=L7 |
| PCIE_TX_CAP_P8 | TXC8-DIFF1 | PAIR | 5 | 5.5 | 5 | 10 | 5 | 50 | 6 | 20 | 12 | 12 | 12 | 12 | 7.5 | 85 Ohms | TOP=L2:L3=L2/L4:L6=L5/L7:BOTTOM=L7 |
| PCIE_TX_CAP_P8 | TXC8-DIFF1 | PAIR | 6 | 5.5 | 5 | 10 | 5 | 50 | 6 | 20 | 12 | 12 | 12 | 12 | 7.5 | 85 Ohms | TOP=L2:L3=L2/L4:L6=L5/L7:BOTTOM=L7 |
| PCIE_TX_CAP_P8 | TXC8-DIFF1 | PAIR | 7 | 5.5 | 5 | 10 | 5 | 50 | 6 | 20 | 12 | 12 | 12 | 12 | 7.5 | 85 Ohms | TOP=L2:L3=L2/L4:L6=L5/L7:BOTTOM=L7 |
| PCIE_TX_CAP_P8 | TXC8-DIFF1 | PAIR | 8 | 5.38 | 5 | 10 | 5 | 50 | 6 | 33 | 12 | 12 | 12 | 12 | 6.62 | 85 Ohms | TOP=L2:L3=L2/L4:L6=L5/L7:BOTTOM=L7 |
| PCIE_TX_CAP_N90 | TXC90-DIFF1 | PAIR | 1 | 5.38 | 5 | 10 | 5 | 50 | 6 | 33 | 12 | 12 | 12 | 12 | 6.62 | 85 Ohms | TOP=L2:L3=L2/L4:L6=L5/L7:BOTTOM=L7 |
| PCIE_TX_CAP_N90 | TXC90-DIFF1 | PAIR | 2 | 5.5 | 5 | 10 | 5 | 50 | 6 | 20 | 12 | 12 | 12 | 12 | 7.5 | 85 Ohms | TOP=L2:L3=L2/L4:L6=L5/L7:BOTTOM=L7 |
| PCIE_TX_CAP_N90 | TXC90-DIFF1 | PAIR | 3 | 5.5 | 5 | 10 | 5 | 50 | 6 | 20 | 12 | 12 | 12 | 12 | 7.5 | 85 Ohms | TOP=L2:L3=L2/L4:L6=L5/L7:BOTTOM=L7 |
| PCIE_TX_CAP_N90 | TXC90-DIFF1 | PAIR | 4 | 5.5 | 5 | 10 | 5 | 50 | 6 | 20 | 12 | 12 | 12 | 12 | 7.5 | 85 Ohms | TOP=L2:L3=L2/L4:L6=L5/L7:BOTTOM=L7 |
| PCIE_TX_CAP_N90 | TXC90-DIFF1 | PAIR | 5 | 5.5 | 5 | 10 | 5 | 50 | 6 | 20 | 12 | 12 | 12 | 12 | 7.5 | 85 Ohms | TOP=L2:L3=L2/L4:L6=L5/L7:BOTTOM=L7 |
| PCIE_TX_CAP_N90 | TXC90-DIFF1 | PAIR | 6 | 5.5 | 5 | 10 | 5 | 50 | 6 | 20 | 12 | 12 | 12 | 12 | 7.5 | 85 Ohms | TOP=L2:L3=L2/L4:L6=L5/L7:BOTTOM=L7 |
| PCIE_TX_CAP_N90 | TXC90-DIFF1 | PAIR | 7 | 5.5 | 5 | 10 | 5 | 50 | 6 | 20 | 12 | 12 | 12 | 12 | 7.5 | 85 Ohms | TOP=L2:L3=L2/L4:L6=L5/L7:BOTTOM=L7 |
| PCIE_TX_CAP_N90 | TXC90-DIFF1 | PAIR | 8 | 5.38 | 5 | 10 | 5 | 50 | 6 | 33 | 12 | 12 | 12 | 12 | 6.62 | 85 Ohms | TOP=L2:L3=L2/L4:L6=L5/L7:BOTTOM=L7 |
| PCIE_TX_CAP_P90 | TXC90-DIFF1 | PAIR | 1 | 5.38 | 5 | 10 | 5 | 50 | 6 | 33 | 12 | 12 | 12 | 12 | 6.62 | 85 Ohms | TOP=L2:L3=L2/L4:L6=L5/L7:BOTTOM=L7 |
| PCIE_TX_CAP_P90 | TXC90-DIFF1 | PAIR | 2 | 5.5 | 5 | 10 | 5 | 50 | 6 | 20 | 12 | 12 | 12 | 12 | 7.5 | 85 Ohms | TOP=L2:L3=L2/L4:L6=L5/L7:BOTTOM=L7 |
| PCIE_TX_CAP_P90 | TXC90-DIFF1 | PAIR | 3 | 5.5 | 5 | 10 | 5 | 50 | 6 | 20 | 12 | 12 | 12 | 12 | 7.5 | 85 Ohms | TOP=L2:L3=L2/L4:L6=L5/L7:BOTTOM=L7 |
| PCIE_TX_CAP_P90 | TXC90-DIFF1 | PAIR | 4 | 5.5 | 5 | 10 | 5 | 50 | 6 | 20 | 12 | 12 | 12 | 12 | 7.5 | 85 Ohms | TOP=L2:L3=L2/L4:L6=L5/L7:BOTTOM=L7 |
| PCIE_TX_CAP_P90 | TXC90-DIFF1 | PAIR | 5 | 5.5 | 5 | 10 | 5 | 50 | 6 | 20 | 12 | 12 | 12 | 12 | 7.5 | 85 Ohms | TOP=L2:L3=L2/L4:L6=L5/L7:BOTTOM=L7 |
| PCIE_TX_CAP_P90 | TXC90-DIFF1 | PAIR | 6 | 5.5 | 5 | 10 | 5 | 50 | 6 | 20 | 12 | 12 | 12 | 12 | 7.5 | 85 Ohms | TOP=L2:L3=L2/L4:L6=L5/L7:BOTTOM=L7 |
| PCIE_TX_CAP_P90 | TXC90-DIFF1 | PAIR | 7 | 5.5 | 5 | 10 | 5 | 50 | 6 | 20 | 12 | 12 | 12 | 12 | 7.5 | 85 Ohms | TOP=L2:L3=L2/L4:L6=L5/L7:BOTTOM=L7 |
| PCIE_TX_CAP_P90 | TXC90-DIFF1 | PAIR | 8 | 5.38 | 5 | 10 | 5 | 50 | 6 | 33 | 12 | 12 | 12 | 12 | 6.62 | 85 Ohms | TOP=L2:L3=L2/L4:L6=L5/L7:BOTTOM=L7 |
| PCIE_TX_CAP_N91 | TXC91-DIFF1 | PAIR | 1 | 5.38 | 5 | 10 | 5 | 50 | 6 | 33 | 12 | 12 | 12 | 12 | 6.62 | 85 Ohms | TOP=L2:L3=L2/L4:L6=L5/L7:BOTTOM=L7 |
| PCIE_TX_CAP_N91 | TXC91-DIFF1 | PAIR | 2 | 5.5 | 5 | 10 | 5 | 50 | 6 | 20 | 12 | 12 | 12 | 12 | 7.5 | 85 Ohms | TOP=L2:L3=L2/L4:L6=L5/L7:BOTTOM=L7 |
| PCIE_TX_CAP_N91 | TXC91-DIFF1 | PAIR | 3 | 5.5 | 5 | 10 | 5 | 50 | 6 | 20 | 12 | 12 | 12 | 12 | 7.5 | 85 Ohms | TOP=L2:L3=L2/L4:L6=L5/L7:BOTTOM=L7 |
| PCIE_TX_CAP_N91 | TXC91-DIFF1 | PAIR | 4 | 5.5 | 5 | 10 | 5 | 50 | 6 | 20 | 12 | 12 | 12 | 12 | 7.5 | 85 Ohms | TOP=L2:L3=L2/L4:L6=L5/L7:BOTTOM=L7 |
| PCIE_TX_CAP_N91 | TXC91-DIFF1 | PAIR | 5 | 5.5 | 5 | 10 | 5 | 50 | 6 | 20 | 12 | 12 | 12 | 12 | 7.5 | 85 Ohms | TOP=L2:L3=L2/L4:L6=L5/L7:BOTTOM=L7 |
| PCIE_TX_CAP_N91 | TXC91-DIFF1 | PAIR | 6 | 5.5 | 5 | 10 | 5 | 50 | 6 | 20 | 12 | 12 | 12 | 12 | 7.5 | 85 Ohms | TOP=L2:L3=L2/L4:L6=L5/L7:BOTTOM=L7 |
| PCIE_TX_CAP_N91 | TXC91-DIFF1 | PAIR | 7 | 5.5 | 5 | 10 | 5 | 50 | 6 | 20 | 12 | 12 | 12 | 12 | 7.5 | 85 Ohms | TOP=L2:L3=L2/L4:L6=L5/L7:BOTTOM=L7 |
| PCIE_TX_CAP_N91 | TXC91-DIFF1 | PAIR | 8 | 5.38 | 5 | 10 | 5 | 50 | 6 | 33 | 12 | 12 | 12 | 12 | 6.62 | 85 Ohms | TOP=L2:L3=L2/L4:L6=L5/L7:BOTTOM=L7 |
| PCIE_TX_CAP_P91 | TXC91-DIFF1 | PAIR | 1 | 5.38 | 5 | 10 | 5 | 50 | 6 | 33 | 12 | 12 | 12 | 12 | 6.62 | 85 Ohms | TOP=L2:L3=L2/L4:L6=L5/L7:BOTTOM=L7 |
| PCIE_TX_CAP_P91 | TXC91-DIFF1 | PAIR | 2 | 5.5 | 5 | 10 | 5 | 50 | 6 | 20 | 12 | 12 | 12 | 12 | 7.5 | 85 Ohms | TOP=L2:L3=L2/L4:L6=L5/L7:BOTTOM=L7 |
| PCIE_TX_CAP_P91 | TXC91-DIFF1 | PAIR | 3 | 5.5 | 5 | 10 | 5 | 50 | 6 | 20 | 12 | 12 | 12 | 12 | 7.5 | 85 Ohms | TOP=L2:L3=L2/L4:L6=L5/L7:BOTTOM=L7 |
| PCIE_TX_CAP_P91 | TXC91-DIFF1 | PAIR | 4 | 5.5 | 5 | 10 | 5 | 50 | 6 | 20 | 12 | 12 | 12 | 12 | 7.5 | 85 Ohms | TOP=L2:L3=L2/L4:L6=L5/L7:BOTTOM=L7 |
| PCIE_TX_CAP_P91 | TXC91-DIFF1 | PAIR | 5 | 5.5 | 5 | 10 | 5 | 50 | 6 | 20 | 12 | 12 | 12 | 12 | 7.5 | 85 Ohms | TOP=L2:L3=L2/L4:L6=L5/L7:BOTTOM=L7 |
| PCIE_TX_CAP_P91 | TXC91-DIFF1 | PAIR | 6 | 5.5 | 5 | 10 | 5 | 50 | 6 | 20 | 12 | 12 | 12 | 12 | 7.5 | 85 Ohms | TOP=L2:L3=L2/L4:L6=L5/L7:BOTTOM=L7 |
| PCIE_TX_CAP_P91 | TXC91-DIFF1 | PAIR | 7 | 5.5 | 5 | 10 | 5 | 50 | 6 | 20 | 12 | 12 | 12 | 12 | 7.5 | 85 Ohms | TOP=L2:L3=L2/L4:L6=L5/L7:BOTTOM=L7 |
| PCIE_TX_CAP_P91 | TXC91-DIFF1 | PAIR | 8 | 5.38 | 5 | 10 | 5 | 50 | 6 | 33 | 12 | 12 | 12 | 12 | 6.62 | 85 Ohms | TOP=L2:L3=L2/L4:L6=L5/L7:BOTTOM=L7 |
| PCIE_TX_CAP_N92 | TXC92-DIFF1 | PAIR | 1 | 5.38 | 5 | 10 | 5 | 50 | 6 | 33 | 12 | 12 | 12 | 12 | 6.62 | 85 Ohms | TOP=L2:L3=L2/L4:L6=L5/L7:BOTTOM=L7 |
| PCIE_TX_CAP_N92 | TXC92-DIFF1 | PAIR | 2 | 5.5 | 5 | 10 | 5 | 50 | 6 | 20 | 12 | 12 | 12 | 12 | 7.5 | 85 Ohms | TOP=L2:L3=L2/L4:L6=L5/L7:BOTTOM=L7 |
| PCIE_TX_CAP_N92 | TXC92-DIFF1 | PAIR | 3 | 5.5 | 5 | 10 | 5 | 50 | 6 | 20 | 12 | 12 | 12 | 12 | 7.5 | 85 Ohms | TOP=L2:L3=L2/L4:L6=L5/L7:BOTTOM=L7 |
| PCIE_TX_CAP_N92 | TXC92-DIFF1 | PAIR | 4 | 5.5 | 5 | 10 | 5 | 50 | 6 | 20 | 12 | 12 | 12 | 12 | 7.5 | 85 Ohms | TOP=L2:L3=L2/L4:L6=L5/L7:BOTTOM=L7 |
| PCIE_TX_CAP_N92 | TXC92-DIFF1 | PAIR | 5 | 5.5 | 5 | 10 | 5 | 50 | 6 | 20 | 12 | 12 | 12 | 12 | 7.5 | 85 Ohms | TOP=L2:L3=L2/L4:L6=L5/L7:BOTTOM=L7 |
| PCIE_TX_CAP_N92 | TXC92-DIFF1 | PAIR | 6 | 5.5 | 5 | 10 | 5 | 50 | 6 | 20 | 12 | 12 | 12 | 12 | 7.5 | 85 Ohms | TOP=L2:L3=L2/L4:L6=L5/L7:BOTTOM=L7 |
| PCIE_TX_CAP_N92 | TXC92-DIFF1 | PAIR | 7 | 5.5 | 5 | 10 | 5 | 50 | 6 | 20 | 12 | 12 | 12 | 12 | 7.5 | 85 Ohms | TOP=L2:L3=L2/L4:L6=L5/L7:BOTTOM=L7 |
| PCIE_TX_CAP_N92 | TXC92-DIFF1 | PAIR | 8 | 5.38 | 5 | 10 | 5 | 50 | 6 | 33 | 12 | 12 | 12 | 12 | 6.62 | 85 Ohms | TOP=L2:L3=L2/L4:L6=L5/L7:BOTTOM=L7 |
| PCIE_TX_CAP_P92 | TXC92-DIFF1 | PAIR | 1 | 5.38 | 5 | 10 | 5 | 50 | 6 | 33 | 12 | 12 | 12 | 12 | 6.62 | 85 Ohms | TOP=L2:L3=L2/L4:L6=L5/L7:BOTTOM=L7 |
| PCIE_TX_CAP_P92 | TXC92-DIFF1 | PAIR | 2 | 5.5 | 5 | 10 | 5 | 50 | 6 | 20 | 12 | 12 | 12 | 12 | 7.5 | 85 Ohms | TOP=L2:L3=L2/L4:L6=L5/L7:BOTTOM=L7 |
| PCIE_TX_CAP_P92 | TXC92-DIFF1 | PAIR | 3 | 5.5 | 5 | 10 | 5 | 50 | 6 | 20 | 12 | 12 | 12 | 12 | 7.5 | 85 Ohms | TOP=L2:L3=L2/L4:L6=L5/L7:BOTTOM=L7 |
| PCIE_TX_CAP_P92 | TXC92-DIFF1 | PAIR | 4 | 5.5 | 5 | 10 | 5 | 50 | 6 | 20 | 12 | 12 | 12 | 12 | 7.5 | 85 Ohms | TOP=L2:L3=L2/L4:L6=L5/L7:BOTTOM=L7 |
| PCIE_TX_CAP_P92 | TXC92-DIFF1 | PAIR | 5 | 5.5 | 5 | 10 | 5 | 50 | 6 | 20 | 12 | 12 | 12 | 12 | 7.5 | 85 Ohms | TOP=L2:L3=L2/L4:L6=L5/L7:BOTTOM=L7 |
| PCIE_TX_CAP_P92 | TXC92-DIFF1 | PAIR | 6 | 5.5 | 5 | 10 | 5 | 50 | 6 | 20 | 12 | 12 | 12 | 12 | 7.5 | 85 Ohms | TOP=L2:L3=L2/L4:L6=L5/L7:BOTTOM=L7 |
| PCIE_TX_CAP_P92 | TXC92-DIFF1 | PAIR | 7 | 5.5 | 5 | 10 | 5 | 50 | 6 | 20 | 12 | 12 | 12 | 12 | 7.5 | 85 Ohms | TOP=L2:L3=L2/L4:L6=L5/L7:BOTTOM=L7 |
| PCIE_TX_CAP_P92 | TXC92-DIFF1 | PAIR | 8 | 5.38 | 5 | 10 | 5 | 50 | 6 | 33 | 12 | 12 | 12 | 12 | 6.62 | 85 Ohms | TOP=L2:L3=L2/L4:L6=L5/L7:BOTTOM=L7 |
| PCIE_TX_CAP_N93 | TXC93-DIFF1 | PAIR | 1 | 5.38 | 5 | 10 | 5 | 50 | 6 | 33 | 12 | 12 | 12 | 12 | 6.62 | 85 Ohms | TOP=L2:L3=L2/L4:L6=L5/L7:BOTTOM=L7 |
| PCIE_TX_CAP_N93 | TXC93-DIFF1 | PAIR | 2 | 5.5 | 5 | 10 | 5 | 50 | 6 | 20 | 12 | 12 | 12 | 12 | 7.5 | 85 Ohms | TOP=L2:L3=L2/L4:L6=L5/L7:BOTTOM=L7 |
| PCIE_TX_CAP_N93 | TXC93-DIFF1 | PAIR | 3 | 5.5 | 5 | 10 | 5 | 50 | 6 | 20 | 12 | 12 | 12 | 12 | 7.5 | 85 Ohms | TOP=L2:L3=L2/L4:L6=L5/L7:BOTTOM=L7 |
| PCIE_TX_CAP_N93 | TXC93-DIFF1 | PAIR | 4 | 5.5 | 5 | 10 | 5 | 50 | 6 | 20 | 12 | 12 | 12 | 12 | 7.5 | 85 Ohms | TOP=L2:L3=L2/L4:L6=L5/L7:BOTTOM=L7 |
| PCIE_TX_CAP_N93 | TXC93-DIFF1 | PAIR | 5 | 5.5 | 5 | 10 | 5 | 50 | 6 | 20 | 12 | 12 | 12 | 12 | 7.5 | 85 Ohms | TOP=L2:L3=L2/L4:L6=L5/L7:BOTTOM=L7 |
| PCIE_TX_CAP_N93 | TXC93-DIFF1 | PAIR | 6 | 5.5 | 5 | 10 | 5 | 50 | 6 | 20 | 12 | 12 | 12 | 12 | 7.5 | 85 Ohms | TOP=L2:L3=L2/L4:L6=L5/L7:BOTTOM=L7 |
| PCIE_TX_CAP_N93 | TXC93-DIFF1 | PAIR | 7 | 5.5 | 5 | 10 | 5 | 50 | 6 | 20 | 12 | 12 | 12 | 12 | 7.5 | 85 Ohms | TOP=L2:L3=L2/L4:L6=L5/L7:BOTTOM=L7 |
| PCIE_TX_CAP_N93 | TXC93-DIFF1 | PAIR | 8 | 5.38 | 5 | 10 | 5 | 50 | 6 | 33 | 12 | 12 | 12 | 12 | 6.62 | 85 Ohms | TOP=L2:L3=L2/L4:L6=L5/L7:BOTTOM=L7 |
| PCIE_TX_CAP_P93 | TXC93-DIFF1 | PAIR | 1 | 5.38 | 5 | 10 | 5 | 50 | 6 | 33 | 12 | 12 | 12 | 12 | 6.62 | 85 Ohms | TOP=L2:L3=L2/L4:L6=L5/L7:BOTTOM=L7 |
| PCIE_TX_CAP_P93 | TXC93-DIFF1 | PAIR | 2 | 5.5 | 5 | 10 | 5 | 50 | 6 | 20 | 12 | 12 | 12 | 12 | 7.5 | 85 Ohms | TOP=L2:L3=L2/L4:L6=L5/L7:BOTTOM=L7 |
| PCIE_TX_CAP_P93 | TXC93-DIFF1 | PAIR | 3 | 5.5 | 5 | 10 | 5 | 50 | 6 | 20 | 12 | 12 | 12 | 12 | 7.5 | 85 Ohms | TOP=L2:L3=L2/L4:L6=L5/L7:BOTTOM=L7 |
| PCIE_TX_CAP_P93 | TXC93-DIFF1 | PAIR | 4 | 5.5 | 5 | 10 | 5 | 50 | 6 | 20 | 12 | 12 | 12 | 12 | 7.5 | 85 Ohms | TOP=L2:L3=L2/L4:L6=L5/L7:BOTTOM=L7 |
| PCIE_TX_CAP_P93 | TXC93-DIFF1 | PAIR | 5 | 5.5 | 5 | 10 | 5 | 50 | 6 | 20 | 12 | 12 | 12 | 12 | 7.5 | 85 Ohms | TOP=L2:L3=L2/L4:L6=L5/L7:BOTTOM=L7 |
| PCIE_TX_CAP_P93 | TXC93-DIFF1 | PAIR | 6 | 5.5 | 5 | 10 | 5 | 50 | 6 | 20 | 12 | 12 | 12 | 12 | 7.5 | 85 Ohms | TOP=L2:L3=L2/L4:L6=L5/L7:BOTTOM=L7 |
| PCIE_TX_CAP_P93 | TXC93-DIFF1 | PAIR | 7 | 5.5 | 5 | 10 | 5 | 50 | 6 | 20 | 12 | 12 | 12 | 12 | 7.5 | 85 Ohms | TOP=L2:L3=L2/L4:L6=L5/L7:BOTTOM=L7 |
| PCIE_TX_CAP_P93 | TXC93-DIFF1 | PAIR | 8 | 5.38 | 5 | 10 | 5 | 50 | 6 | 33 | 12 | 12 | 12 | 12 | 6.62 | 85 Ohms | TOP=L2:L3=L2/L4:L6=L5/L7:BOTTOM=L7 |
| PCIE_TX_CAP_N94 | TXC94-DIFF1 | PAIR | 1 | 5.38 | 5 | 10 | 5 | 50 | 6 | 33 | 12 | 12 | 12 | 12 | 6.62 | 85 Ohms | TOP=L2:L3=L2/L4:L6=L5/L7:BOTTOM=L7 |
| PCIE_TX_CAP_N94 | TXC94-DIFF1 | PAIR | 2 | 5.5 | 5 | 10 | 5 | 50 | 6 | 20 | 12 | 12 | 12 | 12 | 7.5 | 85 Ohms | TOP=L2:L3=L2/L4:L6=L5/L7:BOTTOM=L7 |
| PCIE_TX_CAP_N94 | TXC94-DIFF1 | PAIR | 3 | 5.5 | 5 | 10 | 5 | 50 | 6 | 20 | 12 | 12 | 12 | 12 | 7.5 | 85 Ohms | TOP=L2:L3=L2/L4:L6=L5/L7:BOTTOM=L7 |
| PCIE_TX_CAP_N94 | TXC94-DIFF1 | PAIR | 4 | 5.5 | 5 | 10 | 5 | 50 | 6 | 20 | 12 | 12 | 12 | 12 | 7.5 | 85 Ohms | TOP=L2:L3=L2/L4:L6=L5/L7:BOTTOM=L7 |
| PCIE_TX_CAP_N94 | TXC94-DIFF1 | PAIR | 5 | 5.5 | 5 | 10 | 5 | 50 | 6 | 20 | 12 | 12 | 12 | 12 | 7.5 | 85 Ohms | TOP=L2:L3=L2/L4:L6=L5/L7:BOTTOM=L7 |
| PCIE_TX_CAP_N94 | TXC94-DIFF1 | PAIR | 6 | 5.5 | 5 | 10 | 5 | 50 | 6 | 20 | 12 | 12 | 12 | 12 | 7.5 | 85 Ohms | TOP=L2:L3=L2/L4:L6=L5/L7:BOTTOM=L7 |
| PCIE_TX_CAP_N94 | TXC94-DIFF1 | PAIR | 7 | 5.5 | 5 | 10 | 5 | 50 | 6 | 20 | 12 | 12 | 12 | 12 | 7.5 | 85 Ohms | TOP=L2:L3=L2/L4:L6=L5/L7:BOTTOM=L7 |
| PCIE_TX_CAP_N94 | TXC94-DIFF1 | PAIR | 8 | 5.38 | 5 | 10 | 5 | 50 | 6 | 33 | 12 | 12 | 12 | 12 | 6.62 | 85 Ohms | TOP=L2:L3=L2/L4:L6=L5/L7:BOTTOM=L7 |
| PCIE_TX_CAP_P94 | TXC94-DIFF1 | PAIR | 1 | 5.38 | 5 | 10 | 5 | 50 | 6 | 33 | 12 | 12 | 12 | 12 | 6.62 | 85 Ohms | TOP=L2:L3=L2/L4:L6=L5/L7:BOTTOM=L7 |
| PCIE_TX_CAP_P94 | TXC94-DIFF1 | PAIR | 2 | 5.5 | 5 | 10 | 5 | 50 | 6 | 20 | 12 | 12 | 12 | 12 | 7.5 | 85 Ohms | TOP=L2:L3=L2/L4:L6=L5/L7:BOTTOM=L7 |
| PCIE_TX_CAP_P94 | TXC94-DIFF1 | PAIR | 3 | 5.5 | 5 | 10 | 5 | 50 | 6 | 20 | 12 | 12 | 12 | 12 | 7.5 | 85 Ohms | TOP=L2:L3=L2/L4:L6=L5/L7:BOTTOM=L7 |
| PCIE_TX_CAP_P94 | TXC94-DIFF1 | PAIR | 4 | 5.5 | 5 | 10 | 5 | 50 | 6 | 20 | 12 | 12 | 12 | 12 | 7.5 | 85 Ohms | TOP=L2:L3=L2/L4:L6=L5/L7:BOTTOM=L7 |
| PCIE_TX_CAP_P94 | TXC94-DIFF1 | PAIR | 5 | 5.5 | 5 | 10 | 5 | 50 | 6 | 20 | 12 | 12 | 12 | 12 | 7.5 | 85 Ohms | TOP=L2:L3=L2/L4:L6=L5/L7:BOTTOM=L7 |
| PCIE_TX_CAP_P94 | TXC94-DIFF1 | PAIR | 6 | 5.5 | 5 | 10 | 5 | 50 | 6 | 20 | 12 | 12 | 12 | 12 | 7.5 | 85 Ohms | TOP=L2:L3=L2/L4:L6=L5/L7:BOTTOM=L7 |
| PCIE_TX_CAP_P94 | TXC94-DIFF1 | PAIR | 7 | 5.5 | 5 | 10 | 5 | 50 | 6 | 20 | 12 | 12 | 12 | 12 | 7.5 | 85 Ohms | TOP=L2:L3=L2/L4:L6=L5/L7:BOTTOM=L7 |
| PCIE_TX_CAP_P94 | TXC94-DIFF1 | PAIR | 8 | 5.38 | 5 | 10 | 5 | 50 | 6 | 33 | 12 | 12 | 12 | 12 | 6.62 | 85 Ohms | TOP=L2:L3=L2/L4:L6=L5/L7:BOTTOM=L7 |
| PCIE_TX_CAP_N95 | TXC95-DIFF1 | PAIR | 1 | 5.38 | 5 | 10 | 5 | 50 | 6 | 33 | 12 | 12 | 12 | 12 | 6.62 | 85 Ohms | TOP=L2:L3=L2/L4:L6=L5/L7:BOTTOM=L7 |
| PCIE_TX_CAP_N95 | TXC95-DIFF1 | PAIR | 2 | 5.5 | 5 | 10 | 5 | 50 | 6 | 20 | 12 | 12 | 12 | 12 | 7.5 | 85 Ohms | TOP=L2:L3=L2/L4:L6=L5/L7:BOTTOM=L7 |
| PCIE_TX_CAP_N95 | TXC95-DIFF1 | PAIR | 3 | 5.5 | 5 | 10 | 5 | 50 | 6 | 20 | 12 | 12 | 12 | 12 | 7.5 | 85 Ohms | TOP=L2:L3=L2/L4:L6=L5/L7:BOTTOM=L7 |
| PCIE_TX_CAP_N95 | TXC95-DIFF1 | PAIR | 4 | 5.5 | 5 | 10 | 5 | 50 | 6 | 20 | 12 | 12 | 12 | 12 | 7.5 | 85 Ohms | TOP=L2:L3=L2/L4:L6=L5/L7:BOTTOM=L7 |
| PCIE_TX_CAP_N95 | TXC95-DIFF1 | PAIR | 5 | 5.5 | 5 | 10 | 5 | 50 | 6 | 20 | 12 | 12 | 12 | 12 | 7.5 | 85 Ohms | TOP=L2:L3=L2/L4:L6=L5/L7:BOTTOM=L7 |
| PCIE_TX_CAP_N95 | TXC95-DIFF1 | PAIR | 6 | 5.5 | 5 | 10 | 5 | 50 | 6 | 20 | 12 | 12 | 12 | 12 | 7.5 | 85 Ohms | TOP=L2:L3=L2/L4:L6=L5/L7:BOTTOM=L7 |
| PCIE_TX_CAP_N95 | TXC95-DIFF1 | PAIR | 7 | 5.5 | 5 | 10 | 5 | 50 | 6 | 20 | 12 | 12 | 12 | 12 | 7.5 | 85 Ohms | TOP=L2:L3=L2/L4:L6=L5/L7:BOTTOM=L7 |
| PCIE_TX_CAP_N95 | TXC95-DIFF1 | PAIR | 8 | 5.38 | 5 | 10 | 5 | 50 | 6 | 33 | 12 | 12 | 12 | 12 | 6.62 | 85 Ohms | TOP=L2:L3=L2/L4:L6=L5/L7:BOTTOM=L7 |
| PCIE_TX_CAP_P95 | TXC95-DIFF1 | PAIR | 1 | 5.38 | 5 | 10 | 5 | 50 | 6 | 33 | 12 | 12 | 12 | 12 | 6.62 | 85 Ohms | TOP=L2:L3=L2/L4:L6=L5/L7:BOTTOM=L7 |
| PCIE_TX_CAP_P95 | TXC95-DIFF1 | PAIR | 2 | 5.5 | 5 | 10 | 5 | 50 | 6 | 20 | 12 | 12 | 12 | 12 | 7.5 | 85 Ohms | TOP=L2:L3=L2/L4:L6=L5/L7:BOTTOM=L7 |
| PCIE_TX_CAP_P95 | TXC95-DIFF1 | PAIR | 3 | 5.5 | 5 | 10 | 5 | 50 | 6 | 20 | 12 | 12 | 12 | 12 | 7.5 | 85 Ohms | TOP=L2:L3=L2/L4:L6=L5/L7:BOTTOM=L7 |
| PCIE_TX_CAP_P95 | TXC95-DIFF1 | PAIR | 4 | 5.5 | 5 | 10 | 5 | 50 | 6 | 20 | 12 | 12 | 12 | 12 | 7.5 | 85 Ohms | TOP=L2:L3=L2/L4:L6=L5/L7:BOTTOM=L7 |
| PCIE_TX_CAP_P95 | TXC95-DIFF1 | PAIR | 5 | 5.5 | 5 | 10 | 5 | 50 | 6 | 20 | 12 | 12 | 12 | 12 | 7.5 | 85 Ohms | TOP=L2:L3=L2/L4:L6=L5/L7:BOTTOM=L7 |
| PCIE_TX_CAP_P95 | TXC95-DIFF1 | PAIR | 6 | 5.5 | 5 | 10 | 5 | 50 | 6 | 20 | 12 | 12 | 12 | 12 | 7.5 | 85 Ohms | TOP=L2:L3=L2/L4:L6=L5/L7:BOTTOM=L7 |
| PCIE_TX_CAP_P95 | TXC95-DIFF1 | PAIR | 7 | 5.5 | 5 | 10 | 5 | 50 | 6 | 20 | 12 | 12 | 12 | 12 | 7.5 | 85 Ohms | TOP=L2:L3=L2/L4:L6=L5/L7:BOTTOM=L7 |
| PCIE_TX_CAP_P95 | TXC95-DIFF1 | PAIR | 8 | 5.38 | 5 | 10 | 5 | 50 | 6 | 33 | 12 | 12 | 12 | 12 | 6.62 | 85 Ohms | TOP=L2:L3=L2/L4:L6=L5/L7:BOTTOM=L7 |
| PCIE_TX_CAP_N9 | TXC9-DIFF1 | PAIR | 1 | 5.38 | 5 | 10 | 5 | 50 | 6 | 33 | 12 | 12 | 12 | 12 | 6.62 | 85 Ohms | TOP=L2:L3=L2/L4:L6=L5/L7:BOTTOM=L7 |
| PCIE_TX_CAP_N9 | TXC9-DIFF1 | PAIR | 2 | 5.5 | 5 | 10 | 5 | 50 | 6 | 20 | 12 | 12 | 12 | 12 | 7.5 | 85 Ohms | TOP=L2:L3=L2/L4:L6=L5/L7:BOTTOM=L7 |
| PCIE_TX_CAP_N9 | TXC9-DIFF1 | PAIR | 3 | 5.5 | 5 | 10 | 5 | 50 | 6 | 20 | 12 | 12 | 12 | 12 | 7.5 | 85 Ohms | TOP=L2:L3=L2/L4:L6=L5/L7:BOTTOM=L7 |
| PCIE_TX_CAP_N9 | TXC9-DIFF1 | PAIR | 4 | 5.5 | 5 | 10 | 5 | 50 | 6 | 20 | 12 | 12 | 12 | 12 | 7.5 | 85 Ohms | TOP=L2:L3=L2/L4:L6=L5/L7:BOTTOM=L7 |
| PCIE_TX_CAP_N9 | TXC9-DIFF1 | PAIR | 5 | 5.5 | 5 | 10 | 5 | 50 | 6 | 20 | 12 | 12 | 12 | 12 | 7.5 | 85 Ohms | TOP=L2:L3=L2/L4:L6=L5/L7:BOTTOM=L7 |
| PCIE_TX_CAP_N9 | TXC9-DIFF1 | PAIR | 6 | 5.5 | 5 | 10 | 5 | 50 | 6 | 20 | 12 | 12 | 12 | 12 | 7.5 | 85 Ohms | TOP=L2:L3=L2/L4:L6=L5/L7:BOTTOM=L7 |
| PCIE_TX_CAP_N9 | TXC9-DIFF1 | PAIR | 7 | 5.5 | 5 | 10 | 5 | 50 | 6 | 20 | 12 | 12 | 12 | 12 | 7.5 | 85 Ohms | TOP=L2:L3=L2/L4:L6=L5/L7:BOTTOM=L7 |
| PCIE_TX_CAP_N9 | TXC9-DIFF1 | PAIR | 8 | 5.38 | 5 | 10 | 5 | 50 | 6 | 33 | 12 | 12 | 12 | 12 | 6.62 | 85 Ohms | TOP=L2:L3=L2/L4:L6=L5/L7:BOTTOM=L7 |
| PCIE_TX_CAP_P9 | TXC9-DIFF1 | PAIR | 1 | 5.38 | 5 | 10 | 5 | 50 | 6 | 33 | 12 | 12 | 12 | 12 | 6.62 | 85 Ohms | TOP=L2:L3=L2/L4:L6=L5/L7:BOTTOM=L7 |
| PCIE_TX_CAP_P9 | TXC9-DIFF1 | PAIR | 2 | 5.5 | 5 | 10 | 5 | 50 | 6 | 20 | 12 | 12 | 12 | 12 | 7.5 | 85 Ohms | TOP=L2:L3=L2/L4:L6=L5/L7:BOTTOM=L7 |
| PCIE_TX_CAP_P9 | TXC9-DIFF1 | PAIR | 3 | 5.5 | 5 | 10 | 5 | 50 | 6 | 20 | 12 | 12 | 12 | 12 | 7.5 | 85 Ohms | TOP=L2:L3=L2/L4:L6=L5/L7:BOTTOM=L7 |
| PCIE_TX_CAP_P9 | TXC9-DIFF1 | PAIR | 4 | 5.5 | 5 | 10 | 5 | 50 | 6 | 20 | 12 | 12 | 12 | 12 | 7.5 | 85 Ohms | TOP=L2:L3=L2/L4:L6=L5/L7:BOTTOM=L7 |
| PCIE_TX_CAP_P9 | TXC9-DIFF1 | PAIR | 5 | 5.5 | 5 | 10 | 5 | 50 | 6 | 20 | 12 | 12 | 12 | 12 | 7.5 | 85 Ohms | TOP=L2:L3=L2/L4:L6=L5/L7:BOTTOM=L7 |
| PCIE_TX_CAP_P9 | TXC9-DIFF1 | PAIR | 6 | 5.5 | 5 | 10 | 5 | 50 | 6 | 20 | 12 | 12 | 12 | 12 | 7.5 | 85 Ohms | TOP=L2:L3=L2/L4:L6=L5/L7:BOTTOM=L7 |
| PCIE_TX_CAP_P9 | TXC9-DIFF1 | PAIR | 7 | 5.5 | 5 | 10 | 5 | 50 | 6 | 20 | 12 | 12 | 12 | 12 | 7.5 | 85 Ohms | TOP=L2:L3=L2/L4:L6=L5/L7:BOTTOM=L7 |
| PCIE_TX_CAP_P9 | TXC9-DIFF1 | PAIR | 8 | 5.38 | 5 | 10 | 5 | 50 | 6 | 33 | 12 | 12 | 12 | 12 | 6.62 | 85 Ohms | TOP=L2:L3=L2/L4:L6=L5/L7:BOTTOM=L7 |
| USB_P1_F_DN1 | USB01-DIFF1 | PAIR | 1 | 5.38 | 5 | 10 | 5 | 12 | 6 | 33 | 12 | 12 | 12 | 12 | 6.62 | 85 Ohms | TOP=L2:L3=L2/L4:L6=L5/L7:BOTTOM=L7 |
| USB_P1_F_DN1 | USB01-DIFF1 | PAIR | 2 | 5.5 | 5 | 10 | 5 | 12 | 6 | 20 | 12 | 12 | 12 | 12 | 7.5 | 85 Ohms | TOP=L2:L3=L2/L4:L6=L5/L7:BOTTOM=L7 |
| USB_P1_F_DN1 | USB01-DIFF1 | PAIR | 3 | 5.5 | 5 | 10 | 5 | 12 | 6 | 20 | 12 | 12 | 12 | 12 | 7.5 | 85 Ohms | TOP=L2:L3=L2/L4:L6=L5/L7:BOTTOM=L7 |
| USB_P1_F_DN1 | USB01-DIFF1 | PAIR | 4 | 5.5 | 5 | 10 | 5 | 12 | 6 | 20 | 12 | 12 | 12 | 12 | 7.5 | 85 Ohms | TOP=L2:L3=L2/L4:L6=L5/L7:BOTTOM=L7 |
| USB_P1_F_DN1 | USB01-DIFF1 | PAIR | 5 | 5.5 | 5 | 10 | 5 | 12 | 6 | 20 | 12 | 12 | 12 | 12 | 7.5 | 85 Ohms | TOP=L2:L3=L2/L4:L6=L5/L7:BOTTOM=L7 |
| USB_P1_F_DN1 | USB01-DIFF1 | PAIR | 6 | 5.5 | 5 | 10 | 5 | 12 | 6 | 20 | 12 | 12 | 12 | 12 | 7.5 | 85 Ohms | TOP=L2:L3=L2/L4:L6=L5/L7:BOTTOM=L7 |
| USB_P1_F_DN1 | USB01-DIFF1 | PAIR | 7 | 5.5 | 5 | 10 | 5 | 12 | 6 | 20 | 12 | 12 | 12 | 12 | 7.5 | 85 Ohms | TOP=L2:L3=L2/L4:L6=L5/L7:BOTTOM=L7 |
| USB_P1_F_DN1 | USB01-DIFF1 | PAIR | 8 | 5.38 | 5 | 10 | 5 | 12 | 6 | 33 | 12 | 12 | 12 | 12 | 6.62 | 85 Ohms | TOP=L2:L3=L2/L4:L6=L5/L7:BOTTOM=L7 |
| USB_P1_F_DP1 | USB01-DIFF1 | PAIR | 1 | 5.38 | 5 | 10 | 5 | 12 | 6 | 33 | 12 | 12 | 12 | 12 | 6.62 | 85 Ohms | TOP=L2:L3=L2/L4:L6=L5/L7:BOTTOM=L7 |
| USB_P1_F_DP1 | USB01-DIFF1 | PAIR | 2 | 5.5 | 5 | 10 | 5 | 12 | 6 | 20 | 12 | 12 | 12 | 12 | 7.5 | 85 Ohms | TOP=L2:L3=L2/L4:L6=L5/L7:BOTTOM=L7 |
| USB_P1_F_DP1 | USB01-DIFF1 | PAIR | 3 | 5.5 | 5 | 10 | 5 | 12 | 6 | 20 | 12 | 12 | 12 | 12 | 7.5 | 85 Ohms | TOP=L2:L3=L2/L4:L6=L5/L7:BOTTOM=L7 |
| USB_P1_F_DP1 | USB01-DIFF1 | PAIR | 4 | 5.5 | 5 | 10 | 5 | 12 | 6 | 20 | 12 | 12 | 12 | 12 | 7.5 | 85 Ohms | TOP=L2:L3=L2/L4:L6=L5/L7:BOTTOM=L7 |
| USB_P1_F_DP1 | USB01-DIFF1 | PAIR | 5 | 5.5 | 5 | 10 | 5 | 12 | 6 | 20 | 12 | 12 | 12 | 12 | 7.5 | 85 Ohms | TOP=L2:L3=L2/L4:L6=L5/L7:BOTTOM=L7 |
| USB_P1_F_DP1 | USB01-DIFF1 | PAIR | 6 | 5.5 | 5 | 10 | 5 | 12 | 6 | 20 | 12 | 12 | 12 | 12 | 7.5 | 85 Ohms | TOP=L2:L3=L2/L4:L6=L5/L7:BOTTOM=L7 |
| USB_P1_F_DP1 | USB01-DIFF1 | PAIR | 7 | 5.5 | 5 | 10 | 5 | 12 | 6 | 20 | 12 | 12 | 12 | 12 | 7.5 | 85 Ohms | TOP=L2:L3=L2/L4:L6=L5/L7:BOTTOM=L7 |
| USB_P1_F_DP1 | USB01-DIFF1 | PAIR | 8 | 5.38 | 5 | 10 | 5 | 12 | 6 | 33 | 12 | 12 | 12 | 12 | 6.62 | 85 Ohms | TOP=L2:L3=L2/L4:L6=L5/L7:BOTTOM=L7 |
| USB_P2_DN | USB02-DIFF1 | PAIR | 1 | 5.38 | 5 | 10 | 5 | 12 | 6 | 33 | 12 | 12 | 12 | 12 | 6.62 | 85 Ohms | TOP=L2:L3=L2/L4:L6=L5/L7:BOTTOM=L7 |
| USB_P2_DN | USB02-DIFF1 | PAIR | 2 | 5.5 | 5 | 10 | 5 | 12 | 6 | 20 | 12 | 12 | 12 | 12 | 7.5 | 85 Ohms | TOP=L2:L3=L2/L4:L6=L5/L7:BOTTOM=L7 |
| USB_P2_DN | USB02-DIFF1 | PAIR | 3 | 5.5 | 5 | 10 | 5 | 12 | 6 | 20 | 12 | 12 | 12 | 12 | 7.5 | 85 Ohms | TOP=L2:L3=L2/L4:L6=L5/L7:BOTTOM=L7 |
| USB_P2_DN | USB02-DIFF1 | PAIR | 4 | 5.5 | 5 | 10 | 5 | 12 | 6 | 20 | 12 | 12 | 12 | 12 | 7.5 | 85 Ohms | TOP=L2:L3=L2/L4:L6=L5/L7:BOTTOM=L7 |
| USB_P2_DN | USB02-DIFF1 | PAIR | 5 | 5.5 | 5 | 10 | 5 | 12 | 6 | 20 | 12 | 12 | 12 | 12 | 7.5 | 85 Ohms | TOP=L2:L3=L2/L4:L6=L5/L7:BOTTOM=L7 |
| USB_P2_DN | USB02-DIFF1 | PAIR | 6 | 5.5 | 5 | 10 | 5 | 12 | 6 | 20 | 12 | 12 | 12 | 12 | 7.5 | 85 Ohms | TOP=L2:L3=L2/L4:L6=L5/L7:BOTTOM=L7 |
| USB_P2_DN | USB02-DIFF1 | PAIR | 7 | 5.5 | 5 | 10 | 5 | 12 | 6 | 20 | 12 | 12 | 12 | 12 | 7.5 | 85 Ohms | TOP=L2:L3=L2/L4:L6=L5/L7:BOTTOM=L7 |
| USB_P2_DN | USB02-DIFF1 | PAIR | 8 | 5.38 | 5 | 10 | 5 | 12 | 6 | 33 | 12 | 12 | 12 | 12 | 6.62 | 85 Ohms | TOP=L2:L3=L2/L4:L6=L5/L7:BOTTOM=L7 |
| USB_P2_DP | USB02-DIFF1 | PAIR | 1 | 5.38 | 5 | 10 | 5 | 12 | 6 | 33 | 12 | 12 | 12 | 12 | 6.62 | 85 Ohms | TOP=L2:L3=L2/L4:L6=L5/L7:BOTTOM=L7 |
| USB_P2_DP | USB02-DIFF1 | PAIR | 2 | 5.5 | 5 | 10 | 5 | 12 | 6 | 20 | 12 | 12 | 12 | 12 | 7.5 | 85 Ohms | TOP=L2:L3=L2/L4:L6=L5/L7:BOTTOM=L7 |
| USB_P2_DP | USB02-DIFF1 | PAIR | 3 | 5.5 | 5 | 10 | 5 | 12 | 6 | 20 | 12 | 12 | 12 | 12 | 7.5 | 85 Ohms | TOP=L2:L3=L2/L4:L6=L5/L7:BOTTOM=L7 |
| USB_P2_DP | USB02-DIFF1 | PAIR | 4 | 5.5 | 5 | 10 | 5 | 12 | 6 | 20 | 12 | 12 | 12 | 12 | 7.5 | 85 Ohms | TOP=L2:L3=L2/L4:L6=L5/L7:BOTTOM=L7 |
| USB_P2_DP | USB02-DIFF1 | PAIR | 5 | 5.5 | 5 | 10 | 5 | 12 | 6 | 20 | 12 | 12 | 12 | 12 | 7.5 | 85 Ohms | TOP=L2:L3=L2/L4:L6=L5/L7:BOTTOM=L7 |
| USB_P2_DP | USB02-DIFF1 | PAIR | 6 | 5.5 | 5 | 10 | 5 | 12 | 6 | 20 | 12 | 12 | 12 | 12 | 7.5 | 85 Ohms | TOP=L2:L3=L2/L4:L6=L5/L7:BOTTOM=L7 |
| USB_P2_DP | USB02-DIFF1 | PAIR | 7 | 5.5 | 5 | 10 | 5 | 12 | 6 | 20 | 12 | 12 | 12 | 12 | 7.5 | 85 Ohms | TOP=L2:L3=L2/L4:L6=L5/L7:BOTTOM=L7 |
| USB_P2_DP | USB02-DIFF1 | PAIR | 8 | 5.38 | 5 | 10 | 5 | 12 | 6 | 33 | 12 | 12 | 12 | 12 | 6.62 | 85 Ohms | TOP=L2:L3=L2/L4:L6=L5/L7:BOTTOM=L7 |
| USB_DN_R | USB05-DIFF1 | PAIR | 1 | 5.38 | 5 | 10 | 5 | 12 | 6 | 33 | 12 | 12 | 12 | 12 | 6.62 | 85 Ohms | TOP=L2:L3=L2/L4:L6=L5/L7:BOTTOM=L7 |
| USB_DN_R | USB05-DIFF1 | PAIR | 2 | 5.5 | 5 | 10 | 5 | 12 | 6 | 20 | 12 | 12 | 12 | 12 | 7.5 | 85 Ohms | TOP=L2:L3=L2/L4:L6=L5/L7:BOTTOM=L7 |
| USB_DN_R | USB05-DIFF1 | PAIR | 3 | 5.5 | 5 | 10 | 5 | 12 | 6 | 20 | 12 | 12 | 12 | 12 | 7.5 | 85 Ohms | TOP=L2:L3=L2/L4:L6=L5/L7:BOTTOM=L7 |
| USB_DN_R | USB05-DIFF1 | PAIR | 4 | 5.5 | 5 | 10 | 5 | 12 | 6 | 20 | 12 | 12 | 12 | 12 | 7.5 | 85 Ohms | TOP=L2:L3=L2/L4:L6=L5/L7:BOTTOM=L7 |
| USB_DN_R | USB05-DIFF1 | PAIR | 5 | 5.5 | 5 | 10 | 5 | 12 | 6 | 20 | 12 | 12 | 12 | 12 | 7.5 | 85 Ohms | TOP=L2:L3=L2/L4:L6=L5/L7:BOTTOM=L7 |
| USB_DN_R | USB05-DIFF1 | PAIR | 6 | 5.5 | 5 | 10 | 5 | 12 | 6 | 20 | 12 | 12 | 12 | 12 | 7.5 | 85 Ohms | TOP=L2:L3=L2/L4:L6=L5/L7:BOTTOM=L7 |
| USB_DN_R | USB05-DIFF1 | PAIR | 7 | 5.5 | 5 | 10 | 5 | 12 | 6 | 20 | 12 | 12 | 12 | 12 | 7.5 | 85 Ohms | TOP=L2:L3=L2/L4:L6=L5/L7:BOTTOM=L7 |
| USB_DN_R | USB05-DIFF1 | PAIR | 8 | 5.38 | 5 | 10 | 5 | 12 | 6 | 33 | 12 | 12 | 12 | 12 | 6.62 | 85 Ohms | TOP=L2:L3=L2/L4:L6=L5/L7:BOTTOM=L7 |
| USB_DP_R | USB05-DIFF1 | PAIR | 1 | 5.38 | 5 | 10 | 5 | 12 | 6 | 33 | 12 | 12 | 12 | 12 | 6.62 | 85 Ohms | TOP=L2:L3=L2/L4:L6=L5/L7:BOTTOM=L7 |
| USB_DP_R | USB05-DIFF1 | PAIR | 2 | 5.5 | 5 | 10 | 5 | 12 | 6 | 20 | 12 | 12 | 12 | 12 | 7.5 | 85 Ohms | TOP=L2:L3=L2/L4:L6=L5/L7:BOTTOM=L7 |
| USB_DP_R | USB05-DIFF1 | PAIR | 3 | 5.5 | 5 | 10 | 5 | 12 | 6 | 20 | 12 | 12 | 12 | 12 | 7.5 | 85 Ohms | TOP=L2:L3=L2/L4:L6=L5/L7:BOTTOM=L7 |
| USB_DP_R | USB05-DIFF1 | PAIR | 4 | 5.5 | 5 | 10 | 5 | 12 | 6 | 20 | 12 | 12 | 12 | 12 | 7.5 | 85 Ohms | TOP=L2:L3=L2/L4:L6=L5/L7:BOTTOM=L7 |
| USB_DP_R | USB05-DIFF1 | PAIR | 5 | 5.5 | 5 | 10 | 5 | 12 | 6 | 20 | 12 | 12 | 12 | 12 | 7.5 | 85 Ohms | TOP=L2:L3=L2/L4:L6=L5/L7:BOTTOM=L7 |
| USB_DP_R | USB05-DIFF1 | PAIR | 6 | 5.5 | 5 | 10 | 5 | 12 | 6 | 20 | 12 | 12 | 12 | 12 | 7.5 | 85 Ohms | TOP=L2:L3=L2/L4:L6=L5/L7:BOTTOM=L7 |
| USB_DP_R | USB05-DIFF1 | PAIR | 7 | 5.5 | 5 | 10 | 5 | 12 | 6 | 20 | 12 | 12 | 12 | 12 | 7.5 | 85 Ohms | TOP=L2:L3=L2/L4:L6=L5/L7:BOTTOM=L7 |
| USB_DP_R | USB05-DIFF1 | PAIR | 8 | 5.38 | 5 | 10 | 5 | 12 | 6 | 33 | 12 | 12 | 12 | 12 | 6.62 | 85 Ohms | TOP=L2:L3=L2/L4:L6=L5/L7:BOTTOM=L7 |
| BMC_USB1_HDN | USB06-DIFF1 | PAIR | 1 | 5.38 | 5 | 10 | 5 | 12 | 6 | 33 | 12 | 12 | 12 | 12 | 6.62 | 85 Ohms | TOP=L2:L3=L2/L4:L6=L5/L7:BOTTOM=L7 |
| BMC_USB1_HDN | USB06-DIFF1 | PAIR | 2 | 5.5 | 5 | 10 | 5 | 12 | 6 | 20 | 12 | 12 | 12 | 12 | 7.5 | 85 Ohms | TOP=L2:L3=L2/L4:L6=L5/L7:BOTTOM=L7 |
| BMC_USB1_HDN | USB06-DIFF1 | PAIR | 3 | 5.5 | 5 | 10 | 5 | 12 | 6 | 20 | 12 | 12 | 12 | 12 | 7.5 | 85 Ohms | TOP=L2:L3=L2/L4:L6=L5/L7:BOTTOM=L7 |
| BMC_USB1_HDN | USB06-DIFF1 | PAIR | 4 | 5.5 | 5 | 10 | 5 | 12 | 6 | 20 | 12 | 12 | 12 | 12 | 7.5 | 85 Ohms | TOP=L2:L3=L2/L4:L6=L5/L7:BOTTOM=L7 |
| BMC_USB1_HDN | USB06-DIFF1 | PAIR | 5 | 5.5 | 5 | 10 | 5 | 12 | 6 | 20 | 12 | 12 | 12 | 12 | 7.5 | 85 Ohms | TOP=L2:L3=L2/L4:L6=L5/L7:BOTTOM=L7 |
| BMC_USB1_HDN | USB06-DIFF1 | PAIR | 6 | 5.5 | 5 | 10 | 5 | 12 | 6 | 20 | 12 | 12 | 12 | 12 | 7.5 | 85 Ohms | TOP=L2:L3=L2/L4:L6=L5/L7:BOTTOM=L7 |
| BMC_USB1_HDN | USB06-DIFF1 | PAIR | 7 | 5.5 | 5 | 10 | 5 | 12 | 6 | 20 | 12 | 12 | 12 | 12 | 7.5 | 85 Ohms | TOP=L2:L3=L2/L4:L6=L5/L7:BOTTOM=L7 |
| BMC_USB1_HDN | USB06-DIFF1 | PAIR | 8 | 5.38 | 5 | 10 | 5 | 12 | 6 | 33 | 12 | 12 | 12 | 12 | 6.62 | 85 Ohms | TOP=L2:L3=L2/L4:L6=L5/L7:BOTTOM=L7 |
| BMC_USB1_HDP | USB06-DIFF1 | PAIR | 1 | 5.38 | 5 | 10 | 5 | 12 | 6 | 33 | 12 | 12 | 12 | 12 | 6.62 | 85 Ohms | TOP=L2:L3=L2/L4:L6=L5/L7:BOTTOM=L7 |
| BMC_USB1_HDP | USB06-DIFF1 | PAIR | 2 | 5.5 | 5 | 10 | 5 | 12 | 6 | 20 | 12 | 12 | 12 | 12 | 7.5 | 85 Ohms | TOP=L2:L3=L2/L4:L6=L5/L7:BOTTOM=L7 |
| BMC_USB1_HDP | USB06-DIFF1 | PAIR | 3 | 5.5 | 5 | 10 | 5 | 12 | 6 | 20 | 12 | 12 | 12 | 12 | 7.5 | 85 Ohms | TOP=L2:L3=L2/L4:L6=L5/L7:BOTTOM=L7 |
| BMC_USB1_HDP | USB06-DIFF1 | PAIR | 4 | 5.5 | 5 | 10 | 5 | 12 | 6 | 20 | 12 | 12 | 12 | 12 | 7.5 | 85 Ohms | TOP=L2:L3=L2/L4:L6=L5/L7:BOTTOM=L7 |
| BMC_USB1_HDP | USB06-DIFF1 | PAIR | 5 | 5.5 | 5 | 10 | 5 | 12 | 6 | 20 | 12 | 12 | 12 | 12 | 7.5 | 85 Ohms | TOP=L2:L3=L2/L4:L6=L5/L7:BOTTOM=L7 |
| BMC_USB1_HDP | USB06-DIFF1 | PAIR | 6 | 5.5 | 5 | 10 | 5 | 12 | 6 | 20 | 12 | 12 | 12 | 12 | 7.5 | 85 Ohms | TOP=L2:L3=L2/L4:L6=L5/L7:BOTTOM=L7 |
| BMC_USB1_HDP | USB06-DIFF1 | PAIR | 7 | 5.5 | 5 | 10 | 5 | 12 | 6 | 20 | 12 | 12 | 12 | 12 | 7.5 | 85 Ohms | TOP=L2:L3=L2/L4:L6=L5/L7:BOTTOM=L7 |
| BMC_USB1_HDP | USB06-DIFF1 | PAIR | 8 | 5.38 | 5 | 10 | 5 | 12 | 6 | 33 | 12 | 12 | 12 | 12 | 6.62 | 85 Ohms | TOP=L2:L3=L2/L4:L6=L5/L7:BOTTOM=L7 |
| BMC_USB1_HDN2 | USB07-DIFF1 | PAIR | 1 | 5.38 | 5 | 10 | 5 | 12 | 6 | 33 | 12 | 12 | 12 | 12 | 6.62 | 85 Ohms | TOP=L2:L3=L2/L4:L6=L5/L7:BOTTOM=L7 |
| BMC_USB1_HDN2 | USB07-DIFF1 | PAIR | 2 | 5.5 | 5 | 10 | 5 | 12 | 6 | 20 | 12 | 12 | 12 | 12 | 7.5 | 85 Ohms | TOP=L2:L3=L2/L4:L6=L5/L7:BOTTOM=L7 |
| BMC_USB1_HDN2 | USB07-DIFF1 | PAIR | 3 | 5.5 | 5 | 10 | 5 | 12 | 6 | 20 | 12 | 12 | 12 | 12 | 7.5 | 85 Ohms | TOP=L2:L3=L2/L4:L6=L5/L7:BOTTOM=L7 |
| BMC_USB1_HDN2 | USB07-DIFF1 | PAIR | 4 | 5.5 | 5 | 10 | 5 | 12 | 6 | 20 | 12 | 12 | 12 | 12 | 7.5 | 85 Ohms | TOP=L2:L3=L2/L4:L6=L5/L7:BOTTOM=L7 |
| BMC_USB1_HDN2 | USB07-DIFF1 | PAIR | 5 | 5.5 | 5 | 10 | 5 | 12 | 6 | 20 | 12 | 12 | 12 | 12 | 7.5 | 85 Ohms | TOP=L2:L3=L2/L4:L6=L5/L7:BOTTOM=L7 |
| BMC_USB1_HDN2 | USB07-DIFF1 | PAIR | 6 | 5.5 | 5 | 10 | 5 | 12 | 6 | 20 | 12 | 12 | 12 | 12 | 7.5 | 85 Ohms | TOP=L2:L3=L2/L4:L6=L5/L7:BOTTOM=L7 |
| BMC_USB1_HDN2 | USB07-DIFF1 | PAIR | 7 | 5.5 | 5 | 10 | 5 | 12 | 6 | 20 | 12 | 12 | 12 | 12 | 7.5 | 85 Ohms | TOP=L2:L3=L2/L4:L6=L5/L7:BOTTOM=L7 |
| BMC_USB1_HDN2 | USB07-DIFF1 | PAIR | 8 | 5.38 | 5 | 10 | 5 | 12 | 6 | 33 | 12 | 12 | 12 | 12 | 6.62 | 85 Ohms | TOP=L2:L3=L2/L4:L6=L5/L7:BOTTOM=L7 |
| BMC_USB1_HDP2 | USB07-DIFF1 | PAIR | 1 | 5.38 | 5 | 10 | 5 | 12 | 6 | 33 | 12 | 12 | 12 | 12 | 6.62 | 85 Ohms | TOP=L2:L3=L2/L4:L6=L5/L7:BOTTOM=L7 |
| BMC_USB1_HDP2 | USB07-DIFF1 | PAIR | 2 | 5.5 | 5 | 10 | 5 | 12 | 6 | 20 | 12 | 12 | 12 | 12 | 7.5 | 85 Ohms | TOP=L2:L3=L2/L4:L6=L5/L7:BOTTOM=L7 |
| BMC_USB1_HDP2 | USB07-DIFF1 | PAIR | 3 | 5.5 | 5 | 10 | 5 | 12 | 6 | 20 | 12 | 12 | 12 | 12 | 7.5 | 85 Ohms | TOP=L2:L3=L2/L4:L6=L5/L7:BOTTOM=L7 |
| BMC_USB1_HDP2 | USB07-DIFF1 | PAIR | 4 | 5.5 | 5 | 10 | 5 | 12 | 6 | 20 | 12 | 12 | 12 | 12 | 7.5 | 85 Ohms | TOP=L2:L3=L2/L4:L6=L5/L7:BOTTOM=L7 |
| BMC_USB1_HDP2 | USB07-DIFF1 | PAIR | 5 | 5.5 | 5 | 10 | 5 | 12 | 6 | 20 | 12 | 12 | 12 | 12 | 7.5 | 85 Ohms | TOP=L2:L3=L2/L4:L6=L5/L7:BOTTOM=L7 |
| BMC_USB1_HDP2 | USB07-DIFF1 | PAIR | 6 | 5.5 | 5 | 10 | 5 | 12 | 6 | 20 | 12 | 12 | 12 | 12 | 7.5 | 85 Ohms | TOP=L2:L3=L2/L4:L6=L5/L7:BOTTOM=L7 |
| BMC_USB1_HDP2 | USB07-DIFF1 | PAIR | 7 | 5.5 | 5 | 10 | 5 | 12 | 6 | 20 | 12 | 12 | 12 | 12 | 7.5 | 85 Ohms | TOP=L2:L3=L2/L4:L6=L5/L7:BOTTOM=L7 |
| BMC_USB1_HDP2 | USB07-DIFF1 | PAIR | 8 | 5.38 | 5 | 10 | 5 | 12 | 6 | 33 | 12 | 12 | 12 | 12 | 6.62 | 85 Ohms | TOP=L2:L3=L2/L4:L6=L5/L7:BOTTOM=L7 |
| BMC_USB2_HDN | USB08-DIFF1 | PAIR | 1 | 5.38 | 5 | 10 | 5 | 12 | 6 | 33 | 12 | 12 | 12 | 12 | 6.62 | 85 Ohms | TOP=L2:L3=L2/L4:L6=L5/L7:BOTTOM=L7 |
| BMC_USB2_HDN | USB08-DIFF1 | PAIR | 2 | 5.5 | 5 | 10 | 5 | 12 | 6 | 20 | 12 | 12 | 12 | 12 | 7.5 | 85 Ohms | TOP=L2:L3=L2/L4:L6=L5/L7:BOTTOM=L7 |
| BMC_USB2_HDN | USB08-DIFF1 | PAIR | 3 | 5.5 | 5 | 10 | 5 | 12 | 6 | 20 | 12 | 12 | 12 | 12 | 7.5 | 85 Ohms | TOP=L2:L3=L2/L4:L6=L5/L7:BOTTOM=L7 |
| BMC_USB2_HDN | USB08-DIFF1 | PAIR | 4 | 5.5 | 5 | 10 | 5 | 12 | 6 | 20 | 12 | 12 | 12 | 12 | 7.5 | 85 Ohms | TOP=L2:L3=L2/L4:L6=L5/L7:BOTTOM=L7 |
| BMC_USB2_HDN | USB08-DIFF1 | PAIR | 5 | 5.5 | 5 | 10 | 5 | 12 | 6 | 20 | 12 | 12 | 12 | 12 | 7.5 | 85 Ohms | TOP=L2:L3=L2/L4:L6=L5/L7:BOTTOM=L7 |
| BMC_USB2_HDN | USB08-DIFF1 | PAIR | 6 | 5.5 | 5 | 10 | 5 | 12 | 6 | 20 | 12 | 12 | 12 | 12 | 7.5 | 85 Ohms | TOP=L2:L3=L2/L4:L6=L5/L7:BOTTOM=L7 |
| BMC_USB2_HDN | USB08-DIFF1 | PAIR | 7 | 5.5 | 5 | 10 | 5 | 12 | 6 | 20 | 12 | 12 | 12 | 12 | 7.5 | 85 Ohms | TOP=L2:L3=L2/L4:L6=L5/L7:BOTTOM=L7 |
| BMC_USB2_HDN | USB08-DIFF1 | PAIR | 8 | 5.38 | 5 | 10 | 5 | 12 | 6 | 33 | 12 | 12 | 12 | 12 | 6.62 | 85 Ohms | TOP=L2:L3=L2/L4:L6=L5/L7:BOTTOM=L7 |
| BMC_USB2_HDP | USB08-DIFF1 | PAIR | 1 | 5.38 | 5 | 10 | 5 | 12 | 6 | 33 | 12 | 12 | 12 | 12 | 6.62 | 85 Ohms | TOP=L2:L3=L2/L4:L6=L5/L7:BOTTOM=L7 |
| BMC_USB2_HDP | USB08-DIFF1 | PAIR | 2 | 5.5 | 5 | 10 | 5 | 12 | 6 | 20 | 12 | 12 | 12 | 12 | 7.5 | 85 Ohms | TOP=L2:L3=L2/L4:L6=L5/L7:BOTTOM=L7 |
| BMC_USB2_HDP | USB08-DIFF1 | PAIR | 3 | 5.5 | 5 | 10 | 5 | 12 | 6 | 20 | 12 | 12 | 12 | 12 | 7.5 | 85 Ohms | TOP=L2:L3=L2/L4:L6=L5/L7:BOTTOM=L7 |
| BMC_USB2_HDP | USB08-DIFF1 | PAIR | 4 | 5.5 | 5 | 10 | 5 | 12 | 6 | 20 | 12 | 12 | 12 | 12 | 7.5 | 85 Ohms | TOP=L2:L3=L2/L4:L6=L5/L7:BOTTOM=L7 |
| BMC_USB2_HDP | USB08-DIFF1 | PAIR | 5 | 5.5 | 5 | 10 | 5 | 12 | 6 | 20 | 12 | 12 | 12 | 12 | 7.5 | 85 Ohms | TOP=L2:L3=L2/L4:L6=L5/L7:BOTTOM=L7 |
| BMC_USB2_HDP | USB08-DIFF1 | PAIR | 6 | 5.5 | 5 | 10 | 5 | 12 | 6 | 20 | 12 | 12 | 12 | 12 | 7.5 | 85 Ohms | TOP=L2:L3=L2/L4:L6=L5/L7:BOTTOM=L7 |
| BMC_USB2_HDP | USB08-DIFF1 | PAIR | 7 | 5.5 | 5 | 10 | 5 | 12 | 6 | 20 | 12 | 12 | 12 | 12 | 7.5 | 85 Ohms | TOP=L2:L3=L2/L4:L6=L5/L7:BOTTOM=L7 |
| BMC_USB2_HDP | USB08-DIFF1 | PAIR | 8 | 5.38 | 5 | 10 | 5 | 12 | 6 | 33 | 12 | 12 | 12 | 12 | 6.62 | 85 Ohms | TOP=L2:L3=L2/L4:L6=L5/L7:BOTTOM=L7 |
| 8644_USB_DN1 | USB09-DIFF1 | PAIR | 1 | 5.38 | 5 | 10 | 5 | 12 | 6 | 33 | 12 | 12 | 12 | 12 | 6.62 | 85 Ohms | TOP=L2:L3=L2/L4:L6=L5/L7:BOTTOM=L7 |
| 8644_USB_DN1 | USB09-DIFF1 | PAIR | 2 | 5.5 | 5 | 10 | 5 | 12 | 6 | 20 | 12 | 12 | 12 | 12 | 7.5 | 85 Ohms | TOP=L2:L3=L2/L4:L6=L5/L7:BOTTOM=L7 |
| 8644_USB_DN1 | USB09-DIFF1 | PAIR | 3 | 5.5 | 5 | 10 | 5 | 12 | 6 | 20 | 12 | 12 | 12 | 12 | 7.5 | 85 Ohms | TOP=L2:L3=L2/L4:L6=L5/L7:BOTTOM=L7 |
| 8644_USB_DN1 | USB09-DIFF1 | PAIR | 4 | 5.5 | 5 | 10 | 5 | 12 | 6 | 20 | 12 | 12 | 12 | 12 | 7.5 | 85 Ohms | TOP=L2:L3=L2/L4:L6=L5/L7:BOTTOM=L7 |
| 8644_USB_DN1 | USB09-DIFF1 | PAIR | 5 | 5.5 | 5 | 10 | 5 | 12 | 6 | 20 | 12 | 12 | 12 | 12 | 7.5 | 85 Ohms | TOP=L2:L3=L2/L4:L6=L5/L7:BOTTOM=L7 |
| 8644_USB_DN1 | USB09-DIFF1 | PAIR | 6 | 5.5 | 5 | 10 | 5 | 12 | 6 | 20 | 12 | 12 | 12 | 12 | 7.5 | 85 Ohms | TOP=L2:L3=L2/L4:L6=L5/L7:BOTTOM=L7 |
| 8644_USB_DN1 | USB09-DIFF1 | PAIR | 7 | 5.5 | 5 | 10 | 5 | 12 | 6 | 20 | 12 | 12 | 12 | 12 | 7.5 | 85 Ohms | TOP=L2:L3=L2/L4:L6=L5/L7:BOTTOM=L7 |
| 8644_USB_DN1 | USB09-DIFF1 | PAIR | 8 | 5.38 | 5 | 10 | 5 | 12 | 6 | 33 | 12 | 12 | 12 | 12 | 6.62 | 85 Ohms | TOP=L2:L3=L2/L4:L6=L5/L7:BOTTOM=L7 |
| 8644_USB_DP1 | USB09-DIFF1 | PAIR | 1 | 5.38 | 5 | 10 | 5 | 12 | 6 | 33 | 12 | 12 | 12 | 12 | 6.62 | 85 Ohms | TOP=L2:L3=L2/L4:L6=L5/L7:BOTTOM=L7 |
| 8644_USB_DP1 | USB09-DIFF1 | PAIR | 2 | 5.5 | 5 | 10 | 5 | 12 | 6 | 20 | 12 | 12 | 12 | 12 | 7.5 | 85 Ohms | TOP=L2:L3=L2/L4:L6=L5/L7:BOTTOM=L7 |
| 8644_USB_DP1 | USB09-DIFF1 | PAIR | 3 | 5.5 | 5 | 10 | 5 | 12 | 6 | 20 | 12 | 12 | 12 | 12 | 7.5 | 85 Ohms | TOP=L2:L3=L2/L4:L6=L5/L7:BOTTOM=L7 |
| 8644_USB_DP1 | USB09-DIFF1 | PAIR | 4 | 5.5 | 5 | 10 | 5 | 12 | 6 | 20 | 12 | 12 | 12 | 12 | 7.5 | 85 Ohms | TOP=L2:L3=L2/L4:L6=L5/L7:BOTTOM=L7 |
| 8644_USB_DP1 | USB09-DIFF1 | PAIR | 5 | 5.5 | 5 | 10 | 5 | 12 | 6 | 20 | 12 | 12 | 12 | 12 | 7.5 | 85 Ohms | TOP=L2:L3=L2/L4:L6=L5/L7:BOTTOM=L7 |
| 8644_USB_DP1 | USB09-DIFF1 | PAIR | 6 | 5.5 | 5 | 10 | 5 | 12 | 6 | 20 | 12 | 12 | 12 | 12 | 7.5 | 85 Ohms | TOP=L2:L3=L2/L4:L6=L5/L7:BOTTOM=L7 |
| 8644_USB_DP1 | USB09-DIFF1 | PAIR | 7 | 5.5 | 5 | 10 | 5 | 12 | 6 | 20 | 12 | 12 | 12 | 12 | 7.5 | 85 Ohms | TOP=L2:L3=L2/L4:L6=L5/L7:BOTTOM=L7 |
| 8644_USB_DP1 | USB09-DIFF1 | PAIR | 8 | 5.38 | 5 | 10 | 5 | 12 | 6 | 33 | 12 | 12 | 12 | 12 | 6.62 | 85 Ohms | TOP=L2:L3=L2/L4:L6=L5/L7:BOTTOM=L7 |
| 8644_USB_DN2 | USB10-DIFF1 | PAIR | 1 | 5.38 | 5 | 10 | 5 | 12 | 6 | 33 | 12 | 12 | 12 | 12 | 6.62 | 85 Ohms | TOP=L2:L3=L2/L4:L6=L5/L7:BOTTOM=L7 |
| 8644_USB_DN2 | USB10-DIFF1 | PAIR | 2 | 5.5 | 5 | 10 | 5 | 12 | 6 | 20 | 12 | 12 | 12 | 12 | 7.5 | 85 Ohms | TOP=L2:L3=L2/L4:L6=L5/L7:BOTTOM=L7 |
| 8644_USB_DN2 | USB10-DIFF1 | PAIR | 3 | 5.5 | 5 | 10 | 5 | 12 | 6 | 20 | 12 | 12 | 12 | 12 | 7.5 | 85 Ohms | TOP=L2:L3=L2/L4:L6=L5/L7:BOTTOM=L7 |
| 8644_USB_DN2 | USB10-DIFF1 | PAIR | 4 | 5.5 | 5 | 10 | 5 | 12 | 6 | 20 | 12 | 12 | 12 | 12 | 7.5 | 85 Ohms | TOP=L2:L3=L2/L4:L6=L5/L7:BOTTOM=L7 |
| 8644_USB_DN2 | USB10-DIFF1 | PAIR | 5 | 5.5 | 5 | 10 | 5 | 12 | 6 | 20 | 12 | 12 | 12 | 12 | 7.5 | 85 Ohms | TOP=L2:L3=L2/L4:L6=L5/L7:BOTTOM=L7 |
| 8644_USB_DN2 | USB10-DIFF1 | PAIR | 6 | 5.5 | 5 | 10 | 5 | 12 | 6 | 20 | 12 | 12 | 12 | 12 | 7.5 | 85 Ohms | TOP=L2:L3=L2/L4:L6=L5/L7:BOTTOM=L7 |
| 8644_USB_DN2 | USB10-DIFF1 | PAIR | 7 | 5.5 | 5 | 10 | 5 | 12 | 6 | 20 | 12 | 12 | 12 | 12 | 7.5 | 85 Ohms | TOP=L2:L3=L2/L4:L6=L5/L7:BOTTOM=L7 |
| 8644_USB_DN2 | USB10-DIFF1 | PAIR | 8 | 5.38 | 5 | 10 | 5 | 12 | 6 | 33 | 12 | 12 | 12 | 12 | 6.62 | 85 Ohms | TOP=L2:L3=L2/L4:L6=L5/L7:BOTTOM=L7 |
| 8644_USB_DP2 | USB10-DIFF1 | PAIR | 1 | 5.38 | 5 | 10 | 5 | 12 | 6 | 33 | 12 | 12 | 12 | 12 | 6.62 | 85 Ohms | TOP=L2:L3=L2/L4:L6=L5/L7:BOTTOM=L7 |
| 8644_USB_DP2 | USB10-DIFF1 | PAIR | 2 | 5.5 | 5 | 10 | 5 | 12 | 6 | 20 | 12 | 12 | 12 | 12 | 7.5 | 85 Ohms | TOP=L2:L3=L2/L4:L6=L5/L7:BOTTOM=L7 |
| 8644_USB_DP2 | USB10-DIFF1 | PAIR | 3 | 5.5 | 5 | 10 | 5 | 12 | 6 | 20 | 12 | 12 | 12 | 12 | 7.5 | 85 Ohms | TOP=L2:L3=L2/L4:L6=L5/L7:BOTTOM=L7 |
| 8644_USB_DP2 | USB10-DIFF1 | PAIR | 4 | 5.5 | 5 | 10 | 5 | 12 | 6 | 20 | 12 | 12 | 12 | 12 | 7.5 | 85 Ohms | TOP=L2:L3=L2/L4:L6=L5/L7:BOTTOM=L7 |
| 8644_USB_DP2 | USB10-DIFF1 | PAIR | 5 | 5.5 | 5 | 10 | 5 | 12 | 6 | 20 | 12 | 12 | 12 | 12 | 7.5 | 85 Ohms | TOP=L2:L3=L2/L4:L6=L5/L7:BOTTOM=L7 |
| 8644_USB_DP2 | USB10-DIFF1 | PAIR | 6 | 5.5 | 5 | 10 | 5 | 12 | 6 | 20 | 12 | 12 | 12 | 12 | 7.5 | 85 Ohms | TOP=L2:L3=L2/L4:L6=L5/L7:BOTTOM=L7 |
| 8644_USB_DP2 | USB10-DIFF1 | PAIR | 7 | 5.5 | 5 | 10 | 5 | 12 | 6 | 20 | 12 | 12 | 12 | 12 | 7.5 | 85 Ohms | TOP=L2:L3=L2/L4:L6=L5/L7:BOTTOM=L7 |
| 8644_USB_DP2 | USB10-DIFF1 | PAIR | 8 | 5.38 | 5 | 10 | 5 | 12 | 6 | 33 | 12 | 12 | 12 | 12 | 6.62 | 85 Ohms | TOP=L2:L3=L2/L4:L6=L5/L7:BOTTOM=L7 |
| 8644_USB_DN3 | USB11-DIFF1 | PAIR | 1 | 5.38 | 5 | 10 | 5 | 12 | 6 | 33 | 12 | 12 | 12 | 12 | 6.62 | 85 Ohms | TOP=L2:L3=L2/L4:L6=L5/L7:BOTTOM=L7 |
| 8644_USB_DN3 | USB11-DIFF1 | PAIR | 2 | 5.5 | 5 | 10 | 5 | 12 | 6 | 20 | 12 | 12 | 12 | 12 | 7.5 | 85 Ohms | TOP=L2:L3=L2/L4:L6=L5/L7:BOTTOM=L7 |
| 8644_USB_DN3 | USB11-DIFF1 | PAIR | 3 | 5.5 | 5 | 10 | 5 | 12 | 6 | 20 | 12 | 12 | 12 | 12 | 7.5 | 85 Ohms | TOP=L2:L3=L2/L4:L6=L5/L7:BOTTOM=L7 |
| 8644_USB_DN3 | USB11-DIFF1 | PAIR | 4 | 5.5 | 5 | 10 | 5 | 12 | 6 | 20 | 12 | 12 | 12 | 12 | 7.5 | 85 Ohms | TOP=L2:L3=L2/L4:L6=L5/L7:BOTTOM=L7 |
| 8644_USB_DN3 | USB11-DIFF1 | PAIR | 5 | 5.5 | 5 | 10 | 5 | 12 | 6 | 20 | 12 | 12 | 12 | 12 | 7.5 | 85 Ohms | TOP=L2:L3=L2/L4:L6=L5/L7:BOTTOM=L7 |
| 8644_USB_DN3 | USB11-DIFF1 | PAIR | 6 | 5.5 | 5 | 10 | 5 | 12 | 6 | 20 | 12 | 12 | 12 | 12 | 7.5 | 85 Ohms | TOP=L2:L3=L2/L4:L6=L5/L7:BOTTOM=L7 |
| 8644_USB_DN3 | USB11-DIFF1 | PAIR | 7 | 5.5 | 5 | 10 | 5 | 12 | 6 | 20 | 12 | 12 | 12 | 12 | 7.5 | 85 Ohms | TOP=L2:L3=L2/L4:L6=L5/L7:BOTTOM=L7 |
| 8644_USB_DN3 | USB11-DIFF1 | PAIR | 8 | 5.38 | 5 | 10 | 5 | 12 | 6 | 33 | 12 | 12 | 12 | 12 | 6.62 | 85 Ohms | TOP=L2:L3=L2/L4:L6=L5/L7:BOTTOM=L7 |
| 8644_USB_DP3 | USB11-DIFF1 | PAIR | 1 | 5.38 | 5 | 10 | 5 | 12 | 6 | 33 | 12 | 12 | 12 | 12 | 6.62 | 85 Ohms | TOP=L2:L3=L2/L4:L6=L5/L7:BOTTOM=L7 |
| 8644_USB_DP3 | USB11-DIFF1 | PAIR | 2 | 5.5 | 5 | 10 | 5 | 12 | 6 | 20 | 12 | 12 | 12 | 12 | 7.5 | 85 Ohms | TOP=L2:L3=L2/L4:L6=L5/L7:BOTTOM=L7 |
| 8644_USB_DP3 | USB11-DIFF1 | PAIR | 3 | 5.5 | 5 | 10 | 5 | 12 | 6 | 20 | 12 | 12 | 12 | 12 | 7.5 | 85 Ohms | TOP=L2:L3=L2/L4:L6=L5/L7:BOTTOM=L7 |
| 8644_USB_DP3 | USB11-DIFF1 | PAIR | 4 | 5.5 | 5 | 10 | 5 | 12 | 6 | 20 | 12 | 12 | 12 | 12 | 7.5 | 85 Ohms | TOP=L2:L3=L2/L4:L6=L5/L7:BOTTOM=L7 |
| 8644_USB_DP3 | USB11-DIFF1 | PAIR | 5 | 5.5 | 5 | 10 | 5 | 12 | 6 | 20 | 12 | 12 | 12 | 12 | 7.5 | 85 Ohms | TOP=L2:L3=L2/L4:L6=L5/L7:BOTTOM=L7 |
| 8644_USB_DP3 | USB11-DIFF1 | PAIR | 6 | 5.5 | 5 | 10 | 5 | 12 | 6 | 20 | 12 | 12 | 12 | 12 | 7.5 | 85 Ohms | TOP=L2:L3=L2/L4:L6=L5/L7:BOTTOM=L7 |
| 8644_USB_DP3 | USB11-DIFF1 | PAIR | 7 | 5.5 | 5 | 10 | 5 | 12 | 6 | 20 | 12 | 12 | 12 | 12 | 7.5 | 85 Ohms | TOP=L2:L3=L2/L4:L6=L5/L7:BOTTOM=L7 |
| 8644_USB_DP3 | USB11-DIFF1 | PAIR | 8 | 5.38 | 5 | 10 | 5 | 12 | 6 | 33 | 12 | 12 | 12 | 12 | 6.62 | 85 Ohms | TOP=L2:L3=L2/L4:L6=L5/L7:BOTTOM=L7 |
| 8644_USB_DN5 | USB12-DIFF1 | PAIR | 1 | 5.38 | 5 | 10 | 5 | 12 | 6 | 33 | 12 | 12 | 12 | 12 | 6.62 | 85 Ohms | TOP=L2:L3=L2/L4:L6=L5/L7:BOTTOM=L7 |
| 8644_USB_DN5 | USB12-DIFF1 | PAIR | 2 | 5.5 | 5 | 10 | 5 | 12 | 6 | 20 | 12 | 12 | 12 | 12 | 7.5 | 85 Ohms | TOP=L2:L3=L2/L4:L6=L5/L7:BOTTOM=L7 |
| 8644_USB_DN5 | USB12-DIFF1 | PAIR | 3 | 5.5 | 5 | 10 | 5 | 12 | 6 | 20 | 12 | 12 | 12 | 12 | 7.5 | 85 Ohms | TOP=L2:L3=L2/L4:L6=L5/L7:BOTTOM=L7 |
| 8644_USB_DN5 | USB12-DIFF1 | PAIR | 4 | 5.5 | 5 | 10 | 5 | 12 | 6 | 20 | 12 | 12 | 12 | 12 | 7.5 | 85 Ohms | TOP=L2:L3=L2/L4:L6=L5/L7:BOTTOM=L7 |
| 8644_USB_DN5 | USB12-DIFF1 | PAIR | 5 | 5.5 | 5 | 10 | 5 | 12 | 6 | 20 | 12 | 12 | 12 | 12 | 7.5 | 85 Ohms | TOP=L2:L3=L2/L4:L6=L5/L7:BOTTOM=L7 |
| 8644_USB_DN5 | USB12-DIFF1 | PAIR | 6 | 5.5 | 5 | 10 | 5 | 12 | 6 | 20 | 12 | 12 | 12 | 12 | 7.5 | 85 Ohms | TOP=L2:L3=L2/L4:L6=L5/L7:BOTTOM=L7 |
| 8644_USB_DN5 | USB12-DIFF1 | PAIR | 7 | 5.5 | 5 | 10 | 5 | 12 | 6 | 20 | 12 | 12 | 12 | 12 | 7.5 | 85 Ohms | TOP=L2:L3=L2/L4:L6=L5/L7:BOTTOM=L7 |
| 8644_USB_DN5 | USB12-DIFF1 | PAIR | 8 | 5.38 | 5 | 10 | 5 | 12 | 6 | 33 | 12 | 12 | 12 | 12 | 6.62 | 85 Ohms | TOP=L2:L3=L2/L4:L6=L5/L7:BOTTOM=L7 |
| 8644_USB_DP5 | USB12-DIFF1 | PAIR | 1 | 5.38 | 5 | 10 | 5 | 12 | 6 | 33 | 12 | 12 | 12 | 12 | 6.62 | 85 Ohms | TOP=L2:L3=L2/L4:L6=L5/L7:BOTTOM=L7 |
| 8644_USB_DP5 | USB12-DIFF1 | PAIR | 2 | 5.5 | 5 | 10 | 5 | 12 | 6 | 20 | 12 | 12 | 12 | 12 | 7.5 | 85 Ohms | TOP=L2:L3=L2/L4:L6=L5/L7:BOTTOM=L7 |
| 8644_USB_DP5 | USB12-DIFF1 | PAIR | 3 | 5.5 | 5 | 10 | 5 | 12 | 6 | 20 | 12 | 12 | 12 | 12 | 7.5 | 85 Ohms | TOP=L2:L3=L2/L4:L6=L5/L7:BOTTOM=L7 |
| 8644_USB_DP5 | USB12-DIFF1 | PAIR | 4 | 5.5 | 5 | 10 | 5 | 12 | 6 | 20 | 12 | 12 | 12 | 12 | 7.5 | 85 Ohms | TOP=L2:L3=L2/L4:L6=L5/L7:BOTTOM=L7 |
| 8644_USB_DP5 | USB12-DIFF1 | PAIR | 5 | 5.5 | 5 | 10 | 5 | 12 | 6 | 20 | 12 | 12 | 12 | 12 | 7.5 | 85 Ohms | TOP=L2:L3=L2/L4:L6=L5/L7:BOTTOM=L7 |
| 8644_USB_DP5 | USB12-DIFF1 | PAIR | 6 | 5.5 | 5 | 10 | 5 | 12 | 6 | 20 | 12 | 12 | 12 | 12 | 7.5 | 85 Ohms | TOP=L2:L3=L2/L4:L6=L5/L7:BOTTOM=L7 |
| 8644_USB_DP5 | USB12-DIFF1 | PAIR | 7 | 5.5 | 5 | 10 | 5 | 12 | 6 | 20 | 12 | 12 | 12 | 12 | 7.5 | 85 Ohms | TOP=L2:L3=L2/L4:L6=L5/L7:BOTTOM=L7 |
| 8644_USB_DP5 | USB12-DIFF1 | PAIR | 8 | 5.38 | 5 | 10 | 5 | 12 | 6 | 33 | 12 | 12 | 12 | 12 | 6.62 | 85 Ohms | TOP=L2:L3=L2/L4:L6=L5/L7:BOTTOM=L7 |
| 8644_USB_DN6 | USB13-DIFF1 | PAIR | 1 | 5.38 | 5 | 10 | 5 | 12 | 6 | 33 | 12 | 12 | 12 | 12 | 6.62 | 85 Ohms | TOP=L2:L3=L2/L4:L6=L5/L7:BOTTOM=L7 |
| 8644_USB_DN6 | USB13-DIFF1 | PAIR | 2 | 5.5 | 5 | 10 | 5 | 12 | 6 | 20 | 12 | 12 | 12 | 12 | 7.5 | 85 Ohms | TOP=L2:L3=L2/L4:L6=L5/L7:BOTTOM=L7 |
| 8644_USB_DN6 | USB13-DIFF1 | PAIR | 3 | 5.5 | 5 | 10 | 5 | 12 | 6 | 20 | 12 | 12 | 12 | 12 | 7.5 | 85 Ohms | TOP=L2:L3=L2/L4:L6=L5/L7:BOTTOM=L7 |
| 8644_USB_DN6 | USB13-DIFF1 | PAIR | 4 | 5.5 | 5 | 10 | 5 | 12 | 6 | 20 | 12 | 12 | 12 | 12 | 7.5 | 85 Ohms | TOP=L2:L3=L2/L4:L6=L5/L7:BOTTOM=L7 |
| 8644_USB_DN6 | USB13-DIFF1 | PAIR | 5 | 5.5 | 5 | 10 | 5 | 12 | 6 | 20 | 12 | 12 | 12 | 12 | 7.5 | 85 Ohms | TOP=L2:L3=L2/L4:L6=L5/L7:BOTTOM=L7 |
| 8644_USB_DN6 | USB13-DIFF1 | PAIR | 6 | 5.5 | 5 | 10 | 5 | 12 | 6 | 20 | 12 | 12 | 12 | 12 | 7.5 | 85 Ohms | TOP=L2:L3=L2/L4:L6=L5/L7:BOTTOM=L7 |
| 8644_USB_DN6 | USB13-DIFF1 | PAIR | 7 | 5.5 | 5 | 10 | 5 | 12 | 6 | 20 | 12 | 12 | 12 | 12 | 7.5 | 85 Ohms | TOP=L2:L3=L2/L4:L6=L5/L7:BOTTOM=L7 |
| 8644_USB_DN6 | USB13-DIFF1 | PAIR | 8 | 5.38 | 5 | 10 | 5 | 12 | 6 | 33 | 12 | 12 | 12 | 12 | 6.62 | 85 Ohms | TOP=L2:L3=L2/L4:L6=L5/L7:BOTTOM=L7 |
| 8644_USB_DP6 | USB13-DIFF1 | PAIR | 1 | 5.38 | 5 | 10 | 5 | 12 | 6 | 33 | 12 | 12 | 12 | 12 | 6.62 | 85 Ohms | TOP=L2:L3=L2/L4:L6=L5/L7:BOTTOM=L7 |
| 8644_USB_DP6 | USB13-DIFF1 | PAIR | 2 | 5.5 | 5 | 10 | 5 | 12 | 6 | 20 | 12 | 12 | 12 | 12 | 7.5 | 85 Ohms | TOP=L2:L3=L2/L4:L6=L5/L7:BOTTOM=L7 |
| 8644_USB_DP6 | USB13-DIFF1 | PAIR | 3 | 5.5 | 5 | 10 | 5 | 12 | 6 | 20 | 12 | 12 | 12 | 12 | 7.5 | 85 Ohms | TOP=L2:L3=L2/L4:L6=L5/L7:BOTTOM=L7 |
| 8644_USB_DP6 | USB13-DIFF1 | PAIR | 4 | 5.5 | 5 | 10 | 5 | 12 | 6 | 20 | 12 | 12 | 12 | 12 | 7.5 | 85 Ohms | TOP=L2:L3=L2/L4:L6=L5/L7:BOTTOM=L7 |
| 8644_USB_DP6 | USB13-DIFF1 | PAIR | 5 | 5.5 | 5 | 10 | 5 | 12 | 6 | 20 | 12 | 12 | 12 | 12 | 7.5 | 85 Ohms | TOP=L2:L3=L2/L4:L6=L5/L7:BOTTOM=L7 |
| 8644_USB_DP6 | USB13-DIFF1 | PAIR | 6 | 5.5 | 5 | 10 | 5 | 12 | 6 | 20 | 12 | 12 | 12 | 12 | 7.5 | 85 Ohms | TOP=L2:L3=L2/L4:L6=L5/L7:BOTTOM=L7 |
| 8644_USB_DP6 | USB13-DIFF1 | PAIR | 7 | 5.5 | 5 | 10 | 5 | 12 | 6 | 20 | 12 | 12 | 12 | 12 | 7.5 | 85 Ohms | TOP=L2:L3=L2/L4:L6=L5/L7:BOTTOM=L7 |
| 8644_USB_DP6 | USB13-DIFF1 | PAIR | 8 | 5.38 | 5 | 10 | 5 | 12 | 6 | 33 | 12 | 12 | 12 | 12 | 6.62 | 85 Ohms | TOP=L2:L3=L2/L4:L6=L5/L7:BOTTOM=L7 |
| 8644_USB_DN7 | USB14-DIFF1 | PAIR | 1 | 5.38 | 5 | 10 | 5 | 12 | 6 | 33 | 12 | 12 | 12 | 12 | 6.62 | 85 Ohms | TOP=L2:L3=L2/L4:L6=L5/L7:BOTTOM=L7 |
| 8644_USB_DN7 | USB14-DIFF1 | PAIR | 2 | 5.5 | 5 | 10 | 5 | 12 | 6 | 20 | 12 | 12 | 12 | 12 | 7.5 | 85 Ohms | TOP=L2:L3=L2/L4:L6=L5/L7:BOTTOM=L7 |
| 8644_USB_DN7 | USB14-DIFF1 | PAIR | 3 | 5.5 | 5 | 10 | 5 | 12 | 6 | 20 | 12 | 12 | 12 | 12 | 7.5 | 85 Ohms | TOP=L2:L3=L2/L4:L6=L5/L7:BOTTOM=L7 |
| 8644_USB_DN7 | USB14-DIFF1 | PAIR | 4 | 5.5 | 5 | 10 | 5 | 12 | 6 | 20 | 12 | 12 | 12 | 12 | 7.5 | 85 Ohms | TOP=L2:L3=L2/L4:L6=L5/L7:BOTTOM=L7 |
| 8644_USB_DN7 | USB14-DIFF1 | PAIR | 5 | 5.5 | 5 | 10 | 5 | 12 | 6 | 20 | 12 | 12 | 12 | 12 | 7.5 | 85 Ohms | TOP=L2:L3=L2/L4:L6=L5/L7:BOTTOM=L7 |
| 8644_USB_DN7 | USB14-DIFF1 | PAIR | 6 | 5.5 | 5 | 10 | 5 | 12 | 6 | 20 | 12 | 12 | 12 | 12 | 7.5 | 85 Ohms | TOP=L2:L3=L2/L4:L6=L5/L7:BOTTOM=L7 |
| 8644_USB_DN7 | USB14-DIFF1 | PAIR | 7 | 5.5 | 5 | 10 | 5 | 12 | 6 | 20 | 12 | 12 | 12 | 12 | 7.5 | 85 Ohms | TOP=L2:L3=L2/L4:L6=L5/L7:BOTTOM=L7 |
| 8644_USB_DN7 | USB14-DIFF1 | PAIR | 8 | 5.38 | 5 | 10 | 5 | 12 | 6 | 33 | 12 | 12 | 12 | 12 | 6.62 | 85 Ohms | TOP=L2:L3=L2/L4:L6=L5/L7:BOTTOM=L7 |
| 8644_USB_DP7 | USB14-DIFF1 | PAIR | 1 | 5.38 | 5 | 10 | 5 | 12 | 6 | 33 | 12 | 12 | 12 | 12 | 6.62 | 85 Ohms | TOP=L2:L3=L2/L4:L6=L5/L7:BOTTOM=L7 |
| 8644_USB_DP7 | USB14-DIFF1 | PAIR | 2 | 5.5 | 5 | 10 | 5 | 12 | 6 | 20 | 12 | 12 | 12 | 12 | 7.5 | 85 Ohms | TOP=L2:L3=L2/L4:L6=L5/L7:BOTTOM=L7 |
| 8644_USB_DP7 | USB14-DIFF1 | PAIR | 3 | 5.5 | 5 | 10 | 5 | 12 | 6 | 20 | 12 | 12 | 12 | 12 | 7.5 | 85 Ohms | TOP=L2:L3=L2/L4:L6=L5/L7:BOTTOM=L7 |
| 8644_USB_DP7 | USB14-DIFF1 | PAIR | 4 | 5.5 | 5 | 10 | 5 | 12 | 6 | 20 | 12 | 12 | 12 | 12 | 7.5 | 85 Ohms | TOP=L2:L3=L2/L4:L6=L5/L7:BOTTOM=L7 |
| 8644_USB_DP7 | USB14-DIFF1 | PAIR | 5 | 5.5 | 5 | 10 | 5 | 12 | 6 | 20 | 12 | 12 | 12 | 12 | 7.5 | 85 Ohms | TOP=L2:L3=L2/L4:L6=L5/L7:BOTTOM=L7 |
| 8644_USB_DP7 | USB14-DIFF1 | PAIR | 6 | 5.5 | 5 | 10 | 5 | 12 | 6 | 20 | 12 | 12 | 12 | 12 | 7.5 | 85 Ohms | TOP=L2:L3=L2/L4:L6=L5/L7:BOTTOM=L7 |
| 8644_USB_DP7 | USB14-DIFF1 | PAIR | 7 | 5.5 | 5 | 10 | 5 | 12 | 6 | 20 | 12 | 12 | 12 | 12 | 7.5 | 85 Ohms | TOP=L2:L3=L2/L4:L6=L5/L7:BOTTOM=L7 |
| 8644_USB_DP7 | USB14-DIFF1 | PAIR | 8 | 5.38 | 5 | 10 | 5 | 12 | 6 | 33 | 12 | 12 | 12 | 12 | 6.62 | 85 Ohms | TOP=L2:L3=L2/L4:L6=L5/L7:BOTTOM=L7 |
| 8644_USB_DN8 | USB15-DIFF1 | PAIR | 1 | 5.38 | 5 | 10 | 5 | 12 | 6 | 33 | 12 | 12 | 12 | 12 | 6.62 | 85 Ohms | TOP=L2:L3=L2/L4:L6=L5/L7:BOTTOM=L7 |
| 8644_USB_DN8 | USB15-DIFF1 | PAIR | 2 | 5.5 | 5 | 10 | 5 | 12 | 6 | 20 | 12 | 12 | 12 | 12 | 7.5 | 85 Ohms | TOP=L2:L3=L2/L4:L6=L5/L7:BOTTOM=L7 |
| 8644_USB_DN8 | USB15-DIFF1 | PAIR | 3 | 5.5 | 5 | 10 | 5 | 12 | 6 | 20 | 12 | 12 | 12 | 12 | 7.5 | 85 Ohms | TOP=L2:L3=L2/L4:L6=L5/L7:BOTTOM=L7 |
| 8644_USB_DN8 | USB15-DIFF1 | PAIR | 4 | 5.5 | 5 | 10 | 5 | 12 | 6 | 20 | 12 | 12 | 12 | 12 | 7.5 | 85 Ohms | TOP=L2:L3=L2/L4:L6=L5/L7:BOTTOM=L7 |
| 8644_USB_DN8 | USB15-DIFF1 | PAIR | 5 | 5.5 | 5 | 10 | 5 | 12 | 6 | 20 | 12 | 12 | 12 | 12 | 7.5 | 85 Ohms | TOP=L2:L3=L2/L4:L6=L5/L7:BOTTOM=L7 |
| 8644_USB_DN8 | USB15-DIFF1 | PAIR | 6 | 5.5 | 5 | 10 | 5 | 12 | 6 | 20 | 12 | 12 | 12 | 12 | 7.5 | 85 Ohms | TOP=L2:L3=L2/L4:L6=L5/L7:BOTTOM=L7 |
| 8644_USB_DN8 | USB15-DIFF1 | PAIR | 7 | 5.5 | 5 | 10 | 5 | 12 | 6 | 20 | 12 | 12 | 12 | 12 | 7.5 | 85 Ohms | TOP=L2:L3=L2/L4:L6=L5/L7:BOTTOM=L7 |
| 8644_USB_DN8 | USB15-DIFF1 | PAIR | 8 | 5.38 | 5 | 10 | 5 | 12 | 6 | 33 | 12 | 12 | 12 | 12 | 6.62 | 85 Ohms | TOP=L2:L3=L2/L4:L6=L5/L7:BOTTOM=L7 |
| 8644_USB_DP8 | USB15-DIFF1 | PAIR | 1 | 5.38 | 5 | 10 | 5 | 12 | 6 | 33 | 12 | 12 | 12 | 12 | 6.62 | 85 Ohms | TOP=L2:L3=L2/L4:L6=L5/L7:BOTTOM=L7 |
| 8644_USB_DP8 | USB15-DIFF1 | PAIR | 2 | 5.5 | 5 | 10 | 5 | 12 | 6 | 20 | 12 | 12 | 12 | 12 | 7.5 | 85 Ohms | TOP=L2:L3=L2/L4:L6=L5/L7:BOTTOM=L7 |
| 8644_USB_DP8 | USB15-DIFF1 | PAIR | 3 | 5.5 | 5 | 10 | 5 | 12 | 6 | 20 | 12 | 12 | 12 | 12 | 7.5 | 85 Ohms | TOP=L2:L3=L2/L4:L6=L5/L7:BOTTOM=L7 |
| 8644_USB_DP8 | USB15-DIFF1 | PAIR | 4 | 5.5 | 5 | 10 | 5 | 12 | 6 | 20 | 12 | 12 | 12 | 12 | 7.5 | 85 Ohms | TOP=L2:L3=L2/L4:L6=L5/L7:BOTTOM=L7 |
| 8644_USB_DP8 | USB15-DIFF1 | PAIR | 5 | 5.5 | 5 | 10 | 5 | 12 | 6 | 20 | 12 | 12 | 12 | 12 | 7.5 | 85 Ohms | TOP=L2:L3=L2/L4:L6=L5/L7:BOTTOM=L7 |
| 8644_USB_DP8 | USB15-DIFF1 | PAIR | 6 | 5.5 | 5 | 10 | 5 | 12 | 6 | 20 | 12 | 12 | 12 | 12 | 7.5 | 85 Ohms | TOP=L2:L3=L2/L4:L6=L5/L7:BOTTOM=L7 |
| 8644_USB_DP8 | USB15-DIFF1 | PAIR | 7 | 5.5 | 5 | 10 | 5 | 12 | 6 | 20 | 12 | 12 | 12 | 12 | 7.5 | 85 Ohms | TOP=L2:L3=L2/L4:L6=L5/L7:BOTTOM=L7 |
| 8644_USB_DP8 | USB15-DIFF1 | PAIR | 8 | 5.38 | 5 | 10 | 5 | 12 | 6 | 33 | 12 | 12 | 12 | 12 | 6.62 | 85 Ohms | TOP=L2:L3=L2/L4:L6=L5/L7:BOTTOM=L7 |
| 8644_USB_DN4 | USB17-DIFF1 | PAIR | 1 | 5.38 | 5 | 10 | 5 | 12 | 6 | 33 | 12 | 12 | 12 | 12 | 6.62 | 85 Ohms | TOP=L2:L3=L2/L4:L6=L5/L7:BOTTOM=L7 |
| 8644_USB_DN4 | USB17-DIFF1 | PAIR | 2 | 5.5 | 5 | 10 | 5 | 12 | 6 | 20 | 12 | 12 | 12 | 12 | 7.5 | 85 Ohms | TOP=L2:L3=L2/L4:L6=L5/L7:BOTTOM=L7 |
| 8644_USB_DN4 | USB17-DIFF1 | PAIR | 3 | 5.5 | 5 | 10 | 5 | 12 | 6 | 20 | 12 | 12 | 12 | 12 | 7.5 | 85 Ohms | TOP=L2:L3=L2/L4:L6=L5/L7:BOTTOM=L7 |
| 8644_USB_DN4 | USB17-DIFF1 | PAIR | 4 | 5.5 | 5 | 10 | 5 | 12 | 6 | 20 | 12 | 12 | 12 | 12 | 7.5 | 85 Ohms | TOP=L2:L3=L2/L4:L6=L5/L7:BOTTOM=L7 |
| 8644_USB_DN4 | USB17-DIFF1 | PAIR | 5 | 5.5 | 5 | 10 | 5 | 12 | 6 | 20 | 12 | 12 | 12 | 12 | 7.5 | 85 Ohms | TOP=L2:L3=L2/L4:L6=L5/L7:BOTTOM=L7 |
| 8644_USB_DN4 | USB17-DIFF1 | PAIR | 6 | 5.5 | 5 | 10 | 5 | 12 | 6 | 20 | 12 | 12 | 12 | 12 | 7.5 | 85 Ohms | TOP=L2:L3=L2/L4:L6=L5/L7:BOTTOM=L7 |
| 8644_USB_DN4 | USB17-DIFF1 | PAIR | 7 | 5.5 | 5 | 10 | 5 | 12 | 6 | 20 | 12 | 12 | 12 | 12 | 7.5 | 85 Ohms | TOP=L2:L3=L2/L4:L6=L5/L7:BOTTOM=L7 |
| 8644_USB_DN4 | USB17-DIFF1 | PAIR | 8 | 5.38 | 5 | 10 | 5 | 12 | 6 | 33 | 12 | 12 | 12 | 12 | 6.62 | 85 Ohms | TOP=L2:L3=L2/L4:L6=L5/L7:BOTTOM=L7 |
| 8644_USB_DP4 | USB17-DIFF1 | PAIR | 1 | 5.38 | 5 | 10 | 5 | 12 | 6 | 33 | 12 | 12 | 12 | 12 | 6.62 | 85 Ohms | TOP=L2:L3=L2/L4:L6=L5/L7:BOTTOM=L7 |
| 8644_USB_DP4 | USB17-DIFF1 | PAIR | 2 | 5.5 | 5 | 10 | 5 | 12 | 6 | 20 | 12 | 12 | 12 | 12 | 7.5 | 85 Ohms | TOP=L2:L3=L2/L4:L6=L5/L7:BOTTOM=L7 |
| 8644_USB_DP4 | USB17-DIFF1 | PAIR | 3 | 5.5 | 5 | 10 | 5 | 12 | 6 | 20 | 12 | 12 | 12 | 12 | 7.5 | 85 Ohms | TOP=L2:L3=L2/L4:L6=L5/L7:BOTTOM=L7 |
| 8644_USB_DP4 | USB17-DIFF1 | PAIR | 4 | 5.5 | 5 | 10 | 5 | 12 | 6 | 20 | 12 | 12 | 12 | 12 | 7.5 | 85 Ohms | TOP=L2:L3=L2/L4:L6=L5/L7:BOTTOM=L7 |
| 8644_USB_DP4 | USB17-DIFF1 | PAIR | 5 | 5.5 | 5 | 10 | 5 | 12 | 6 | 20 | 12 | 12 | 12 | 12 | 7.5 | 85 Ohms | TOP=L2:L3=L2/L4:L6=L5/L7:BOTTOM=L7 |
| 8644_USB_DP4 | USB17-DIFF1 | PAIR | 6 | 5.5 | 5 | 10 | 5 | 12 | 6 | 20 | 12 | 12 | 12 | 12 | 7.5 | 85 Ohms | TOP=L2:L3=L2/L4:L6=L5/L7:BOTTOM=L7 |
| 8644_USB_DP4 | USB17-DIFF1 | PAIR | 7 | 5.5 | 5 | 10 | 5 | 12 | 6 | 20 | 12 | 12 | 12 | 12 | 7.5 | 85 Ohms | TOP=L2:L3=L2/L4:L6=L5/L7:BOTTOM=L7 |
| 8644_USB_DP4 | USB17-DIFF1 | PAIR | 8 | 5.38 | 5 | 10 | 5 | 12 | 6 | 33 | 12 | 12 | 12 | 12 | 6.62 | 85 Ohms | TOP=L2:L3=L2/L4:L6=L5/L7:BOTTOM=L7 |
| USB_P4_DN_BMC | USB20-DIFF1 | PAIR | 1 | 5.38 | 5 | 10 | 5 | 12 | 6 | 33 | 12 | 12 | 12 | 12 | 6.62 | 85 Ohms | TOP=L2:L3=L2/L4:L6=L5/L7:BOTTOM=L7 |
| USB_P4_DN_BMC | USB20-DIFF1 | PAIR | 2 | 5.5 | 5 | 10 | 5 | 12 | 6 | 20 | 12 | 12 | 12 | 12 | 7.5 | 85 Ohms | TOP=L2:L3=L2/L4:L6=L5/L7:BOTTOM=L7 |
| USB_P4_DN_BMC | USB20-DIFF1 | PAIR | 3 | 5.5 | 5 | 10 | 5 | 12 | 6 | 20 | 12 | 12 | 12 | 12 | 7.5 | 85 Ohms | TOP=L2:L3=L2/L4:L6=L5/L7:BOTTOM=L7 |
| USB_P4_DN_BMC | USB20-DIFF1 | PAIR | 4 | 5.5 | 5 | 10 | 5 | 12 | 6 | 20 | 12 | 12 | 12 | 12 | 7.5 | 85 Ohms | TOP=L2:L3=L2/L4:L6=L5/L7:BOTTOM=L7 |
| USB_P4_DN_BMC | USB20-DIFF1 | PAIR | 5 | 5.5 | 5 | 10 | 5 | 12 | 6 | 20 | 12 | 12 | 12 | 12 | 7.5 | 85 Ohms | TOP=L2:L3=L2/L4:L6=L5/L7:BOTTOM=L7 |
| USB_P4_DN_BMC | USB20-DIFF1 | PAIR | 6 | 5.5 | 5 | 10 | 5 | 12 | 6 | 20 | 12 | 12 | 12 | 12 | 7.5 | 85 Ohms | TOP=L2:L3=L2/L4:L6=L5/L7:BOTTOM=L7 |
| USB_P4_DN_BMC | USB20-DIFF1 | PAIR | 7 | 5.5 | 5 | 10 | 5 | 12 | 6 | 20 | 12 | 12 | 12 | 12 | 7.5 | 85 Ohms | TOP=L2:L3=L2/L4:L6=L5/L7:BOTTOM=L7 |
| USB_P4_DN_BMC | USB20-DIFF1 | PAIR | 8 | 5.38 | 5 | 10 | 5 | 12 | 6 | 33 | 12 | 12 | 12 | 12 | 6.62 | 85 Ohms | TOP=L2:L3=L2/L4:L6=L5/L7:BOTTOM=L7 |
| USB_P4_DP_BMC | USB20-DIFF1 | PAIR | 1 | 5.38 | 5 | 10 | 5 | 12 | 6 | 33 | 12 | 12 | 12 | 12 | 6.62 | 85 Ohms | TOP=L2:L3=L2/L4:L6=L5/L7:BOTTOM=L7 |
| USB_P4_DP_BMC | USB20-DIFF1 | PAIR | 2 | 5.5 | 5 | 10 | 5 | 12 | 6 | 20 | 12 | 12 | 12 | 12 | 7.5 | 85 Ohms | TOP=L2:L3=L2/L4:L6=L5/L7:BOTTOM=L7 |
| USB_P4_DP_BMC | USB20-DIFF1 | PAIR | 3 | 5.5 | 5 | 10 | 5 | 12 | 6 | 20 | 12 | 12 | 12 | 12 | 7.5 | 85 Ohms | TOP=L2:L3=L2/L4:L6=L5/L7:BOTTOM=L7 |
| USB_P4_DP_BMC | USB20-DIFF1 | PAIR | 4 | 5.5 | 5 | 10 | 5 | 12 | 6 | 20 | 12 | 12 | 12 | 12 | 7.5 | 85 Ohms | TOP=L2:L3=L2/L4:L6=L5/L7:BOTTOM=L7 |
| USB_P4_DP_BMC | USB20-DIFF1 | PAIR | 5 | 5.5 | 5 | 10 | 5 | 12 | 6 | 20 | 12 | 12 | 12 | 12 | 7.5 | 85 Ohms | TOP=L2:L3=L2/L4:L6=L5/L7:BOTTOM=L7 |
| USB_P4_DP_BMC | USB20-DIFF1 | PAIR | 6 | 5.5 | 5 | 10 | 5 | 12 | 6 | 20 | 12 | 12 | 12 | 12 | 7.5 | 85 Ohms | TOP=L2:L3=L2/L4:L6=L5/L7:BOTTOM=L7 |
| USB_P4_DP_BMC | USB20-DIFF1 | PAIR | 7 | 5.5 | 5 | 10 | 5 | 12 | 6 | 20 | 12 | 12 | 12 | 12 | 7.5 | 85 Ohms | TOP=L2:L3=L2/L4:L6=L5/L7:BOTTOM=L7 |
| USB_P4_DP_BMC | USB20-DIFF1 | PAIR | 8 | 5.38 | 5 | 10 | 5 | 12 | 6 | 33 | 12 | 12 | 12 | 12 | 6.62 | 85 Ohms | TOP=L2:L3=L2/L4:L6=L5/L7:BOTTOM=L7 |
| USB2_BMC_DN | USB22-DIFF1 | PAIR | 1 | 5.38 | 5 | 10 | 5 | 12 | 6 | 33 | 12 | 12 | 12 | 12 | 6.62 | 85 Ohms | TOP=L2:L3=L2/L4:L6=L5/L7:BOTTOM=L7 |
| USB2_BMC_DN | USB22-DIFF1 | PAIR | 2 | 5.5 | 5 | 10 | 5 | 12 | 6 | 20 | 12 | 12 | 12 | 12 | 7.5 | 85 Ohms | TOP=L2:L3=L2/L4:L6=L5/L7:BOTTOM=L7 |
| USB2_BMC_DN | USB22-DIFF1 | PAIR | 3 | 5.5 | 5 | 10 | 5 | 12 | 6 | 20 | 12 | 12 | 12 | 12 | 7.5 | 85 Ohms | TOP=L2:L3=L2/L4:L6=L5/L7:BOTTOM=L7 |
| USB2_BMC_DN | USB22-DIFF1 | PAIR | 4 | 5.5 | 5 | 10 | 5 | 12 | 6 | 20 | 12 | 12 | 12 | 12 | 7.5 | 85 Ohms | TOP=L2:L3=L2/L4:L6=L5/L7:BOTTOM=L7 |
| USB2_BMC_DN | USB22-DIFF1 | PAIR | 5 | 5.5 | 5 | 10 | 5 | 12 | 6 | 20 | 12 | 12 | 12 | 12 | 7.5 | 85 Ohms | TOP=L2:L3=L2/L4:L6=L5/L7:BOTTOM=L7 |
| USB2_BMC_DN | USB22-DIFF1 | PAIR | 6 | 5.5 | 5 | 10 | 5 | 12 | 6 | 20 | 12 | 12 | 12 | 12 | 7.5 | 85 Ohms | TOP=L2:L3=L2/L4:L6=L5/L7:BOTTOM=L7 |
| USB2_BMC_DN | USB22-DIFF1 | PAIR | 7 | 5.5 | 5 | 10 | 5 | 12 | 6 | 20 | 12 | 12 | 12 | 12 | 7.5 | 85 Ohms | TOP=L2:L3=L2/L4:L6=L5/L7:BOTTOM=L7 |
| USB2_BMC_DN | USB22-DIFF1 | PAIR | 8 | 5.38 | 5 | 10 | 5 | 12 | 6 | 33 | 12 | 12 | 12 | 12 | 6.62 | 85 Ohms | TOP=L2:L3=L2/L4:L6=L5/L7:BOTTOM=L7 |
| USB2_BMC_DP | USB22-DIFF1 | PAIR | 1 | 5.38 | 5 | 10 | 5 | 12 | 6 | 33 | 12 | 12 | 12 | 12 | 6.62 | 85 Ohms | TOP=L2:L3=L2/L4:L6=L5/L7:BOTTOM=L7 |
| USB2_BMC_DP | USB22-DIFF1 | PAIR | 2 | 5.5 | 5 | 10 | 5 | 12 | 6 | 20 | 12 | 12 | 12 | 12 | 7.5 | 85 Ohms | TOP=L2:L3=L2/L4:L6=L5/L7:BOTTOM=L7 |
| USB2_BMC_DP | USB22-DIFF1 | PAIR | 3 | 5.5 | 5 | 10 | 5 | 12 | 6 | 20 | 12 | 12 | 12 | 12 | 7.5 | 85 Ohms | TOP=L2:L3=L2/L4:L6=L5/L7:BOTTOM=L7 |
| USB2_BMC_DP | USB22-DIFF1 | PAIR | 4 | 5.5 | 5 | 10 | 5 | 12 | 6 | 20 | 12 | 12 | 12 | 12 | 7.5 | 85 Ohms | TOP=L2:L3=L2/L4:L6=L5/L7:BOTTOM=L7 |
| USB2_BMC_DP | USB22-DIFF1 | PAIR | 5 | 5.5 | 5 | 10 | 5 | 12 | 6 | 20 | 12 | 12 | 12 | 12 | 7.5 | 85 Ohms | TOP=L2:L3=L2/L4:L6=L5/L7:BOTTOM=L7 |
| USB2_BMC_DP | USB22-DIFF1 | PAIR | 6 | 5.5 | 5 | 10 | 5 | 12 | 6 | 20 | 12 | 12 | 12 | 12 | 7.5 | 85 Ohms | TOP=L2:L3=L2/L4:L6=L5/L7:BOTTOM=L7 |
| USB2_BMC_DP | USB22-DIFF1 | PAIR | 7 | 5.5 | 5 | 10 | 5 | 12 | 6 | 20 | 12 | 12 | 12 | 12 | 7.5 | 85 Ohms | TOP=L2:L3=L2/L4:L6=L5/L7:BOTTOM=L7 |
| USB2_BMC_DP | USB22-DIFF1 | PAIR | 8 | 5.38 | 5 | 10 | 5 | 12 | 6 | 33 | 12 | 12 | 12 | 12 | 6.62 | 85 Ohms | TOP=L2:L3=L2/L4:L6=L5/L7:BOTTOM=L7 |
| MB0_P12V_R | 120MIL | PWR/GND | 1 | 120 | 5 | 10 | 5 | 14 | 6 | 6 | 12 | 12 | 12 | 12 |  |  |  |
| MB0_VCC | 120MIL | PWR/GND | 1 | 120 | 5 | 10 | 5 | 14 | 6 | 6 | 12 | 12 | 12 | 12 |  |  |  |
| MPLLAV33 | 120MIL | PWR/GND | 1 | 120 | 5 | 10 | 5 | 14 | 6 | 6 | 12 | 12 | 12 | 12 |  |  |  |
| P0V9_I210 | 120MIL | PWR/GND | 1 | 120 | 5 | 10 | 5 | 14 | 6 | 6 | 12 | 12 | 12 | 12 |  |  |  |
| P1V26_PWR | 120MIL | PWR/GND | 1 | 120 | 5 | 10 | 5 | 14 | 6 | 6 | 12 | 12 | 12 | 12 |  |  |  |
| P1V26_STBY | 120MIL | PWR/GND | 1 | 120 | 5 | 10 | 5 | 14 | 6 | 6 | 12 | 12 | 12 | 12 |  |  |  |
| P1V5_I210 | 120MIL | PWR/GND | 1 | 120 | 5 | 10 | 5 | 14 | 6 | 6 | 12 | 12 | 12 | 12 |  |  |  |
| P1V53_PWR | 120MIL | PWR/GND | 1 | 120 | 5 | 10 | 5 | 14 | 6 | 6 | 12 | 12 | 12 | 12 |  |  |  |
| P1V53_STBY | 120MIL | PWR/GND | 1 | 120 | 5 | 10 | 5 | 14 | 6 | 6 | 12 | 12 | 12 | 12 |  |  |  |
| P1V8_PWR | 120MIL | PWR/GND | 1 | 120 | 5 | 10 | 5 | 14 | 6 | 6 | 12 | 12 | 12 | 12 |  |  |  |
| P1V8_STBY | 120MIL | PWR/GND | 1 | 120 | 5 | 10 | 5 | 14 | 6 | 6 | 12 | 12 | 12 | 12 |  |  |  |
| P3V0_BAT | 120MIL | PWR/GND | 1 | 120 | 5 | 10 | 5 | 14 | 6 | 6 | 12 | 12 | 12 | 12 |  |  |  |
| P3V0_BAT_R | 120MIL | PWR/GND | 1 | 120 | 5 | 10 | 5 | 14 | 6 | 6 | 12 | 12 | 12 | 12 |  |  |  |
| P3V3_I2C_MUX | 120MIL | PWR/GND | 1 | 120 | 5 | 10 | 5 | 14 | 6 | 6 | 12 | 12 | 12 | 12 |  |  |  |
| P3V3_PWR | 120MIL | PWR/GND | 1 | 120 | 5 | 10 | 5 | 14 | 6 | 6 | 12 | 12 | 12 | 12 |  |  |  |
| P3V3_RTC | 120MIL | PWR/GND | 1 | 120 | 5 | 10 | 5 | 14 | 6 | 6 | 12 | 12 | 12 | 12 |  |  |  |
| P3V3_STBY | 120MIL | PWR/GND | 1 | 120 | 5 | 10 | 5 | 14 | 6 | 6 | 12 | 12 | 12 | 12 |  |  |  |
| P3V3_STBY_VDD | 120MIL | PWR/GND | 1 | 120 | 5 | 10 | 5 | 14 | 6 | 6 | 12 | 12 | 12 | 12 |  |  |  |
| P5V_STBY | 120MIL | PWR/GND | 1 | 120 | 5 | 10 | 5 | 14 | 6 | 6 | 12 | 12 | 12 | 12 |  |  |  |
| P5V_STBY_LR | 120MIL | PWR/GND | 1 | 120 | 5 | 10 | 5 | 14 | 6 | 6 | 12 | 12 | 12 | 12 |  |  |  |
| P5V_STBY_LX | 120MIL | PWR/GND | 1 | 120 | 5 | 10 | 5 | 14 | 6 | 6 | 12 | 12 | 12 | 12 |  |  |  |
| P5V_USB | 120MIL | PWR/GND | 1 | 120 | 5 | 10 | 5 | 14 | 6 | 6 | 12 | 12 | 12 | 12 |  |  |  |
| P5V_USB_BP1_F | 120MIL | PWR/GND | 1 | 120 | 5 | 10 | 5 | 14 | 6 | 6 | 12 | 12 | 12 | 12 |  |  |  |
| ADCVREFFN | ADCVREFF | PWR/GND | 1 | 40 | 5 | 10 | 5 | 14 | 6 | 6 | 12 | 12 | 12 | 12 |  |  |  |
| ADCVREFFP | ADCVREFF | PWR/GND | 1 | 40 | 5 | 10 | 5 | 14 | 6 | 6 | 12 | 12 | 12 | 12 |  |  |  |
| ADCVREXT | ADCVREFF | PWR/GND | 1 | 40 | 5 | 10 | 5 | 14 | 6 | 6 | 12 | 12 | 12 | 12 |  |  |  |
| DDR_VREF | ADCVREFF | PWR/GND | 1 | 40 | 5 | 10 | 5 | 14 | 6 | 6 | 12 | 12 | 12 | 12 |  |  |  |
| AGND_CURRENT_MON | GND | PWR/GND | 1 | 1000 | 5 | 10 | 5 | 14 | 6 | 6 | 12 | 12 | 12 | 12 |  |  |  |
| AGND_P0V9 | GND | PWR/GND | 1 | 1000 | 5 | 10 | 5 | 14 | 6 | 6 | 12 | 12 | 12 | 12 |  |  |  |
| AGND_P0V9_E | GND | PWR/GND | 1 | 1000 | 5 | 10 | 5 | 14 | 6 | 6 | 12 | 12 | 12 | 12 |  |  |  |
| AGND_P3V3_STBY | GND | PWR/GND | 1 | 1000 | 5 | 10 | 5 | 14 | 6 | 6 | 12 | 12 | 12 | 12 |  |  |  |
| AGND_USB | GND | PWR/GND | 1 | 1000 | 5 | 10 | 5 | 14 | 6 | 6 | 12 | 12 | 12 | 12 |  |  |  |
| GND | GND | PWR/GND | 1 | 1000 | 5 | 10 | 5 | 14 | 6 | 6 | 12 | 12 | 12 | 12 |  |  |  |
| 50M_CLK_OE | XTAL | PWR/GND | 1 | 6 | 5 | 10 | 5 | 14 | 6 | 6 | 12 | 12 | 12 | 12 |  |  |  |
| 50M_CLK_OUT | XTAL | PWR/GND | 1 | 6 | 5 | 10 | 5 | 14 | 6 | 6 | 12 | 12 | 12 | 12 |  |  |  |
| 50M_CLK_OUT_R | XTAL | PWR/GND | 1 | 6 | 5 | 10 | 5 | 14 | 6 | 6 | 12 | 12 | 12 | 12 |  |  |  |
| OSC0_AS_CLKIN | XTAL | PWR/GND | 1 | 6 | 5 | 10 | 5 | 14 | 6 | 6 | 12 | 12 | 12 | 12 |  |  |  |
| OSC2_CONT | XTAL | PWR/GND | 1 | 6 | 5 | 10 | 5 | 14 | 6 | 6 | 12 | 12 | 12 | 12 |  |  |  |
| OSC2_OUT | XTAL | PWR/GND | 1 | 6 | 5 | 10 | 5 | 14 | 6 | 6 | 12 | 12 | 12 | 12 |  |  |  |
| RTC_CLK_OUT | XTAL | PWR/GND | 1 | 6 | 5 | 10 | 5 | 14 | 6 | 6 | 12 | 12 | 12 | 12 |  |  |  |
| RTC_INT_N | XTAL | PWR/GND | 1 | 6 | 5 | 10 | 5 | 14 | 6 | 6 | 12 | 12 | 12 | 12 |  |  |  |
| RTC_OSCI | XTAL | PWR/GND | 1 | 6 | 5 | 10 | 5 | 14 | 6 | 6 | 12 | 12 | 12 | 12 |  |  |  |
| RTC_OSCO | XTAL | PWR/GND | 1 | 6 | 5 | 10 | 5 | 14 | 6 | 6 | 12 | 12 | 12 | 12 |  |  |  |
| XTAL_IN_I210 | XTAL | PWR/GND | 1 | 6 | 5 | 10 | 5 | 14 | 6 | 6 | 12 | 12 | 12 | 12 |  |  |  |
| XTAL_IN_I210_R | XTAL | PWR/GND | 1 | 6 | 5 | 10 | 5 | 14 | 6 | 6 | 12 | 12 | 12 | 12 |  |  |  |
| XTAL_OUT_I210 | XTAL | PWR/GND | 1 | 6 | 5 | 10 | 5 | 14 | 6 | 6 | 12 | 12 | 12 | 12 |  |  |  |
| XTAL_OUT_I210_R | XTAL | PWR/GND | 1 | 6 | 5 | 10 | 5 | 14 | 6 | 6 | 12 | 12 | 12 | 12 |  |  |  |
| XTAL_X1 | XTAL | PWR/GND | 1 | 6 | 5 | 10 | 5 | 14 | 6 | 6 | 12 | 12 | 12 | 12 |  |  |  |
| XTAL_X2 | XTAL | PWR/GND | 1 | 6 | 5 | 10 | 5 | 14 | 6 | 6 | 12 | 12 | 12 | 12 |  |  |  |
| XTAL_X2_CLKGEN | XTAL | PWR/GND | 1 | 6 | 5 | 10 | 5 | 14 | 6 | 6 | 12 | 12 | 12 | 12 |  |  |  |
